; Packager-XL run on 30-Nov-2015 AT 15:33:22 CONSTRAINTS_VIEW_GENERATED
( ConstraintFile "baseboard_fab2"
	( constraintHeader
		( objectKey
			( physical )
		)
		( version
			( 16.6 )
		)
		( revisionNumber
			( logicalViewRevNum 574 )
			( physicalViewRevNum 0 )
			( otherViewRevNum 0 )
		)
		( contents
			( dictionaryExtensions )
			( worksheetCustomizations )
			( electricalConstraints )
			( netClasses )
			( properties )
		)
		( precision
			( units mil )
			( numberOfDecimalPlaces 2 )
		)
	)
	( DictionaryExtensions
		( Attribute
			( Name "BOM_COST" )
			( Description " " )
			( Value
				( DataType ( dString ) )
				( Status  sProperty  sPackage )
			)
			( Objects
				( ValidObjects  oGate  oGateDefn  oBlock  oPart  oDesign  oSystem  oPartDefn  oNet )
				( NoInherit
					( oGate oPin )
				)
			)
			( Analysis
			)
		)
		( Attribute
			( Name "MATERIAL" )
			( Description " " )
			( Value
				( DataType ( dString ) )
				( Status  sProperty  sPackage )
			)
			( Objects
				( ValidObjects  oGate  oGateDefn  oBlock  oPart  oDesign  oSystem  oPartDefn )
				( NoInherit
					( oGate oPin )
				)
			)
			( Analysis
			)
		)
		( Attribute
			( Name "SEC_TYPE" )
			( Description " " )
			( Value
				( DataType ( dString ) )
				( Status  sProperty  sPackage )
			)
			( Objects
				( ValidObjects  oGate  oGateDefn  oBlock  oPart  oDesign  oSystem  oPartDefn )
				( NoInherit
					( oGate oPin )
				)
			)
			( Analysis
			)
		)
		( Attribute
			( Name "TOLERANCE" )
			( Description " " )
			( Value
				( DataType ( dString ) )
				( Status  sProperty  sPackage )
			)
			( Objects
				( ValidObjects  oGate  oGateDefn  oBlock  oPart  oDesign  oSystem  oPartDefn )
				( NoInherit
					( oGate oPin )
				)
			)
			( Analysis
			)
		)
		( Attribute
			( Name "WATTAGE" )
			( Description " " )
			( Value
				( DataType ( dString ) )
				( Status  sProperty  sPackage )
			)
			( Objects
				( ValidObjects  oGate  oGateDefn  oBlock  oPart  oDesign  oSystem  oPartDefn )
				( NoInherit
					( oGate oPin )
				)
			)
			( Analysis
			)
		)
		( Attribute
			( Name "SKT_NUMBER" )
			( Description " " )
			( Value
				( DataType ( dString ) )
				( Status  sProperty  sPackage )
			)
			( Objects
				( ValidObjects  oGate  oGateDefn  oBlock  oPart  oDesign  oSystem  oPartDefn )
				( NoInherit
					( oGate oPin )
				)
			)
			( Analysis
			)
		)
		( Attribute
			( Name "CD_SEC" )
			( Description " " )
			( Value
				( DataType ( dString ) )
				( Status  sProperty  sPackage )
			)
			( Objects
				( ValidObjects  oGate  oGateDefn  oBlock  oPart  oDesign  oSystem  oPartDefn )
				( NoInherit
					( oGate oPin )
				)
			)
			( Analysis
			)
		)
		( Attribute
			( Name "CDS_LMAN_SYM_OUTLINE" )
			( Description " " )
			( Value
				( DataType ( dString ) )
				( Status  sProperty  sPackage )
			)
			( Objects
				( ValidObjects  oGate  oGateDefn  oBlock  oPart  oDesign  oSystem  oPartDefn )
				( NoInherit
					( oGate oPin )
				)
			)
			( Analysis
			)
		)
		( Attribute
			( Name "SKU" )
			( Description " " )
			( Value
				( DataType ( dString ) )
				( Status  sProperty  sPackage )
			)
			( Objects
				( ValidObjects  oGate  oGateDefn  oBlock  oPart  oDesign  oSystem  oPartDefn )
				( NoInherit
					( oGate oPin )
				)
			)
			( Analysis
			)
		)
		( Attribute
			( Name "COLOR" )
			( Description " " )
			( Value
				( DataType ( dString ) )
				( Status  sProperty  sPackage )
			)
			( Objects
				( ValidObjects  oGate  oGateDefn  oBlock  oPart  oDesign  oSystem  oPartDefn )
				( NoInherit
					( oGate oPin )
				)
			)
			( Analysis
			)
		)
		( Attribute
			( Name "VOLATGE" )
			( Description " " )
			( Value
				( DataType ( dString ) )
				( Status  sProperty  sPackage )
			)
			( Objects
				( ValidObjects  oNet  oXnet  oPinPair  oBus  oDiffPair  oECSet )
			)
			( Analysis
			)
		)
		( Attribute
			( Name "SPOF" )
			( Description " " )
			( Value
				( DataType ( dString ) )
				( Status  sProperty  sPackage )
			)
			( Objects
				( ValidObjects  oGate  oGateDefn  oBlock  oPart  oDesign  oSystem  oPartDefn )
				( NoInherit
					( oGate oPin )
				)
			)
			( Analysis
			)
		)
		( Attribute
			( Name "PIN_SHORT" )
			( Description " " )
			( Value
				( DataType ( dString ) )
				( Status  sProperty  sPackage )
			)
			( Objects
				( ValidObjects  oGate  oGateDefn  oBlock  oPart  oDesign  oSystem  oPartDefn )
				( NoInherit
					( oGate oPin )
				)
			)
			( Analysis
			)
		)
		( Attribute
			( Name "BOM" )
			( Description " " )
			( Value
				( DataType ( dString ) )
				( Status  sProperty  sPackage )
			)
			( Objects
				( ValidObjects  oGate  oGateDefn  oBlock  oPart  oDesign  oSystem  oPartDefn )
				( NoInherit
					( oGate oPin )
				)
			)
			( Analysis
			)
		)
		( Attribute
			( Name "FIN" )
			( Description " " )
			( Value
				( DataType ( dString ) )
				( Status  sProperty  sPackage )
			)
			( Objects
				( ValidObjects  oGate  oGateDefn  oBlock  oPart  oDesign  oSystem  oPartDefn )
				( NoInherit
					( oGate oPin )
				)
			)
			( Analysis
			)
		)
		( Attribute
			( Name "P1V5_STBY_IBMC" )
			( Description " " )
			( Value
				( DataType ( dString ) )
				( Status  sProperty  sPackage )
			)
			( Objects
				( ValidObjects  oGate  oGateDefn  oBlock  oPart  oDesign  oSystem  oPartDefn )
				( NoInherit
					( oGate oPin )
				)
			)
			( Analysis
			)
		)
		( Attribute
			( Name "P1V5_STBY_IBMC_VR" )
			( Description " " )
			( Value
				( DataType ( dString ) )
				( Status  sProperty  sPackage )
			)
			( Objects
				( ValidObjects  oGate  oGateDefn  oBlock  oPart  oDesign  oSystem  oPartDefn )
				( NoInherit
					( oGate oPin )
				)
			)
			( Analysis
			)
		)
		( Attribute
			( Name "DIMMSIED" )
			( Description " " )
			( Value
				( DataType ( dString ) )
				( Status  sProperty  sPackage )
			)
			( Objects
				( ValidObjects  oGate  oGateDefn  oBlock  oPart  oDesign  oSystem  oPartDefn )
				( NoInherit
					( oGate oPin )
				)
			)
			( Analysis
			)
		)
		( Attribute
			( Name "DIMMSIDE" )
			( Description " " )
			( Value
				( DataType ( dString ) )
				( Status  sProperty  sPackage )
			)
			( Objects
				( ValidObjects  oGate  oGateDefn  oBlock  oPart  oDesign  oSystem  oPartDefn )
				( NoInherit
					( oGate oPin )
				)
			)
			( Analysis
			)
		)
		( Attribute
			( Name "$location" )
			( Description "" )
			( Value
				( DataType ( dString ) )
				( Status  sProperty )
			)
			( Objects
				( ValidObjects  oAll )
			)
			( Analysis
			)
		)
		( Attribute
			( Name "$sec" )
			( Description "" )
			( Value
				( DataType ( dString ) )
				( Status  sProperty )
			)
			( Objects
				( ValidObjects  oAll )
			)
			( Analysis
			)
		)
		( Attribute
			( Name "RATED_CURRENT" )
			( Description " " )
			( Value
				( DataType ( dString ) )
				( Status  sProperty  sPackage )
			)
			( Objects
				( ValidObjects  oGate  oGateDefn  oBlock  oPart  oDesign  oSystem  oPartDefn )
				( NoInherit
					( oGate oPin )
				)
			)
			( Analysis
			)
		)
		( Attribute
			( Name "STATUS" )
			( Description " " )
			( Value
				( DataType ( dString ) )
				( Status  sProperty  sPackage )
			)
			( Objects
				( ValidObjects  oGate  oGateDefn  oBlock  oPart  oDesign  oSystem  oPartDefn )
				( NoInherit
					( oGate oPin )
				)
			)
			( Analysis
			)
		)
		( Attribute
			( Name "STTATUS" )
			( Description " " )
			( Value
				( DataType ( dString ) )
				( Status  sProperty  sPackage )
			)
			( Objects
				( ValidObjects  oGate  oGateDefn  oBlock  oPart  oDesign  oSystem  oPartDefn )
				( NoInherit
					( oGate oPin )
				)
			)
			( Analysis
			)
		)
		( Attribute
			( Name "SIDE_SKU" )
			( Description " " )
			( Value
				( DataType ( dString ) )
				( Status  sProperty  sPackage )
			)
			( Objects
				( ValidObjects  oGate  oGateDefn  oBlock  oPart  oDesign  oSystem  oPartDefn )
				( NoInherit
					( oGate oPin )
				)
			)
			( Analysis
			)
		)
	)
	( designConstraints
		( ruleChanges
			( allRules )
			( design "baseboard_fab2"
				( objectFlag fObjectReadOnly )
				( objectStatus sObjectLogicalNet )
			)
			( signal "A_CPU0_ABC_RCOMP0"
				( objectStatus "@baseboard_fab2_lib.baseboard_fab2(sch_1):a_cpu0_abc_rcomp0" )
			)
			( signal "A_CPU0_ABC_RCOMP1"
				( objectStatus "@baseboard_fab2_lib.baseboard_fab2(sch_1):a_cpu0_abc_rcomp1" )
			)
			( signal "A_CPU0_ABC_RCOMP2"
				( objectStatus "@baseboard_fab2_lib.baseboard_fab2(sch_1):a_cpu0_abc_rcomp2" )
			)
			( signal "A_CPU0_DEF_RCOMP0"
				( objectStatus "@baseboard_fab2_lib.baseboard_fab2(sch_1):a_cpu0_def_rcomp0" )
			)
			( signal "A_CPU0_DEF_RCOMP1"
				( objectStatus "@baseboard_fab2_lib.baseboard_fab2(sch_1):a_cpu0_def_rcomp1" )
			)
			( signal "A_CPU0_DEF_RCOMP2"
				( objectStatus "@baseboard_fab2_lib.baseboard_fab2(sch_1):a_cpu0_def_rcomp2" )
			)
			( signal "A_CPU0_MCP01_RBIAS"
				( objectStatus "@baseboard_fab2_lib.baseboard_fab2(sch_1):a_cpu0_mcp01_rbias" )
			)
			( signal "A_CPU0_PE012_RBIAS"
				( objectStatus "@baseboard_fab2_lib.baseboard_fab2(sch_1):a_cpu0_pe012_rbias" )
			)
			( signal "A_CPU0_PE3_RBIAS"
				( objectStatus "@baseboard_fab2_lib.baseboard_fab2(sch_1):a_cpu0_pe3_rbias" )
			)
			( signal "A_CPU0_UPI01_RBIAS"
				( objectStatus "@baseboard_fab2_lib.baseboard_fab2(sch_1):a_cpu0_upi01_rbias" )
			)
			( signal "A_CPU0_UPI2_RBIAS"
				( objectStatus "@baseboard_fab2_lib.baseboard_fab2(sch_1):a_cpu0_upi2_rbias" )
			)
			( signal "CLK_100M_CPU0_BCLK0_DN"
				( objectStatus "@baseboard_fab2_lib.baseboard_fab2(sch_1):clk_100m_cpu0_bclk0_dn" )
			)
			( signal "CLK_100M_CPU0_BCLK0_DP"
				( objectStatus "@baseboard_fab2_lib.baseboard_fab2(sch_1):clk_100m_cpu0_bclk0_dp" )
			)
			( signal "CLK_100M_CPU0_BCLK1_DN"
				( objectStatus "@baseboard_fab2_lib.baseboard_fab2(sch_1):clk_100m_cpu0_bclk1_dn" )
			)
			( signal "CLK_100M_CPU0_BCLK1_DP"
				( objectStatus "@baseboard_fab2_lib.baseboard_fab2(sch_1):clk_100m_cpu0_bclk1_dp" )
			)
			( signal "CLK_100M_CPU0_BCLK2_DN"
				( objectStatus "@baseboard_fab2_lib.baseboard_fab2(sch_1):clk_100m_cpu0_bclk2_dn" )
			)
			( signal "CLK_100M_CPU0_BCLK2_DP"
				( objectStatus "@baseboard_fab2_lib.baseboard_fab2(sch_1):clk_100m_cpu0_bclk2_dp" )
			)
			( signal "FM_CPU0_PKGID0"
				( objectStatus "@baseboard_fab2_lib.baseboard_fab2(sch_1):fm_cpu0_pkgid0" )
			)
			( signal "FM_CPU0_PKGID1"
				( objectStatus "@baseboard_fab2_lib.baseboard_fab2(sch_1):fm_cpu0_pkgid1" )
			)
			( signal "FM_CPU0_PKGID2"
				( objectStatus "@baseboard_fab2_lib.baseboard_fab2(sch_1):fm_cpu0_pkgid2" )
			)
			( signal "FM_CPU0_PROC_ID0"
				( objectStatus "@baseboard_fab2_lib.baseboard_fab2(sch_1):fm_cpu0_proc_id0" )
			)
			( signal "FM_CPU0_PROC_ID1"
				( objectStatus "@baseboard_fab2_lib.baseboard_fab2(sch_1):fm_cpu0_proc_id1" )
			)
			( signal "FM_CPU0_SKTOCC_LVT3_N"
				( objectStatus "@baseboard_fab2_lib.baseboard_fab2(sch_1):fm_cpu0_sktocc_lvt3_n" )
			)
			( signal "FM_CPU0_SM_WP"
				( objectStatus "@baseboard_fab2_lib.baseboard_fab2(sch_1):fm_cpu0_sm_wp" )
			)
			( signal "GND"
				( attribute "VOLTAGE" "0.0V"
					( Units "uVoltage" "V" 1.000000)
					( Status sAliasFlattened )
					( Status sAliasConflict )
					( Origin gFrontEnd )
				)
				( objectStatus "@baseboard_fab2_lib.baseboard_fab2(sch_1):gnd" )
			)
			( signal "H_CPU0_BMCINIT"
				( objectStatus "@baseboard_fab2_lib.baseboard_fab2(sch_1):h_cpu0_bmcinit" )
			)
			( signal "H_CPU0_CATERR_G_N"
				( objectStatus "@baseboard_fab2_lib.baseboard_fab2(sch_1):h_cpu0_caterr_g_n" )
			)
			( signal "H_CPU0_ERR0_G_N"
				( objectStatus "@baseboard_fab2_lib.baseboard_fab2(sch_1):h_cpu0_err0_g_n" )
			)
			( signal "H_CPU0_ERR1_G_N"
				( objectStatus "@baseboard_fab2_lib.baseboard_fab2(sch_1):h_cpu0_err1_g_n" )
			)
			( signal "H_CPU0_ERR2_G_N"
				( objectStatus "@baseboard_fab2_lib.baseboard_fab2(sch_1):h_cpu0_err2_g_n" )
			)
			( signal "H_CPU0_FAST_WAKE_N"
				( objectStatus "@baseboard_fab2_lib.baseboard_fab2(sch_1):h_cpu0_fast_wake_n" )
			)
			( signal "H_CPU0_MEMABC_MEMHOT_G_N"
				( objectStatus "@baseboard_fab2_lib.baseboard_fab2(sch_1):h_cpu0_memabc_memhot_g_n" )
			)
			( signal "H_CPU0_MEMDEF_MEMHOT_G_N"
				( objectStatus "@baseboard_fab2_lib.baseboard_fab2(sch_1):h_cpu0_memdef_memhot_g_n" )
			)
			( signal "H_CPU0_MSMI_G_N"
				( objectStatus "@baseboard_fab2_lib.baseboard_fab2(sch_1):h_cpu0_msmi_g_n" )
			)
			( signal "H_CPU0_PROCHOT_G_N"
				( objectStatus "@baseboard_fab2_lib.baseboard_fab2(sch_1):h_cpu0_prochot_g_n" )
			)
			( signal "H_CPU0_THERMTRIP_G_N"
				( objectStatus "@baseboard_fab2_lib.baseboard_fab2(sch_1):h_cpu0_thermtrip_g_n" )
			)
			( signal "H_PM_SYNC_GTL"
				( objectStatus "@baseboard_fab2_lib.baseboard_fab2(sch_1):h_pm_sync_gtl" )
			)
			( signal "H_PM_SYNC_GTL_R1"
				( objectStatus "@baseboard_fab2_lib.baseboard_fab2(sch_1):h_pm_sync_gtl_r1" )
			)
			( signal "H_PMSYNC_CLK_24M"
				( objectStatus "@baseboard_fab2_lib.baseboard_fab2(sch_1):h_pmsync_clk_24m" )
			)
			( signal "H_PMSYNC_CLK_24M_CPU0"
				( objectStatus "@baseboard_fab2_lib.baseboard_fab2(sch_1):h_pmsync_clk_24m_cpu0" )
			)
			( signal "M_A_CPU_VREF"
				( objectStatus "@baseboard_fab2_lib.baseboard_fab2(sch_1):m_a_cpu_vref" )
			)
			( signal "M_ABC_RST_N"
				( objectStatus "@baseboard_fab2_lib.baseboard_fab2(sch_1):m_abc_rst_n" )
			)
			( signal "M_B_CPU_VREF"
				( objectStatus "@baseboard_fab2_lib.baseboard_fab2(sch_1):m_b_cpu_vref" )
			)
			( signal "M_C_CPU_VREF"
				( objectStatus "@baseboard_fab2_lib.baseboard_fab2(sch_1):m_c_cpu_vref" )
			)
			( signal "M_D_CPU_VREF"
				( objectStatus "@baseboard_fab2_lib.baseboard_fab2(sch_1):m_d_cpu_vref" )
			)
			( signal "M_DEF_RST_N"
				( objectStatus "@baseboard_fab2_lib.baseboard_fab2(sch_1):m_def_rst_n" )
			)
			( signal "M_E_CPU_VREF"
				( objectStatus "@baseboard_fab2_lib.baseboard_fab2(sch_1):m_e_cpu_vref" )
			)
			( signal "M_F_CPU_VREF"
				( objectStatus "@baseboard_fab2_lib.baseboard_fab2(sch_1):m_f_cpu_vref" )
			)
			( signal "P3V3_STBY"
				( attribute "VOLTAGE" "3.3V"
					( Units "uVoltage" "V" 1.000000)
					( Status sAliasFlattened )
					( Status sAliasConflict )
					( Origin gFrontEnd )
				)
				( objectStatus "@baseboard_fab2_lib.baseboard_fab2(sch_1):p3v3_stby" )
			)
			( signal "SMB_IE_3V3AUX_SCL"
				( objectStatus "@baseboard_fab2_lib.baseboard_fab2(sch_1):smb_ie_3v3aux_scl" )
			)
			( signal "PD_CPU0_BIST_ENABLE"
				( objectStatus "@baseboard_fab2_lib.baseboard_fab2(sch_1):pd_cpu0_bist_enable" )
			)
			( signal "PD_CPU0_KSFC_DIS"
				( objectStatus "@baseboard_fab2_lib.baseboard_fab2(sch_1):pd_cpu0_ksfc_dis" )
			)
			( signal "PD_CPU0_TEST12"
				( objectStatus "@baseboard_fab2_lib.baseboard_fab2(sch_1):pd_cpu0_test12" )
			)
			( signal "PD_CPU0_TEST13"
				( objectStatus "@baseboard_fab2_lib.baseboard_fab2(sch_1):pd_cpu0_test13" )
			)
			( signal "PD_CPU0_TEST14"
				( objectStatus "@baseboard_fab2_lib.baseboard_fab2(sch_1):pd_cpu0_test14" )
			)
			( signal "PD_CPU0_TXT_PLTEN"
				( objectStatus "@baseboard_fab2_lib.baseboard_fab2(sch_1):pd_cpu0_txt_plten" )
			)
			( signal "PD_PIROM_CPU0_ADDR0"
				( objectStatus "@baseboard_fab2_lib.baseboard_fab2(sch_1):pd_pirom_cpu0_addr0" )
			)
			( signal "PD_PIROM_CPU0_ADDR1"
				( objectStatus "@baseboard_fab2_lib.baseboard_fab2(sch_1):pd_pirom_cpu0_addr1" )
			)
			( signal "PD_PIROM_CPU0_ADDR2"
				( objectStatus "@baseboard_fab2_lib.baseboard_fab2(sch_1):pd_pirom_cpu0_addr2" )
			)
			( signal "PECI_CPU_G"
				( objectStatus "@baseboard_fab2_lib.baseboard_fab2(sch_1):peci_cpu_g" )
			)
			( signal "PU_CPU0_EAR_N"
				( objectStatus "@baseboard_fab2_lib.baseboard_fab2(sch_1):pu_cpu0_ear_n" )
			)
			( signal "PU_CPU0_FRMAGENT"
				( objectStatus "@baseboard_fab2_lib.baseboard_fab2(sch_1):pu_cpu0_frmagent" )
			)
			( signal "PU_CPU0_LEGACY_SKT"
				( objectStatus "@baseboard_fab2_lib.baseboard_fab2(sch_1):pu_cpu0_legacy_skt" )
			)
			( signal "PU_CPU0_SAFE_MODE_BOOT"
				( objectStatus "@baseboard_fab2_lib.baseboard_fab2(sch_1):pu_cpu0_safe_mode_boot" )
			)
			( signal "PU_CPU0_SOCKET_ID_0"
				( objectStatus "@baseboard_fab2_lib.baseboard_fab2(sch_1):pu_cpu0_socket_id_0" )
			)
			( signal "PU_CPU0_SOCKET_ID_1"
				( objectStatus "@baseboard_fab2_lib.baseboard_fab2(sch_1):pu_cpu0_socket_id_1" )
			)
			( signal "PU_CPU0_TSC_SYNC"
				( objectStatus "@baseboard_fab2_lib.baseboard_fab2(sch_1):pu_cpu0_tsc_sync" )
			)
			( signal "PU_CPU0_TXT_AGENT"
				( objectStatus "@baseboard_fab2_lib.baseboard_fab2(sch_1):pu_cpu0_txt_agent" )
			)
			( signal "PVCCIO_CPU0"
				( attribute "VOLTAGE" "1.1V"
					( Units "uVoltage" "V" 1.000000)
					( Status sAliasFlattened )
					( Origin gFrontEnd )
				)
				( objectStatus "@baseboard_fab2_lib.baseboard_fab2(sch_1):pvccio_cpu0" )
			)
			( signal "P1V15_AUX_BMC"
				( attribute "VOLTAGE" "1.5"
					( Units "uVoltage" "V" 1.000000)
					( Status sAliasFlattened )
					( Origin gFrontEnd )
				)
				( objectStatus "@baseboard_fab2_lib.baseboard_fab2(sch_1):p1v15_aux_bmc" )
			)
			( signal "PWRGD_CPU0_DRAMPWROK_ABC_G"
				( objectStatus "@baseboard_fab2_lib.baseboard_fab2(sch_1):pwrgd_cpu0_drampwrok_abc_g" )
			)
			( signal "PWRGD_CPU0_DRAMPWROK_DEF_G"
				( objectStatus "@baseboard_fab2_lib.baseboard_fab2(sch_1):pwrgd_cpu0_drampwrok_def_g" )
			)
			( signal "PWRGD_CPU0_G"
				( objectStatus "@baseboard_fab2_lib.baseboard_fab2(sch_1):pwrgd_cpu0_g" )
			)
			( signal "RST_CPU0_G_N"
				( objectStatus "@baseboard_fab2_lib.baseboard_fab2(sch_1):rst_cpu0_g_n" )
			)
			( signal "SMB_DDR_ABC_SCL_G_R"
				( objectStatus "@baseboard_fab2_lib.baseboard_fab2(sch_1):smb_ddr_abc_scl_g_r" )
			)
			( signal "SMB_DDR_ABC_SDA_G_R"
				( objectStatus "@baseboard_fab2_lib.baseboard_fab2(sch_1):smb_ddr_abc_sda_g_r" )
			)
			( signal "SMB_DDR_DEF_SCL_G_R"
				( objectStatus "@baseboard_fab2_lib.baseboard_fab2(sch_1):smb_ddr_def_scl_g_r" )
			)
			( signal "SMB_DDR_DEF_SDA_G_R"
				( objectStatus "@baseboard_fab2_lib.baseboard_fab2(sch_1):smb_ddr_def_sda_g_r" )
			)
			( signal "SMB_PIROM_CPU0_SCL"
				( objectStatus "@baseboard_fab2_lib.baseboard_fab2(sch_1):smb_pirom_cpu0_scl" )
			)
			( signal "SMB_PIROM_CPU0_SDA"
				( objectStatus "@baseboard_fab2_lib.baseboard_fab2(sch_1):smb_pirom_cpu0_sda" )
			)
			( signal "SVID_ALERT0_CPU0_N"
				( objectStatus "@baseboard_fab2_lib.baseboard_fab2(sch_1):svid_alert0_cpu0_n" )
			)
			( signal "SVID_ALERT0_CPU0_R_N"
				( objectStatus "@baseboard_fab2_lib.baseboard_fab2(sch_1):svid_alert0_cpu0_r_n" )
			)
			( signal "SVID_ALERT1_CPU0_N"
				( objectStatus "@baseboard_fab2_lib.baseboard_fab2(sch_1):svid_alert1_cpu0_n" )
			)
			( signal "SVID_ALERT1_CPU0_R_N"
				( objectStatus "@baseboard_fab2_lib.baseboard_fab2(sch_1):svid_alert1_cpu0_r_n" )
			)
			( signal "SVID_CLK0_CPU0"
				( objectStatus "@baseboard_fab2_lib.baseboard_fab2(sch_1):svid_clk0_cpu0" )
			)
			( signal "SVID_CLK0_CPU0_R"
				( objectStatus "@baseboard_fab2_lib.baseboard_fab2(sch_1):svid_clk0_cpu0_r" )
			)
			( signal "SVID_CLK1_CPU0"
				( objectStatus "@baseboard_fab2_lib.baseboard_fab2(sch_1):svid_clk1_cpu0" )
			)
			( signal "SVID_CLK1_CPU0_R"
				( objectStatus "@baseboard_fab2_lib.baseboard_fab2(sch_1):svid_clk1_cpu0_r" )
			)
			( signal "SVID_DIO0_CPU0"
				( objectStatus "@baseboard_fab2_lib.baseboard_fab2(sch_1):svid_dio0_cpu0" )
			)
			( signal "SVID_DIO0_CPU0_R"
				( objectStatus "@baseboard_fab2_lib.baseboard_fab2(sch_1):svid_dio0_cpu0_r" )
			)
			( signal "SVID_DIO1_CPU0"
				( objectStatus "@baseboard_fab2_lib.baseboard_fab2(sch_1):svid_dio1_cpu0" )
			)
			( signal "SVID_DIO1_CPU0_R"
				( objectStatus "@baseboard_fab2_lib.baseboard_fab2(sch_1):svid_dio1_cpu0_r" )
			)
			( signal "TP_CPU0_PE_HP_SCL"
				( objectStatus "@baseboard_fab2_lib.baseboard_fab2(sch_1):tp_cpu0_pe_hp_scl" )
			)
			( signal "TP_CPU0_PE_HP_SDA"
				( objectStatus "@baseboard_fab2_lib.baseboard_fab2(sch_1):tp_cpu0_pe_hp_sda" )
			)
			( signal "TP_CPU0_PROCDIS_G_N"
				( objectStatus "@baseboard_fab2_lib.baseboard_fab2(sch_1):tp_cpu0_procdis_g_n" )
			)
			( signal "TP_CPU0_SOCKET_ID_2"
				( objectStatus "@baseboard_fab2_lib.baseboard_fab2(sch_1):tp_cpu0_socket_id_2" )
			)
			( signal "TP_NMI_CPU0"
				( objectStatus "@baseboard_fab2_lib.baseboard_fab2(sch_1):tp_nmi_cpu0" )
			)
			( signal "TP_XDP_CPU0_OBSDATA_A0_MBP2_N"
				( objectStatus "@baseboard_fab2_lib.baseboard_fab2(sch_1):tp_xdp_cpu0_obsdata_a0_mbp2_n" )
			)
			( signal "TP_XDP_CPU0_OBSDATA_A1_MBP3_N"
				( objectStatus "@baseboard_fab2_lib.baseboard_fab2(sch_1):tp_xdp_cpu0_obsdata_a1_mbp3_n" )
			)
			( signal "TP_XDP_CPU0_OBSDATA_A2_MBP4_N"
				( objectStatus "@baseboard_fab2_lib.baseboard_fab2(sch_1):tp_xdp_cpu0_obsdata_a2_mbp4_n" )
			)
			( signal "TP_XDP_CPU0_OBSDATA_A3_MBP5_N"
				( objectStatus "@baseboard_fab2_lib.baseboard_fab2(sch_1):tp_xdp_cpu0_obsdata_a3_mbp5_n" )
			)
			( signal "XDP_CPU0_TDO"
				( objectStatus "@baseboard_fab2_lib.baseboard_fab2(sch_1):xdp_cpu0_tdo" )
			)
			( signal "XDP_CPU_MBP0_N"
				( objectStatus "@baseboard_fab2_lib.baseboard_fab2(sch_1):xdp_cpu_mbp0_n" )
			)
			( signal "XDP_CPU_MBP1_N"
				( objectStatus "@baseboard_fab2_lib.baseboard_fab2(sch_1):xdp_cpu_mbp1_n" )
			)
			( signal "XDP_CPU_OBSFN_B0_MBP6_N"
				( objectStatus "@baseboard_fab2_lib.baseboard_fab2(sch_1):xdp_cpu_obsfn_b0_mbp6_n" )
			)
			( signal "XDP_CPU_OBSFN_B1_MBP7_N"
				( objectStatus "@baseboard_fab2_lib.baseboard_fab2(sch_1):xdp_cpu_obsfn_b1_mbp7_n" )
			)
			( signal "XDP_CPU_PRDY_N"
				( objectStatus "@baseboard_fab2_lib.baseboard_fab2(sch_1):xdp_cpu_prdy_n" )
			)
			( signal "XDP_CPU_PREQ_N"
				( objectStatus "@baseboard_fab2_lib.baseboard_fab2(sch_1):xdp_cpu_preq_n" )
			)
			( signal "XDP_CPU_TCK0"
				( objectStatus "@baseboard_fab2_lib.baseboard_fab2(sch_1):xdp_cpu_tck0" )
			)
			( signal "XDP_CPU_TDI"
				( objectStatus "@baseboard_fab2_lib.baseboard_fab2(sch_1):xdp_cpu_tdi" )
			)
			( signal "XDP_CPU_TMS"
				( objectStatus "@baseboard_fab2_lib.baseboard_fab2(sch_1):xdp_cpu_tms" )
			)
			( signal "XDP_CPU_TRST_N"
				( objectStatus "@baseboard_fab2_lib.baseboard_fab2(sch_1):xdp_cpu_trst_n" )
			)
			( signal "CLK_100M_CPU0_RC_REFCLK0_DN"
				( objectStatus "@baseboard_fab2_lib.baseboard_fab2(sch_1):clk_100m_cpu0_rc_refclk0_dn" )
			)
			( signal "CLK_100M_CPU0_RC_REFCLK0_DP"
				( objectStatus "@baseboard_fab2_lib.baseboard_fab2(sch_1):clk_100m_cpu0_rc_refclk0_dp" )
			)
			( signal "CLK_322M_OSC_CPU0_RC_DN"
				( objectStatus "@baseboard_fab2_lib.baseboard_fab2(sch_1):clk_322m_osc_cpu0_rc_dn" )
			)
			( signal "CLK_322M_OSC_CPU0_RC_DP"
				( objectStatus "@baseboard_fab2_lib.baseboard_fab2(sch_1):clk_322m_osc_cpu0_rc_dp" )
			)
			( signal "FM_CPU0_RC_ERROR_N"
				( objectStatus "@baseboard_fab2_lib.baseboard_fab2(sch_1):fm_cpu0_rc_error_n" )
			)
			( signal "H_CPU0_FIVR_FAULT_G"
				( objectStatus "@baseboard_fab2_lib.baseboard_fab2(sch_1):h_cpu0_fivr_fault_g" )
			)
			( signal "P1V8_MCP_CPU0"
				( attribute "VOLTAGE" "+1.8V"
					( Units "uVoltage" "V" 1.000000)
					( Status sAliasFlattened )
					( Origin gFrontEnd )
				)
				( objectStatus "@baseboard_fab2_lib.baseboard_fab2(sch_1):p1v8_mcp_cpu0" )
			)
			( signal "PD_CPU0_DMIMODE_OVERRIDE"
				( objectStatus "@baseboard_fab2_lib.baseboard_fab2(sch_1):pd_cpu0_dmimode_override" )
			)
			( signal "PD_CPU0_RSVD_TEST_1"
				( objectStatus "@baseboard_fab2_lib.baseboard_fab2(sch_1):pd_cpu0_rsvd_test_1" )
			)
			( signal "PD_CPU0_RSVD_TEST_2"
				( objectStatus "@baseboard_fab2_lib.baseboard_fab2(sch_1):pd_cpu0_rsvd_test_2" )
			)
			( signal "PVCCMCP_CPU0"
				( attribute "VOLTAGE" "1.2V"
					( Units "uVoltage" "V" 1.000000)
					( Status sAliasFlattened )
					( Origin gFrontEnd )
				)
				( objectStatus "@baseboard_fab2_lib.baseboard_fab2(sch_1):pvccmcp_cpu0" )
			)
			( signal "TP_CPU0_RSVD_194"
				( objectStatus "@baseboard_fab2_lib.baseboard_fab2(sch_1):tp_cpu0_rsvd_194" )
			)
			( signal "TP_CPU0_RSVD_198"
				( objectStatus "@baseboard_fab2_lib.baseboard_fab2(sch_1):tp_cpu0_rsvd_198" )
			)
			( signal "TP_CPU0_RSVD_199"
				( objectStatus "@baseboard_fab2_lib.baseboard_fab2(sch_1):tp_cpu0_rsvd_199" )
			)
			( signal "TP_CPU0_RSVD_204"
				( objectStatus "@baseboard_fab2_lib.baseboard_fab2(sch_1):tp_cpu0_rsvd_204" )
			)
			( signal "TP_CPU0_RSVD_205"
				( objectStatus "@baseboard_fab2_lib.baseboard_fab2(sch_1):tp_cpu0_rsvd_205" )
			)
			( signal "TP_CPU0_RSVD_208"
				( objectStatus "@baseboard_fab2_lib.baseboard_fab2(sch_1):tp_cpu0_rsvd_208" )
			)
			( signal "TP_CPU0_RSVD_210"
				( objectStatus "@baseboard_fab2_lib.baseboard_fab2(sch_1):tp_cpu0_rsvd_210" )
			)
			( signal "TP_CPU0_RSVD_211"
				( objectStatus "@baseboard_fab2_lib.baseboard_fab2(sch_1):tp_cpu0_rsvd_211" )
			)
			( signal "TP_CPU0_RSVD_212"
				( objectStatus "@baseboard_fab2_lib.baseboard_fab2(sch_1):tp_cpu0_rsvd_212" )
			)
			( signal "TP_CPU0_RSVD_214"
				( objectStatus "@baseboard_fab2_lib.baseboard_fab2(sch_1):tp_cpu0_rsvd_214" )
			)
			( signal "TP_CPU0_RSVD_216"
				( objectStatus "@baseboard_fab2_lib.baseboard_fab2(sch_1):tp_cpu0_rsvd_216" )
			)
			( signal "TP_CPU0_RSVD_217"
				( objectStatus "@baseboard_fab2_lib.baseboard_fab2(sch_1):tp_cpu0_rsvd_217" )
			)
			( signal "TP_CPU0_RSVD_218"
				( objectStatus "@baseboard_fab2_lib.baseboard_fab2(sch_1):tp_cpu0_rsvd_218" )
			)
			( signal "TP_CPU0_RSVD_219"
				( objectStatus "@baseboard_fab2_lib.baseboard_fab2(sch_1):tp_cpu0_rsvd_219" )
			)
			( signal "TP_CPU0_RSVD_222"
				( objectStatus "@baseboard_fab2_lib.baseboard_fab2(sch_1):tp_cpu0_rsvd_222" )
			)
			( signal "TP_CPU0_RSVD_223"
				( objectStatus "@baseboard_fab2_lib.baseboard_fab2(sch_1):tp_cpu0_rsvd_223" )
			)
			( signal "TP_CPU0_RSVD_224"
				( objectStatus "@baseboard_fab2_lib.baseboard_fab2(sch_1):tp_cpu0_rsvd_224" )
			)
			( signal "TP_CPU0_RSVD_225"
				( objectStatus "@baseboard_fab2_lib.baseboard_fab2(sch_1):tp_cpu0_rsvd_225" )
			)
			( signal "TP_CPU0_RSVD_226"
				( objectStatus "@baseboard_fab2_lib.baseboard_fab2(sch_1):tp_cpu0_rsvd_226" )
			)
			( signal "TP_CPU0_RSVD_227"
				( objectStatus "@baseboard_fab2_lib.baseboard_fab2(sch_1):tp_cpu0_rsvd_227" )
			)
			( signal "TP_CPU0_RSVD_228"
				( objectStatus "@baseboard_fab2_lib.baseboard_fab2(sch_1):tp_cpu0_rsvd_228" )
			)
			( signal "TP_CPU0_RSVD_229"
				( objectStatus "@baseboard_fab2_lib.baseboard_fab2(sch_1):tp_cpu0_rsvd_229" )
			)
			( signal "TP_CPU0_RSVD_230"
				( objectStatus "@baseboard_fab2_lib.baseboard_fab2(sch_1):tp_cpu0_rsvd_230" )
			)
			( signal "TP_CPU0_RSVD_231"
				( objectStatus "@baseboard_fab2_lib.baseboard_fab2(sch_1):tp_cpu0_rsvd_231" )
			)
			( signal "TP_CPU0_RSVD_232"
				( objectStatus "@baseboard_fab2_lib.baseboard_fab2(sch_1):tp_cpu0_rsvd_232" )
			)
			( signal "TP_CPU0_RSVD_233"
				( objectStatus "@baseboard_fab2_lib.baseboard_fab2(sch_1):tp_cpu0_rsvd_233" )
			)
			( signal "TP_CPU0_RSVD_234"
				( objectStatus "@baseboard_fab2_lib.baseboard_fab2(sch_1):tp_cpu0_rsvd_234" )
			)
			( signal "TP_CPU0_RSVD_235"
				( objectStatus "@baseboard_fab2_lib.baseboard_fab2(sch_1):tp_cpu0_rsvd_235" )
			)
			( signal "TP_CPU0_RSVD_236"
				( objectStatus "@baseboard_fab2_lib.baseboard_fab2(sch_1):tp_cpu0_rsvd_236" )
			)
			( signal "TP_CPU0_RSVD_237"
				( objectStatus "@baseboard_fab2_lib.baseboard_fab2(sch_1):tp_cpu0_rsvd_237" )
			)
			( signal "TP_CPU0_RSVD_238"
				( objectStatus "@baseboard_fab2_lib.baseboard_fab2(sch_1):tp_cpu0_rsvd_238" )
			)
			( signal "TP_CPU0_RSVD_239"
				( objectStatus "@baseboard_fab2_lib.baseboard_fab2(sch_1):tp_cpu0_rsvd_239" )
			)
			( signal "TP_CPU0_RSVD_240"
				( objectStatus "@baseboard_fab2_lib.baseboard_fab2(sch_1):tp_cpu0_rsvd_240" )
			)
			( signal "TP_CPU0_RSVD_241"
				( objectStatus "@baseboard_fab2_lib.baseboard_fab2(sch_1):tp_cpu0_rsvd_241" )
			)
			( signal "TP_CPU0_RSVD_242"
				( objectStatus "@baseboard_fab2_lib.baseboard_fab2(sch_1):tp_cpu0_rsvd_242" )
			)
			( signal "TP_CPU0_RSVD_243"
				( objectStatus "@baseboard_fab2_lib.baseboard_fab2(sch_1):tp_cpu0_rsvd_243" )
			)
			( signal "TP_CPU0_RSVD_244"
				( objectStatus "@baseboard_fab2_lib.baseboard_fab2(sch_1):tp_cpu0_rsvd_244" )
			)
			( signal "TP_CPU0_RSVD_245"
				( objectStatus "@baseboard_fab2_lib.baseboard_fab2(sch_1):tp_cpu0_rsvd_245" )
			)
			( signal "TP_CPU0_RSVD_246"
				( objectStatus "@baseboard_fab2_lib.baseboard_fab2(sch_1):tp_cpu0_rsvd_246" )
			)
			( signal "TP_CPU0_RSVD_247"
				( objectStatus "@baseboard_fab2_lib.baseboard_fab2(sch_1):tp_cpu0_rsvd_247" )
			)
			( signal "TP_CPU0_RSVD_248"
				( objectStatus "@baseboard_fab2_lib.baseboard_fab2(sch_1):tp_cpu0_rsvd_248" )
			)
			( signal "TP_CPU0_RSVD_249"
				( objectStatus "@baseboard_fab2_lib.baseboard_fab2(sch_1):tp_cpu0_rsvd_249" )
			)
			( signal "TP_CPU0_RSVD_250"
				( objectStatus "@baseboard_fab2_lib.baseboard_fab2(sch_1):tp_cpu0_rsvd_250" )
			)
			( signal "TP_CPU0_RSVD_251"
				( objectStatus "@baseboard_fab2_lib.baseboard_fab2(sch_1):tp_cpu0_rsvd_251" )
			)
			( signal "TP_CPU0_RSVD_252"
				( objectStatus "@baseboard_fab2_lib.baseboard_fab2(sch_1):tp_cpu0_rsvd_252" )
			)
			( signal "TP_CPU0_RSVD_253"
				( objectStatus "@baseboard_fab2_lib.baseboard_fab2(sch_1):tp_cpu0_rsvd_253" )
			)
			( signal "TP_CPU0_RSVD_254"
				( objectStatus "@baseboard_fab2_lib.baseboard_fab2(sch_1):tp_cpu0_rsvd_254" )
			)
			( signal "TP_CPU0_RSVD_256"
				( objectStatus "@baseboard_fab2_lib.baseboard_fab2(sch_1):tp_cpu0_rsvd_256" )
			)
			( signal "TP_CPU0_RSVD_258"
				( objectStatus "@baseboard_fab2_lib.baseboard_fab2(sch_1):tp_cpu0_rsvd_258" )
			)
			( signal "TP_CPU0_RSVD_259"
				( objectStatus "@baseboard_fab2_lib.baseboard_fab2(sch_1):tp_cpu0_rsvd_259" )
			)
			( signal "TP_CPU0_RSVD_260"
				( objectStatus "@baseboard_fab2_lib.baseboard_fab2(sch_1):tp_cpu0_rsvd_260" )
			)
			( signal "TP_CPU0_RSVD_261"
				( objectStatus "@baseboard_fab2_lib.baseboard_fab2(sch_1):tp_cpu0_rsvd_261" )
			)
			( signal "TP_CPU0_RSVD_262"
				( objectStatus "@baseboard_fab2_lib.baseboard_fab2(sch_1):tp_cpu0_rsvd_262" )
			)
			( signal "TP_CPU0_RSVD_263"
				( objectStatus "@baseboard_fab2_lib.baseboard_fab2(sch_1):tp_cpu0_rsvd_263" )
			)
			( signal "TP_CPU0_RSVD_264"
				( objectStatus "@baseboard_fab2_lib.baseboard_fab2(sch_1):tp_cpu0_rsvd_264" )
			)
			( signal "TP_CPU0_RSVD_265"
				( objectStatus "@baseboard_fab2_lib.baseboard_fab2(sch_1):tp_cpu0_rsvd_265" )
			)
			( signal "TP_CPU0_RSVD_266"
				( objectStatus "@baseboard_fab2_lib.baseboard_fab2(sch_1):tp_cpu0_rsvd_266" )
			)
			( signal "TP_CPU0_RSVD_267"
				( objectStatus "@baseboard_fab2_lib.baseboard_fab2(sch_1):tp_cpu0_rsvd_267" )
			)
			( signal "TP_CPU0_RSVD_268"
				( objectStatus "@baseboard_fab2_lib.baseboard_fab2(sch_1):tp_cpu0_rsvd_268" )
			)
			( signal "TP_CPU0_RSVD_269"
				( objectStatus "@baseboard_fab2_lib.baseboard_fab2(sch_1):tp_cpu0_rsvd_269" )
			)
			( signal "TP_CPU0_RSVD_270"
				( objectStatus "@baseboard_fab2_lib.baseboard_fab2(sch_1):tp_cpu0_rsvd_270" )
			)
			( signal "TP_CPU0_RSVD_271"
				( objectStatus "@baseboard_fab2_lib.baseboard_fab2(sch_1):tp_cpu0_rsvd_271" )
			)
			( signal "TP_CPU0_RSVD_272"
				( objectStatus "@baseboard_fab2_lib.baseboard_fab2(sch_1):tp_cpu0_rsvd_272" )
			)
			( signal "TP_CPU0_RSVD_273"
				( objectStatus "@baseboard_fab2_lib.baseboard_fab2(sch_1):tp_cpu0_rsvd_273" )
			)
			( signal "TP_CPU0_RSVD_274"
				( objectStatus "@baseboard_fab2_lib.baseboard_fab2(sch_1):tp_cpu0_rsvd_274" )
			)
			( signal "TP_CPU0_RSVD_275"
				( objectStatus "@baseboard_fab2_lib.baseboard_fab2(sch_1):tp_cpu0_rsvd_275" )
			)
			( signal "TP_CPU0_RSVD_276"
				( objectStatus "@baseboard_fab2_lib.baseboard_fab2(sch_1):tp_cpu0_rsvd_276" )
			)
			( signal "TP_CPU0_RSVD_277"
				( objectStatus "@baseboard_fab2_lib.baseboard_fab2(sch_1):tp_cpu0_rsvd_277" )
			)
			( signal "TP_CPU0_RSVD_278"
				( objectStatus "@baseboard_fab2_lib.baseboard_fab2(sch_1):tp_cpu0_rsvd_278" )
			)
			( signal "TP_CPU0_RSVD_279"
				( objectStatus "@baseboard_fab2_lib.baseboard_fab2(sch_1):tp_cpu0_rsvd_279" )
			)
			( signal "TP_CPU0_RSVD_280"
				( objectStatus "@baseboard_fab2_lib.baseboard_fab2(sch_1):tp_cpu0_rsvd_280" )
			)
			( signal "TP_CPU0_RSVD_281"
				( objectStatus "@baseboard_fab2_lib.baseboard_fab2(sch_1):tp_cpu0_rsvd_281" )
			)
			( signal "TP_CPU0_RSVD_282"
				( objectStatus "@baseboard_fab2_lib.baseboard_fab2(sch_1):tp_cpu0_rsvd_282" )
			)
			( signal "TP_CPU0_RSVD_283"
				( objectStatus "@baseboard_fab2_lib.baseboard_fab2(sch_1):tp_cpu0_rsvd_283" )
			)
			( signal "TP_CPU0_RSVD_284"
				( objectStatus "@baseboard_fab2_lib.baseboard_fab2(sch_1):tp_cpu0_rsvd_284" )
			)
			( signal "TP_CPU0_RSVD_285"
				( objectStatus "@baseboard_fab2_lib.baseboard_fab2(sch_1):tp_cpu0_rsvd_285" )
			)
			( signal "TP_CPU0_RSVD_286"
				( objectStatus "@baseboard_fab2_lib.baseboard_fab2(sch_1):tp_cpu0_rsvd_286" )
			)
			( signal "TP_CPU0_RSVD_287"
				( objectStatus "@baseboard_fab2_lib.baseboard_fab2(sch_1):tp_cpu0_rsvd_287" )
			)
			( signal "TP_CPU0_RSVD_288"
				( objectStatus "@baseboard_fab2_lib.baseboard_fab2(sch_1):tp_cpu0_rsvd_288" )
			)
			( signal "TP_CPU0_RSVD_289"
				( objectStatus "@baseboard_fab2_lib.baseboard_fab2(sch_1):tp_cpu0_rsvd_289" )
			)
			( signal "TP_CPU0_RSVD_290"
				( objectStatus "@baseboard_fab2_lib.baseboard_fab2(sch_1):tp_cpu0_rsvd_290" )
			)
			( signal "TP_CPU0_RSVD_291"
				( objectStatus "@baseboard_fab2_lib.baseboard_fab2(sch_1):tp_cpu0_rsvd_291" )
			)
			( signal "TP_CPU0_RSVD_292"
				( objectStatus "@baseboard_fab2_lib.baseboard_fab2(sch_1):tp_cpu0_rsvd_292" )
			)
			( signal "TP_CPU0_RSVD_293"
				( objectStatus "@baseboard_fab2_lib.baseboard_fab2(sch_1):tp_cpu0_rsvd_293" )
			)
			( signal "TP_CPU0_RSVD_298"
				( objectStatus "@baseboard_fab2_lib.baseboard_fab2(sch_1):tp_cpu0_rsvd_298" )
			)
			( signal "TP_CPU0_RSVD_299"
				( objectStatus "@baseboard_fab2_lib.baseboard_fab2(sch_1):tp_cpu0_rsvd_299" )
			)
			( signal "TP_CPU0_RSVD_300"
				( objectStatus "@baseboard_fab2_lib.baseboard_fab2(sch_1):tp_cpu0_rsvd_300" )
			)
			( signal "TP_CPU0_RSVD_303"
				( objectStatus "@baseboard_fab2_lib.baseboard_fab2(sch_1):tp_cpu0_rsvd_303" )
			)
			( signal "TP_CPU0_RSVD_304"
				( objectStatus "@baseboard_fab2_lib.baseboard_fab2(sch_1):tp_cpu0_rsvd_304" )
			)
			( signal "TP_CPU0_RSVD_TEST_11"
				( objectStatus "@baseboard_fab2_lib.baseboard_fab2(sch_1):tp_cpu0_rsvd_test_11" )
			)
			( signal "TP_CPU0_RSVD_TEST_3"
				( objectStatus "@baseboard_fab2_lib.baseboard_fab2(sch_1):tp_cpu0_rsvd_test_3" )
			)
			( signal "TP_CPU0_RSVD_TEST_4"
				( objectStatus "@baseboard_fab2_lib.baseboard_fab2(sch_1):tp_cpu0_rsvd_test_4" )
			)
			( signal "TP_CPU0_RSVD_TEST_5"
				( objectStatus "@baseboard_fab2_lib.baseboard_fab2(sch_1):tp_cpu0_rsvd_test_5" )
			)
			( signal "VSENSE_P1V8MCP_CPU0_SKT_VRTN"
				( objectStatus "@baseboard_fab2_lib.baseboard_fab2(sch_1):vsense_p1v8mcp_cpu0_skt_vrtn" )
			)
			( signal "VSENSE_P1V8MCP_CPU0_SKT_VSEN"
				( objectStatus "@baseboard_fab2_lib.baseboard_fab2(sch_1):vsense_p1v8mcp_cpu0_skt_vsen" )
			)
			( signal "XDP_CPU_PWR_DEBUG_N"
				( objectStatus "@baseboard_fab2_lib.baseboard_fab2(sch_1):xdp_cpu_pwr_debug_n" )
			)
			( signal "XDP_PRESENT_N"
				( objectStatus "@baseboard_fab2_lib.baseboard_fab2(sch_1):xdp_present_n" )
			)
			( signal "M_A_ACT_N"
				( objectStatus "@baseboard_fab2_lib.baseboard_fab2(sch_1):m_a_act_n" )
			)
			( signal "M_A_ALERT_N"
				( objectStatus "@baseboard_fab2_lib.baseboard_fab2(sch_1):m_a_alert_n" )
			)
			( signal "M_A_BA<0>"
				( objectStatus "@baseboard_fab2_lib.baseboard_fab2(sch_1):m_a_ba(0)" )
			)
			( signal "M_A_BA<1>"
				( objectStatus "@baseboard_fab2_lib.baseboard_fab2(sch_1):m_a_ba(1)" )
			)
			( signal "M_A_BG<0>"
				( objectStatus "@baseboard_fab2_lib.baseboard_fab2(sch_1):m_a_bg(0)" )
			)
			( signal "M_A_BG<1>"
				( objectStatus "@baseboard_fab2_lib.baseboard_fab2(sch_1):m_a_bg(1)" )
			)
			( signal "M_A_C<2>"
				( objectStatus "@baseboard_fab2_lib.baseboard_fab2(sch_1):m_a_c(2)" )
			)
			( signal "M_A_CKE<0>"
				( objectStatus "@baseboard_fab2_lib.baseboard_fab2(sch_1):m_a_cke(0)" )
			)
			( signal "M_A_CKE<1>"
				( objectStatus "@baseboard_fab2_lib.baseboard_fab2(sch_1):m_a_cke(1)" )
			)
			( signal "M_A_CKE<2>"
				( objectStatus "@baseboard_fab2_lib.baseboard_fab2(sch_1):m_a_cke(2)" )
			)
			( signal "M_A_CKE<3>"
				( objectStatus "@baseboard_fab2_lib.baseboard_fab2(sch_1):m_a_cke(3)" )
			)
			( signal "M_A_CLK_DN<0>"
				( objectStatus "@baseboard_fab2_lib.baseboard_fab2(sch_1):m_a_clk_dn(0)" )
			)
			( signal "M_A_CLK_DN<1>"
				( objectStatus "@baseboard_fab2_lib.baseboard_fab2(sch_1):m_a_clk_dn(1)" )
			)
			( signal "M_A_CLK_DN<2>"
				( objectStatus "@baseboard_fab2_lib.baseboard_fab2(sch_1):m_a_clk_dn(2)" )
			)
			( signal "M_A_CLK_DN<3>"
				( objectStatus "@baseboard_fab2_lib.baseboard_fab2(sch_1):m_a_clk_dn(3)" )
			)
			( signal "M_A_CLK_DP<0>"
				( objectStatus "@baseboard_fab2_lib.baseboard_fab2(sch_1):m_a_clk_dp(0)" )
			)
			( signal "M_A_CLK_DP<1>"
				( objectStatus "@baseboard_fab2_lib.baseboard_fab2(sch_1):m_a_clk_dp(1)" )
			)
			( signal "M_A_CLK_DP<2>"
				( objectStatus "@baseboard_fab2_lib.baseboard_fab2(sch_1):m_a_clk_dp(2)" )
			)
			( signal "M_A_CLK_DP<3>"
				( objectStatus "@baseboard_fab2_lib.baseboard_fab2(sch_1):m_a_clk_dp(3)" )
			)
			( signal "M_A_CS_N<0>"
				( objectStatus "@baseboard_fab2_lib.baseboard_fab2(sch_1):m_a_cs_n(0)" )
			)
			( signal "M_A_CS_N<1>"
				( objectStatus "@baseboard_fab2_lib.baseboard_fab2(sch_1):m_a_cs_n(1)" )
			)
			( signal "M_A_CS_N<2>"
				( objectStatus "@baseboard_fab2_lib.baseboard_fab2(sch_1):m_a_cs_n(2)" )
			)
			( signal "M_A_CS_N<3>"
				( objectStatus "@baseboard_fab2_lib.baseboard_fab2(sch_1):m_a_cs_n(3)" )
			)
			( signal "M_A_CS_N<4>"
				( objectStatus "@baseboard_fab2_lib.baseboard_fab2(sch_1):m_a_cs_n(4)" )
			)
			( signal "M_A_CS_N<5>"
				( objectStatus "@baseboard_fab2_lib.baseboard_fab2(sch_1):m_a_cs_n(5)" )
			)
			( signal "M_A_CS_N<6>"
				( objectStatus "@baseboard_fab2_lib.baseboard_fab2(sch_1):m_a_cs_n(6)" )
			)
			( signal "M_A_CS_N<7>"
				( objectStatus "@baseboard_fab2_lib.baseboard_fab2(sch_1):m_a_cs_n(7)" )
			)
			( signal "M_A_DQ<0>"
				( objectStatus "@baseboard_fab2_lib.baseboard_fab2(sch_1):m_a_dq(0)" )
			)
			( signal "M_A_DQ<1>"
				( objectStatus "@baseboard_fab2_lib.baseboard_fab2(sch_1):m_a_dq(1)" )
			)
			( signal "M_A_DQ<2>"
				( objectStatus "@baseboard_fab2_lib.baseboard_fab2(sch_1):m_a_dq(2)" )
			)
			( signal "M_A_DQ<3>"
				( objectStatus "@baseboard_fab2_lib.baseboard_fab2(sch_1):m_a_dq(3)" )
			)
			( signal "M_A_DQ<4>"
				( objectStatus "@baseboard_fab2_lib.baseboard_fab2(sch_1):m_a_dq(4)" )
			)
			( signal "M_A_DQ<5>"
				( objectStatus "@baseboard_fab2_lib.baseboard_fab2(sch_1):m_a_dq(5)" )
			)
			( signal "M_A_DQ<6>"
				( objectStatus "@baseboard_fab2_lib.baseboard_fab2(sch_1):m_a_dq(6)" )
			)
			( signal "M_A_DQ<7>"
				( objectStatus "@baseboard_fab2_lib.baseboard_fab2(sch_1):m_a_dq(7)" )
			)
			( signal "M_A_DQ<8>"
				( objectStatus "@baseboard_fab2_lib.baseboard_fab2(sch_1):m_a_dq(8)" )
			)
			( signal "M_A_DQ<9>"
				( objectStatus "@baseboard_fab2_lib.baseboard_fab2(sch_1):m_a_dq(9)" )
			)
			( signal "M_A_DQ<10>"
				( objectStatus "@baseboard_fab2_lib.baseboard_fab2(sch_1):m_a_dq(10)" )
			)
			( signal "M_A_DQ<11>"
				( objectStatus "@baseboard_fab2_lib.baseboard_fab2(sch_1):m_a_dq(11)" )
			)
			( signal "M_A_DQ<12>"
				( objectStatus "@baseboard_fab2_lib.baseboard_fab2(sch_1):m_a_dq(12)" )
			)
			( signal "M_A_DQ<13>"
				( objectStatus "@baseboard_fab2_lib.baseboard_fab2(sch_1):m_a_dq(13)" )
			)
			( signal "M_A_DQ<14>"
				( objectStatus "@baseboard_fab2_lib.baseboard_fab2(sch_1):m_a_dq(14)" )
			)
			( signal "M_A_DQ<15>"
				( objectStatus "@baseboard_fab2_lib.baseboard_fab2(sch_1):m_a_dq(15)" )
			)
			( signal "M_A_DQ<16>"
				( objectStatus "@baseboard_fab2_lib.baseboard_fab2(sch_1):m_a_dq(16)" )
			)
			( signal "M_A_DQ<17>"
				( objectStatus "@baseboard_fab2_lib.baseboard_fab2(sch_1):m_a_dq(17)" )
			)
			( signal "M_A_DQ<18>"
				( objectStatus "@baseboard_fab2_lib.baseboard_fab2(sch_1):m_a_dq(18)" )
			)
			( signal "M_A_DQ<19>"
				( objectStatus "@baseboard_fab2_lib.baseboard_fab2(sch_1):m_a_dq(19)" )
			)
			( signal "M_A_DQ<20>"
				( objectStatus "@baseboard_fab2_lib.baseboard_fab2(sch_1):m_a_dq(20)" )
			)
			( signal "M_A_DQ<21>"
				( objectStatus "@baseboard_fab2_lib.baseboard_fab2(sch_1):m_a_dq(21)" )
			)
			( signal "M_A_DQ<22>"
				( objectStatus "@baseboard_fab2_lib.baseboard_fab2(sch_1):m_a_dq(22)" )
			)
			( signal "M_A_DQ<23>"
				( objectStatus "@baseboard_fab2_lib.baseboard_fab2(sch_1):m_a_dq(23)" )
			)
			( signal "M_A_DQ<24>"
				( objectStatus "@baseboard_fab2_lib.baseboard_fab2(sch_1):m_a_dq(24)" )
			)
			( signal "M_A_DQ<25>"
				( objectStatus "@baseboard_fab2_lib.baseboard_fab2(sch_1):m_a_dq(25)" )
			)
			( signal "M_A_DQ<26>"
				( objectStatus "@baseboard_fab2_lib.baseboard_fab2(sch_1):m_a_dq(26)" )
			)
			( signal "M_A_DQ<27>"
				( objectStatus "@baseboard_fab2_lib.baseboard_fab2(sch_1):m_a_dq(27)" )
			)
			( signal "M_A_DQ<28>"
				( objectStatus "@baseboard_fab2_lib.baseboard_fab2(sch_1):m_a_dq(28)" )
			)
			( signal "M_A_DQ<29>"
				( objectStatus "@baseboard_fab2_lib.baseboard_fab2(sch_1):m_a_dq(29)" )
			)
			( signal "M_A_DQ<30>"
				( objectStatus "@baseboard_fab2_lib.baseboard_fab2(sch_1):m_a_dq(30)" )
			)
			( signal "M_A_DQ<31>"
				( objectStatus "@baseboard_fab2_lib.baseboard_fab2(sch_1):m_a_dq(31)" )
			)
			( signal "M_A_DQ<32>"
				( objectStatus "@baseboard_fab2_lib.baseboard_fab2(sch_1):m_a_dq(32)" )
			)
			( signal "M_A_DQ<33>"
				( objectStatus "@baseboard_fab2_lib.baseboard_fab2(sch_1):m_a_dq(33)" )
			)
			( signal "M_A_DQ<34>"
				( objectStatus "@baseboard_fab2_lib.baseboard_fab2(sch_1):m_a_dq(34)" )
			)
			( signal "M_A_DQ<35>"
				( objectStatus "@baseboard_fab2_lib.baseboard_fab2(sch_1):m_a_dq(35)" )
			)
			( signal "M_A_DQ<36>"
				( objectStatus "@baseboard_fab2_lib.baseboard_fab2(sch_1):m_a_dq(36)" )
			)
			( signal "M_A_DQ<37>"
				( objectStatus "@baseboard_fab2_lib.baseboard_fab2(sch_1):m_a_dq(37)" )
			)
			( signal "M_A_DQ<38>"
				( objectStatus "@baseboard_fab2_lib.baseboard_fab2(sch_1):m_a_dq(38)" )
			)
			( signal "M_A_DQ<39>"
				( objectStatus "@baseboard_fab2_lib.baseboard_fab2(sch_1):m_a_dq(39)" )
			)
			( signal "M_A_DQ<40>"
				( objectStatus "@baseboard_fab2_lib.baseboard_fab2(sch_1):m_a_dq(40)" )
			)
			( signal "M_A_DQ<41>"
				( objectStatus "@baseboard_fab2_lib.baseboard_fab2(sch_1):m_a_dq(41)" )
			)
			( signal "M_A_DQ<42>"
				( objectStatus "@baseboard_fab2_lib.baseboard_fab2(sch_1):m_a_dq(42)" )
			)
			( signal "M_A_DQ<43>"
				( objectStatus "@baseboard_fab2_lib.baseboard_fab2(sch_1):m_a_dq(43)" )
			)
			( signal "M_A_DQ<44>"
				( objectStatus "@baseboard_fab2_lib.baseboard_fab2(sch_1):m_a_dq(44)" )
			)
			( signal "M_A_DQ<45>"
				( objectStatus "@baseboard_fab2_lib.baseboard_fab2(sch_1):m_a_dq(45)" )
			)
			( signal "M_A_DQ<46>"
				( objectStatus "@baseboard_fab2_lib.baseboard_fab2(sch_1):m_a_dq(46)" )
			)
			( signal "M_A_DQ<47>"
				( objectStatus "@baseboard_fab2_lib.baseboard_fab2(sch_1):m_a_dq(47)" )
			)
			( signal "M_A_DQ<48>"
				( objectStatus "@baseboard_fab2_lib.baseboard_fab2(sch_1):m_a_dq(48)" )
			)
			( signal "M_A_DQ<49>"
				( objectStatus "@baseboard_fab2_lib.baseboard_fab2(sch_1):m_a_dq(49)" )
			)
			( signal "M_A_DQ<50>"
				( objectStatus "@baseboard_fab2_lib.baseboard_fab2(sch_1):m_a_dq(50)" )
			)
			( signal "M_A_DQ<51>"
				( objectStatus "@baseboard_fab2_lib.baseboard_fab2(sch_1):m_a_dq(51)" )
			)
			( signal "M_A_DQ<52>"
				( objectStatus "@baseboard_fab2_lib.baseboard_fab2(sch_1):m_a_dq(52)" )
			)
			( signal "M_A_DQ<53>"
				( objectStatus "@baseboard_fab2_lib.baseboard_fab2(sch_1):m_a_dq(53)" )
			)
			( signal "M_A_DQ<54>"
				( objectStatus "@baseboard_fab2_lib.baseboard_fab2(sch_1):m_a_dq(54)" )
			)
			( signal "M_A_DQ<55>"
				( objectStatus "@baseboard_fab2_lib.baseboard_fab2(sch_1):m_a_dq(55)" )
			)
			( signal "M_A_DQ<56>"
				( objectStatus "@baseboard_fab2_lib.baseboard_fab2(sch_1):m_a_dq(56)" )
			)
			( signal "M_A_DQ<57>"
				( objectStatus "@baseboard_fab2_lib.baseboard_fab2(sch_1):m_a_dq(57)" )
			)
			( signal "M_A_DQ<58>"
				( objectStatus "@baseboard_fab2_lib.baseboard_fab2(sch_1):m_a_dq(58)" )
			)
			( signal "M_A_DQ<59>"
				( objectStatus "@baseboard_fab2_lib.baseboard_fab2(sch_1):m_a_dq(59)" )
			)
			( signal "M_A_DQ<60>"
				( objectStatus "@baseboard_fab2_lib.baseboard_fab2(sch_1):m_a_dq(60)" )
			)
			( signal "M_A_DQ<61>"
				( objectStatus "@baseboard_fab2_lib.baseboard_fab2(sch_1):m_a_dq(61)" )
			)
			( signal "M_A_DQ<62>"
				( objectStatus "@baseboard_fab2_lib.baseboard_fab2(sch_1):m_a_dq(62)" )
			)
			( signal "M_A_DQ<63>"
				( objectStatus "@baseboard_fab2_lib.baseboard_fab2(sch_1):m_a_dq(63)" )
			)
			( signal "M_A_DQS_DN<0>"
				( objectStatus "@baseboard_fab2_lib.baseboard_fab2(sch_1):m_a_dqs_dn(0)" )
			)
			( signal "M_A_DQS_DN<1>"
				( objectStatus "@baseboard_fab2_lib.baseboard_fab2(sch_1):m_a_dqs_dn(1)" )
			)
			( signal "M_A_DQS_DN<2>"
				( objectStatus "@baseboard_fab2_lib.baseboard_fab2(sch_1):m_a_dqs_dn(2)" )
			)
			( signal "M_A_DQS_DN<3>"
				( objectStatus "@baseboard_fab2_lib.baseboard_fab2(sch_1):m_a_dqs_dn(3)" )
			)
			( signal "M_A_DQS_DN<4>"
				( objectStatus "@baseboard_fab2_lib.baseboard_fab2(sch_1):m_a_dqs_dn(4)" )
			)
			( signal "M_A_DQS_DN<5>"
				( objectStatus "@baseboard_fab2_lib.baseboard_fab2(sch_1):m_a_dqs_dn(5)" )
			)
			( signal "M_A_DQS_DN<6>"
				( objectStatus "@baseboard_fab2_lib.baseboard_fab2(sch_1):m_a_dqs_dn(6)" )
			)
			( signal "M_A_DQS_DN<7>"
				( objectStatus "@baseboard_fab2_lib.baseboard_fab2(sch_1):m_a_dqs_dn(7)" )
			)
			( signal "M_A_DQS_DN<8>"
				( objectStatus "@baseboard_fab2_lib.baseboard_fab2(sch_1):m_a_dqs_dn(8)" )
			)
			( signal "M_A_DQS_DN<9>"
				( objectStatus "@baseboard_fab2_lib.baseboard_fab2(sch_1):m_a_dqs_dn(9)" )
			)
			( signal "M_A_DQS_DN<10>"
				( objectStatus "@baseboard_fab2_lib.baseboard_fab2(sch_1):m_a_dqs_dn(10)" )
			)
			( signal "M_A_DQS_DN<11>"
				( objectStatus "@baseboard_fab2_lib.baseboard_fab2(sch_1):m_a_dqs_dn(11)" )
			)
			( signal "M_A_DQS_DN<12>"
				( objectStatus "@baseboard_fab2_lib.baseboard_fab2(sch_1):m_a_dqs_dn(12)" )
			)
			( signal "M_A_DQS_DN<13>"
				( objectStatus "@baseboard_fab2_lib.baseboard_fab2(sch_1):m_a_dqs_dn(13)" )
			)
			( signal "M_A_DQS_DN<14>"
				( objectStatus "@baseboard_fab2_lib.baseboard_fab2(sch_1):m_a_dqs_dn(14)" )
			)
			( signal "M_A_DQS_DN<15>"
				( objectStatus "@baseboard_fab2_lib.baseboard_fab2(sch_1):m_a_dqs_dn(15)" )
			)
			( signal "M_A_DQS_DN<16>"
				( objectStatus "@baseboard_fab2_lib.baseboard_fab2(sch_1):m_a_dqs_dn(16)" )
			)
			( signal "M_A_DQS_DN<17>"
				( objectStatus "@baseboard_fab2_lib.baseboard_fab2(sch_1):m_a_dqs_dn(17)" )
			)
			( signal "M_A_DQS_DP<0>"
				( objectStatus "@baseboard_fab2_lib.baseboard_fab2(sch_1):m_a_dqs_dp(0)" )
			)
			( signal "M_A_DQS_DP<1>"
				( objectStatus "@baseboard_fab2_lib.baseboard_fab2(sch_1):m_a_dqs_dp(1)" )
			)
			( signal "M_A_DQS_DP<2>"
				( objectStatus "@baseboard_fab2_lib.baseboard_fab2(sch_1):m_a_dqs_dp(2)" )
			)
			( signal "M_A_DQS_DP<3>"
				( objectStatus "@baseboard_fab2_lib.baseboard_fab2(sch_1):m_a_dqs_dp(3)" )
			)
			( signal "M_A_DQS_DP<4>"
				( objectStatus "@baseboard_fab2_lib.baseboard_fab2(sch_1):m_a_dqs_dp(4)" )
			)
			( signal "M_A_DQS_DP<5>"
				( objectStatus "@baseboard_fab2_lib.baseboard_fab2(sch_1):m_a_dqs_dp(5)" )
			)
			( signal "M_A_DQS_DP<6>"
				( objectStatus "@baseboard_fab2_lib.baseboard_fab2(sch_1):m_a_dqs_dp(6)" )
			)
			( signal "M_A_DQS_DP<7>"
				( objectStatus "@baseboard_fab2_lib.baseboard_fab2(sch_1):m_a_dqs_dp(7)" )
			)
			( signal "M_A_DQS_DP<8>"
				( objectStatus "@baseboard_fab2_lib.baseboard_fab2(sch_1):m_a_dqs_dp(8)" )
			)
			( signal "M_A_DQS_DP<9>"
				( objectStatus "@baseboard_fab2_lib.baseboard_fab2(sch_1):m_a_dqs_dp(9)" )
			)
			( signal "M_A_DQS_DP<10>"
				( objectStatus "@baseboard_fab2_lib.baseboard_fab2(sch_1):m_a_dqs_dp(10)" )
			)
			( signal "M_A_DQS_DP<11>"
				( objectStatus "@baseboard_fab2_lib.baseboard_fab2(sch_1):m_a_dqs_dp(11)" )
			)
			( signal "M_A_DQS_DP<12>"
				( objectStatus "@baseboard_fab2_lib.baseboard_fab2(sch_1):m_a_dqs_dp(12)" )
			)
			( signal "M_A_DQS_DP<13>"
				( objectStatus "@baseboard_fab2_lib.baseboard_fab2(sch_1):m_a_dqs_dp(13)" )
			)
			( signal "M_A_DQS_DP<14>"
				( objectStatus "@baseboard_fab2_lib.baseboard_fab2(sch_1):m_a_dqs_dp(14)" )
			)
			( signal "M_A_DQS_DP<15>"
				( objectStatus "@baseboard_fab2_lib.baseboard_fab2(sch_1):m_a_dqs_dp(15)" )
			)
			( signal "M_A_DQS_DP<16>"
				( objectStatus "@baseboard_fab2_lib.baseboard_fab2(sch_1):m_a_dqs_dp(16)" )
			)
			( signal "M_A_DQS_DP<17>"
				( objectStatus "@baseboard_fab2_lib.baseboard_fab2(sch_1):m_a_dqs_dp(17)" )
			)
			( signal "M_A_ECC<0>"
				( objectStatus "@baseboard_fab2_lib.baseboard_fab2(sch_1):m_a_ecc(0)" )
			)
			( signal "M_A_ECC<1>"
				( objectStatus "@baseboard_fab2_lib.baseboard_fab2(sch_1):m_a_ecc(1)" )
			)
			( signal "M_A_ECC<2>"
				( objectStatus "@baseboard_fab2_lib.baseboard_fab2(sch_1):m_a_ecc(2)" )
			)
			( signal "M_A_ECC<3>"
				( objectStatus "@baseboard_fab2_lib.baseboard_fab2(sch_1):m_a_ecc(3)" )
			)
			( signal "M_A_ECC<4>"
				( objectStatus "@baseboard_fab2_lib.baseboard_fab2(sch_1):m_a_ecc(4)" )
			)
			( signal "M_A_ECC<5>"
				( objectStatus "@baseboard_fab2_lib.baseboard_fab2(sch_1):m_a_ecc(5)" )
			)
			( signal "M_A_ECC<6>"
				( objectStatus "@baseboard_fab2_lib.baseboard_fab2(sch_1):m_a_ecc(6)" )
			)
			( signal "M_A_ECC<7>"
				( objectStatus "@baseboard_fab2_lib.baseboard_fab2(sch_1):m_a_ecc(7)" )
			)
			( signal "M_A_MA<0>"
				( objectStatus "@baseboard_fab2_lib.baseboard_fab2(sch_1):m_a_ma(0)" )
			)
			( signal "M_A_MA<1>"
				( objectStatus "@baseboard_fab2_lib.baseboard_fab2(sch_1):m_a_ma(1)" )
			)
			( signal "M_A_MA<2>"
				( objectStatus "@baseboard_fab2_lib.baseboard_fab2(sch_1):m_a_ma(2)" )
			)
			( signal "M_A_MA<3>"
				( objectStatus "@baseboard_fab2_lib.baseboard_fab2(sch_1):m_a_ma(3)" )
			)
			( signal "M_A_MA<4>"
				( objectStatus "@baseboard_fab2_lib.baseboard_fab2(sch_1):m_a_ma(4)" )
			)
			( signal "M_A_MA<5>"
				( objectStatus "@baseboard_fab2_lib.baseboard_fab2(sch_1):m_a_ma(5)" )
			)
			( signal "M_A_MA<6>"
				( objectStatus "@baseboard_fab2_lib.baseboard_fab2(sch_1):m_a_ma(6)" )
			)
			( signal "M_A_MA<7>"
				( objectStatus "@baseboard_fab2_lib.baseboard_fab2(sch_1):m_a_ma(7)" )
			)
			( signal "M_A_MA<8>"
				( objectStatus "@baseboard_fab2_lib.baseboard_fab2(sch_1):m_a_ma(8)" )
			)
			( signal "M_A_MA<9>"
				( objectStatus "@baseboard_fab2_lib.baseboard_fab2(sch_1):m_a_ma(9)" )
			)
			( signal "M_A_MA<10>"
				( objectStatus "@baseboard_fab2_lib.baseboard_fab2(sch_1):m_a_ma(10)" )
			)
			( signal "M_A_MA<11>"
				( objectStatus "@baseboard_fab2_lib.baseboard_fab2(sch_1):m_a_ma(11)" )
			)
			( signal "M_A_MA<12>"
				( objectStatus "@baseboard_fab2_lib.baseboard_fab2(sch_1):m_a_ma(12)" )
			)
			( signal "M_A_MA<13>"
				( objectStatus "@baseboard_fab2_lib.baseboard_fab2(sch_1):m_a_ma(13)" )
			)
			( signal "M_A_MA<14>"
				( objectStatus "@baseboard_fab2_lib.baseboard_fab2(sch_1):m_a_ma(14)" )
			)
			( signal "M_A_MA<15>"
				( objectStatus "@baseboard_fab2_lib.baseboard_fab2(sch_1):m_a_ma(15)" )
			)
			( signal "M_A_MA<16>"
				( objectStatus "@baseboard_fab2_lib.baseboard_fab2(sch_1):m_a_ma(16)" )
			)
			( signal "M_A_MA<17>"
				( objectStatus "@baseboard_fab2_lib.baseboard_fab2(sch_1):m_a_ma(17)" )
			)
			( signal "M_A_ODT<0>"
				( objectStatus "@baseboard_fab2_lib.baseboard_fab2(sch_1):m_a_odt(0)" )
			)
			( signal "M_A_ODT<1>"
				( objectStatus "@baseboard_fab2_lib.baseboard_fab2(sch_1):m_a_odt(1)" )
			)
			( signal "M_A_ODT<2>"
				( objectStatus "@baseboard_fab2_lib.baseboard_fab2(sch_1):m_a_odt(2)" )
			)
			( signal "M_A_ODT<3>"
				( objectStatus "@baseboard_fab2_lib.baseboard_fab2(sch_1):m_a_odt(3)" )
			)
			( signal "M_A_PAR"
				( objectStatus "@baseboard_fab2_lib.baseboard_fab2(sch_1):m_a_par" )
			)
			( signal "M_B_ACT_N"
				( objectStatus "@baseboard_fab2_lib.baseboard_fab2(sch_1):m_b_act_n" )
			)
			( signal "M_B_ALERT_N"
				( objectStatus "@baseboard_fab2_lib.baseboard_fab2(sch_1):m_b_alert_n" )
			)
			( signal "M_B_BA<0>"
				( objectStatus "@baseboard_fab2_lib.baseboard_fab2(sch_1):m_b_ba(0)" )
			)
			( signal "M_B_BA<1>"
				( objectStatus "@baseboard_fab2_lib.baseboard_fab2(sch_1):m_b_ba(1)" )
			)
			( signal "M_B_BG<0>"
				( objectStatus "@baseboard_fab2_lib.baseboard_fab2(sch_1):m_b_bg(0)" )
			)
			( signal "M_B_BG<1>"
				( objectStatus "@baseboard_fab2_lib.baseboard_fab2(sch_1):m_b_bg(1)" )
			)
			( signal "M_B_C<2>"
				( objectStatus "@baseboard_fab2_lib.baseboard_fab2(sch_1):m_b_c(2)" )
			)
			( signal "M_B_CKE<0>"
				( objectStatus "@baseboard_fab2_lib.baseboard_fab2(sch_1):m_b_cke(0)" )
			)
			( signal "M_B_CKE<1>"
				( objectStatus "@baseboard_fab2_lib.baseboard_fab2(sch_1):m_b_cke(1)" )
			)
			( signal "M_B_CKE<2>"
				( objectStatus "@baseboard_fab2_lib.baseboard_fab2(sch_1):m_b_cke(2)" )
			)
			( signal "M_B_CKE<3>"
				( objectStatus "@baseboard_fab2_lib.baseboard_fab2(sch_1):m_b_cke(3)" )
			)
			( signal "M_B_CLK_DN<0>"
				( objectStatus "@baseboard_fab2_lib.baseboard_fab2(sch_1):m_b_clk_dn(0)" )
			)
			( signal "M_B_CLK_DN<1>"
				( objectStatus "@baseboard_fab2_lib.baseboard_fab2(sch_1):m_b_clk_dn(1)" )
			)
			( signal "M_B_CLK_DN<2>"
				( objectStatus "@baseboard_fab2_lib.baseboard_fab2(sch_1):m_b_clk_dn(2)" )
			)
			( signal "M_B_CLK_DN<3>"
				( objectStatus "@baseboard_fab2_lib.baseboard_fab2(sch_1):m_b_clk_dn(3)" )
			)
			( signal "M_B_CLK_DP<0>"
				( objectStatus "@baseboard_fab2_lib.baseboard_fab2(sch_1):m_b_clk_dp(0)" )
			)
			( signal "M_B_CLK_DP<1>"
				( objectStatus "@baseboard_fab2_lib.baseboard_fab2(sch_1):m_b_clk_dp(1)" )
			)
			( signal "M_B_CLK_DP<2>"
				( objectStatus "@baseboard_fab2_lib.baseboard_fab2(sch_1):m_b_clk_dp(2)" )
			)
			( signal "M_B_CLK_DP<3>"
				( objectStatus "@baseboard_fab2_lib.baseboard_fab2(sch_1):m_b_clk_dp(3)" )
			)
			( signal "M_B_CS_N<0>"
				( objectStatus "@baseboard_fab2_lib.baseboard_fab2(sch_1):m_b_cs_n(0)" )
			)
			( signal "M_B_CS_N<1>"
				( objectStatus "@baseboard_fab2_lib.baseboard_fab2(sch_1):m_b_cs_n(1)" )
			)
			( signal "M_B_CS_N<2>"
				( objectStatus "@baseboard_fab2_lib.baseboard_fab2(sch_1):m_b_cs_n(2)" )
			)
			( signal "M_B_CS_N<3>"
				( objectStatus "@baseboard_fab2_lib.baseboard_fab2(sch_1):m_b_cs_n(3)" )
			)
			( signal "M_B_CS_N<4>"
				( objectStatus "@baseboard_fab2_lib.baseboard_fab2(sch_1):m_b_cs_n(4)" )
			)
			( signal "M_B_CS_N<5>"
				( objectStatus "@baseboard_fab2_lib.baseboard_fab2(sch_1):m_b_cs_n(5)" )
			)
			( signal "M_B_CS_N<6>"
				( objectStatus "@baseboard_fab2_lib.baseboard_fab2(sch_1):m_b_cs_n(6)" )
			)
			( signal "M_B_CS_N<7>"
				( objectStatus "@baseboard_fab2_lib.baseboard_fab2(sch_1):m_b_cs_n(7)" )
			)
			( signal "M_B_DQ<0>"
				( objectStatus "@baseboard_fab2_lib.baseboard_fab2(sch_1):m_b_dq(0)" )
			)
			( signal "M_B_DQ<1>"
				( objectStatus "@baseboard_fab2_lib.baseboard_fab2(sch_1):m_b_dq(1)" )
			)
			( signal "M_B_DQ<2>"
				( objectStatus "@baseboard_fab2_lib.baseboard_fab2(sch_1):m_b_dq(2)" )
			)
			( signal "M_B_DQ<3>"
				( objectStatus "@baseboard_fab2_lib.baseboard_fab2(sch_1):m_b_dq(3)" )
			)
			( signal "M_B_DQ<4>"
				( objectStatus "@baseboard_fab2_lib.baseboard_fab2(sch_1):m_b_dq(4)" )
			)
			( signal "M_B_DQ<5>"
				( objectStatus "@baseboard_fab2_lib.baseboard_fab2(sch_1):m_b_dq(5)" )
			)
			( signal "M_B_DQ<6>"
				( objectStatus "@baseboard_fab2_lib.baseboard_fab2(sch_1):m_b_dq(6)" )
			)
			( signal "M_B_DQ<7>"
				( objectStatus "@baseboard_fab2_lib.baseboard_fab2(sch_1):m_b_dq(7)" )
			)
			( signal "M_B_DQ<8>"
				( objectStatus "@baseboard_fab2_lib.baseboard_fab2(sch_1):m_b_dq(8)" )
			)
			( signal "M_B_DQ<9>"
				( objectStatus "@baseboard_fab2_lib.baseboard_fab2(sch_1):m_b_dq(9)" )
			)
			( signal "M_B_DQ<10>"
				( objectStatus "@baseboard_fab2_lib.baseboard_fab2(sch_1):m_b_dq(10)" )
			)
			( signal "M_B_DQ<11>"
				( objectStatus "@baseboard_fab2_lib.baseboard_fab2(sch_1):m_b_dq(11)" )
			)
			( signal "M_B_DQ<12>"
				( objectStatus "@baseboard_fab2_lib.baseboard_fab2(sch_1):m_b_dq(12)" )
			)
			( signal "M_B_DQ<13>"
				( objectStatus "@baseboard_fab2_lib.baseboard_fab2(sch_1):m_b_dq(13)" )
			)
			( signal "M_B_DQ<14>"
				( objectStatus "@baseboard_fab2_lib.baseboard_fab2(sch_1):m_b_dq(14)" )
			)
			( signal "M_B_DQ<15>"
				( objectStatus "@baseboard_fab2_lib.baseboard_fab2(sch_1):m_b_dq(15)" )
			)
			( signal "M_B_DQ<16>"
				( objectStatus "@baseboard_fab2_lib.baseboard_fab2(sch_1):m_b_dq(16)" )
			)
			( signal "M_B_DQ<17>"
				( objectStatus "@baseboard_fab2_lib.baseboard_fab2(sch_1):m_b_dq(17)" )
			)
			( signal "M_B_DQ<18>"
				( objectStatus "@baseboard_fab2_lib.baseboard_fab2(sch_1):m_b_dq(18)" )
			)
			( signal "M_B_DQ<19>"
				( objectStatus "@baseboard_fab2_lib.baseboard_fab2(sch_1):m_b_dq(19)" )
			)
			( signal "M_B_DQ<20>"
				( objectStatus "@baseboard_fab2_lib.baseboard_fab2(sch_1):m_b_dq(20)" )
			)
			( signal "M_B_DQ<21>"
				( objectStatus "@baseboard_fab2_lib.baseboard_fab2(sch_1):m_b_dq(21)" )
			)
			( signal "M_B_DQ<22>"
				( objectStatus "@baseboard_fab2_lib.baseboard_fab2(sch_1):m_b_dq(22)" )
			)
			( signal "M_B_DQ<23>"
				( objectStatus "@baseboard_fab2_lib.baseboard_fab2(sch_1):m_b_dq(23)" )
			)
			( signal "M_B_DQ<24>"
				( objectStatus "@baseboard_fab2_lib.baseboard_fab2(sch_1):m_b_dq(24)" )
			)
			( signal "M_B_DQ<25>"
				( objectStatus "@baseboard_fab2_lib.baseboard_fab2(sch_1):m_b_dq(25)" )
			)
			( signal "M_B_DQ<26>"
				( objectStatus "@baseboard_fab2_lib.baseboard_fab2(sch_1):m_b_dq(26)" )
			)
			( signal "M_B_DQ<27>"
				( objectStatus "@baseboard_fab2_lib.baseboard_fab2(sch_1):m_b_dq(27)" )
			)
			( signal "M_B_DQ<28>"
				( objectStatus "@baseboard_fab2_lib.baseboard_fab2(sch_1):m_b_dq(28)" )
			)
			( signal "M_B_DQ<29>"
				( objectStatus "@baseboard_fab2_lib.baseboard_fab2(sch_1):m_b_dq(29)" )
			)
			( signal "M_B_DQ<30>"
				( objectStatus "@baseboard_fab2_lib.baseboard_fab2(sch_1):m_b_dq(30)" )
			)
			( signal "M_B_DQ<31>"
				( objectStatus "@baseboard_fab2_lib.baseboard_fab2(sch_1):m_b_dq(31)" )
			)
			( signal "M_B_DQ<32>"
				( objectStatus "@baseboard_fab2_lib.baseboard_fab2(sch_1):m_b_dq(32)" )
			)
			( signal "M_B_DQ<33>"
				( objectStatus "@baseboard_fab2_lib.baseboard_fab2(sch_1):m_b_dq(33)" )
			)
			( signal "M_B_DQ<34>"
				( objectStatus "@baseboard_fab2_lib.baseboard_fab2(sch_1):m_b_dq(34)" )
			)
			( signal "M_B_DQ<35>"
				( objectStatus "@baseboard_fab2_lib.baseboard_fab2(sch_1):m_b_dq(35)" )
			)
			( signal "M_B_DQ<36>"
				( objectStatus "@baseboard_fab2_lib.baseboard_fab2(sch_1):m_b_dq(36)" )
			)
			( signal "M_B_DQ<37>"
				( objectStatus "@baseboard_fab2_lib.baseboard_fab2(sch_1):m_b_dq(37)" )
			)
			( signal "M_B_DQ<38>"
				( objectStatus "@baseboard_fab2_lib.baseboard_fab2(sch_1):m_b_dq(38)" )
			)
			( signal "M_B_DQ<39>"
				( objectStatus "@baseboard_fab2_lib.baseboard_fab2(sch_1):m_b_dq(39)" )
			)
			( signal "M_B_DQ<40>"
				( objectStatus "@baseboard_fab2_lib.baseboard_fab2(sch_1):m_b_dq(40)" )
			)
			( signal "M_B_DQ<41>"
				( objectStatus "@baseboard_fab2_lib.baseboard_fab2(sch_1):m_b_dq(41)" )
			)
			( signal "M_B_DQ<42>"
				( objectStatus "@baseboard_fab2_lib.baseboard_fab2(sch_1):m_b_dq(42)" )
			)
			( signal "M_B_DQ<43>"
				( objectStatus "@baseboard_fab2_lib.baseboard_fab2(sch_1):m_b_dq(43)" )
			)
			( signal "M_B_DQ<44>"
				( objectStatus "@baseboard_fab2_lib.baseboard_fab2(sch_1):m_b_dq(44)" )
			)
			( signal "M_B_DQ<45>"
				( objectStatus "@baseboard_fab2_lib.baseboard_fab2(sch_1):m_b_dq(45)" )
			)
			( signal "M_B_DQ<46>"
				( objectStatus "@baseboard_fab2_lib.baseboard_fab2(sch_1):m_b_dq(46)" )
			)
			( signal "M_B_DQ<47>"
				( objectStatus "@baseboard_fab2_lib.baseboard_fab2(sch_1):m_b_dq(47)" )
			)
			( signal "M_B_DQ<48>"
				( objectStatus "@baseboard_fab2_lib.baseboard_fab2(sch_1):m_b_dq(48)" )
			)
			( signal "M_B_DQ<49>"
				( objectStatus "@baseboard_fab2_lib.baseboard_fab2(sch_1):m_b_dq(49)" )
			)
			( signal "M_B_DQ<50>"
				( objectStatus "@baseboard_fab2_lib.baseboard_fab2(sch_1):m_b_dq(50)" )
			)
			( signal "M_B_DQ<51>"
				( objectStatus "@baseboard_fab2_lib.baseboard_fab2(sch_1):m_b_dq(51)" )
			)
			( signal "M_B_DQ<52>"
				( objectStatus "@baseboard_fab2_lib.baseboard_fab2(sch_1):m_b_dq(52)" )
			)
			( signal "M_B_DQ<53>"
				( objectStatus "@baseboard_fab2_lib.baseboard_fab2(sch_1):m_b_dq(53)" )
			)
			( signal "M_B_DQ<54>"
				( objectStatus "@baseboard_fab2_lib.baseboard_fab2(sch_1):m_b_dq(54)" )
			)
			( signal "M_B_DQ<55>"
				( objectStatus "@baseboard_fab2_lib.baseboard_fab2(sch_1):m_b_dq(55)" )
			)
			( signal "M_B_DQ<56>"
				( objectStatus "@baseboard_fab2_lib.baseboard_fab2(sch_1):m_b_dq(56)" )
			)
			( signal "M_B_DQ<57>"
				( objectStatus "@baseboard_fab2_lib.baseboard_fab2(sch_1):m_b_dq(57)" )
			)
			( signal "M_B_DQ<58>"
				( objectStatus "@baseboard_fab2_lib.baseboard_fab2(sch_1):m_b_dq(58)" )
			)
			( signal "M_B_DQ<59>"
				( objectStatus "@baseboard_fab2_lib.baseboard_fab2(sch_1):m_b_dq(59)" )
			)
			( signal "M_B_DQ<60>"
				( objectStatus "@baseboard_fab2_lib.baseboard_fab2(sch_1):m_b_dq(60)" )
			)
			( signal "M_B_DQ<61>"
				( objectStatus "@baseboard_fab2_lib.baseboard_fab2(sch_1):m_b_dq(61)" )
			)
			( signal "M_B_DQ<62>"
				( objectStatus "@baseboard_fab2_lib.baseboard_fab2(sch_1):m_b_dq(62)" )
			)
			( signal "M_B_DQ<63>"
				( objectStatus "@baseboard_fab2_lib.baseboard_fab2(sch_1):m_b_dq(63)" )
			)
			( signal "M_B_DQS_DN<0>"
				( objectStatus "@baseboard_fab2_lib.baseboard_fab2(sch_1):m_b_dqs_dn(0)" )
			)
			( signal "M_B_DQS_DN<1>"
				( objectStatus "@baseboard_fab2_lib.baseboard_fab2(sch_1):m_b_dqs_dn(1)" )
			)
			( signal "M_B_DQS_DN<2>"
				( objectStatus "@baseboard_fab2_lib.baseboard_fab2(sch_1):m_b_dqs_dn(2)" )
			)
			( signal "M_B_DQS_DN<3>"
				( objectStatus "@baseboard_fab2_lib.baseboard_fab2(sch_1):m_b_dqs_dn(3)" )
			)
			( signal "M_B_DQS_DN<4>"
				( objectStatus "@baseboard_fab2_lib.baseboard_fab2(sch_1):m_b_dqs_dn(4)" )
			)
			( signal "M_B_DQS_DN<5>"
				( objectStatus "@baseboard_fab2_lib.baseboard_fab2(sch_1):m_b_dqs_dn(5)" )
			)
			( signal "M_B_DQS_DN<6>"
				( objectStatus "@baseboard_fab2_lib.baseboard_fab2(sch_1):m_b_dqs_dn(6)" )
			)
			( signal "M_B_DQS_DN<7>"
				( objectStatus "@baseboard_fab2_lib.baseboard_fab2(sch_1):m_b_dqs_dn(7)" )
			)
			( signal "M_B_DQS_DN<8>"
				( objectStatus "@baseboard_fab2_lib.baseboard_fab2(sch_1):m_b_dqs_dn(8)" )
			)
			( signal "M_B_DQS_DN<9>"
				( objectStatus "@baseboard_fab2_lib.baseboard_fab2(sch_1):m_b_dqs_dn(9)" )
			)
			( signal "M_B_DQS_DN<10>"
				( objectStatus "@baseboard_fab2_lib.baseboard_fab2(sch_1):m_b_dqs_dn(10)" )
			)
			( signal "M_B_DQS_DN<11>"
				( objectStatus "@baseboard_fab2_lib.baseboard_fab2(sch_1):m_b_dqs_dn(11)" )
			)
			( signal "M_B_DQS_DN<12>"
				( objectStatus "@baseboard_fab2_lib.baseboard_fab2(sch_1):m_b_dqs_dn(12)" )
			)
			( signal "M_B_DQS_DN<13>"
				( objectStatus "@baseboard_fab2_lib.baseboard_fab2(sch_1):m_b_dqs_dn(13)" )
			)
			( signal "M_B_DQS_DN<14>"
				( objectStatus "@baseboard_fab2_lib.baseboard_fab2(sch_1):m_b_dqs_dn(14)" )
			)
			( signal "M_B_DQS_DN<15>"
				( objectStatus "@baseboard_fab2_lib.baseboard_fab2(sch_1):m_b_dqs_dn(15)" )
			)
			( signal "M_B_DQS_DN<16>"
				( objectStatus "@baseboard_fab2_lib.baseboard_fab2(sch_1):m_b_dqs_dn(16)" )
			)
			( signal "M_B_DQS_DN<17>"
				( objectStatus "@baseboard_fab2_lib.baseboard_fab2(sch_1):m_b_dqs_dn(17)" )
			)
			( signal "M_B_DQS_DP<0>"
				( objectStatus "@baseboard_fab2_lib.baseboard_fab2(sch_1):m_b_dqs_dp(0)" )
			)
			( signal "M_B_DQS_DP<1>"
				( objectStatus "@baseboard_fab2_lib.baseboard_fab2(sch_1):m_b_dqs_dp(1)" )
			)
			( signal "M_B_DQS_DP<2>"
				( objectStatus "@baseboard_fab2_lib.baseboard_fab2(sch_1):m_b_dqs_dp(2)" )
			)
			( signal "M_B_DQS_DP<3>"
				( objectStatus "@baseboard_fab2_lib.baseboard_fab2(sch_1):m_b_dqs_dp(3)" )
			)
			( signal "M_B_DQS_DP<4>"
				( objectStatus "@baseboard_fab2_lib.baseboard_fab2(sch_1):m_b_dqs_dp(4)" )
			)
			( signal "M_B_DQS_DP<5>"
				( objectStatus "@baseboard_fab2_lib.baseboard_fab2(sch_1):m_b_dqs_dp(5)" )
			)
			( signal "M_B_DQS_DP<6>"
				( objectStatus "@baseboard_fab2_lib.baseboard_fab2(sch_1):m_b_dqs_dp(6)" )
			)
			( signal "M_B_DQS_DP<7>"
				( objectStatus "@baseboard_fab2_lib.baseboard_fab2(sch_1):m_b_dqs_dp(7)" )
			)
			( signal "M_B_DQS_DP<8>"
				( objectStatus "@baseboard_fab2_lib.baseboard_fab2(sch_1):m_b_dqs_dp(8)" )
			)
			( signal "M_B_DQS_DP<9>"
				( objectStatus "@baseboard_fab2_lib.baseboard_fab2(sch_1):m_b_dqs_dp(9)" )
			)
			( signal "M_B_DQS_DP<10>"
				( objectStatus "@baseboard_fab2_lib.baseboard_fab2(sch_1):m_b_dqs_dp(10)" )
			)
			( signal "M_B_DQS_DP<11>"
				( objectStatus "@baseboard_fab2_lib.baseboard_fab2(sch_1):m_b_dqs_dp(11)" )
			)
			( signal "M_B_DQS_DP<12>"
				( objectStatus "@baseboard_fab2_lib.baseboard_fab2(sch_1):m_b_dqs_dp(12)" )
			)
			( signal "M_B_DQS_DP<13>"
				( objectStatus "@baseboard_fab2_lib.baseboard_fab2(sch_1):m_b_dqs_dp(13)" )
			)
			( signal "M_B_DQS_DP<14>"
				( objectStatus "@baseboard_fab2_lib.baseboard_fab2(sch_1):m_b_dqs_dp(14)" )
			)
			( signal "M_B_DQS_DP<15>"
				( objectStatus "@baseboard_fab2_lib.baseboard_fab2(sch_1):m_b_dqs_dp(15)" )
			)
			( signal "M_B_DQS_DP<16>"
				( objectStatus "@baseboard_fab2_lib.baseboard_fab2(sch_1):m_b_dqs_dp(16)" )
			)
			( signal "M_B_DQS_DP<17>"
				( objectStatus "@baseboard_fab2_lib.baseboard_fab2(sch_1):m_b_dqs_dp(17)" )
			)
			( signal "M_B_ECC<0>"
				( objectStatus "@baseboard_fab2_lib.baseboard_fab2(sch_1):m_b_ecc(0)" )
			)
			( signal "M_B_ECC<1>"
				( objectStatus "@baseboard_fab2_lib.baseboard_fab2(sch_1):m_b_ecc(1)" )
			)
			( signal "M_B_ECC<2>"
				( objectStatus "@baseboard_fab2_lib.baseboard_fab2(sch_1):m_b_ecc(2)" )
			)
			( signal "M_B_ECC<3>"
				( objectStatus "@baseboard_fab2_lib.baseboard_fab2(sch_1):m_b_ecc(3)" )
			)
			( signal "M_B_ECC<4>"
				( objectStatus "@baseboard_fab2_lib.baseboard_fab2(sch_1):m_b_ecc(4)" )
			)
			( signal "M_B_ECC<5>"
				( objectStatus "@baseboard_fab2_lib.baseboard_fab2(sch_1):m_b_ecc(5)" )
			)
			( signal "M_B_ECC<6>"
				( objectStatus "@baseboard_fab2_lib.baseboard_fab2(sch_1):m_b_ecc(6)" )
			)
			( signal "M_B_ECC<7>"
				( objectStatus "@baseboard_fab2_lib.baseboard_fab2(sch_1):m_b_ecc(7)" )
			)
			( signal "M_B_MA<0>"
				( objectStatus "@baseboard_fab2_lib.baseboard_fab2(sch_1):m_b_ma(0)" )
			)
			( signal "M_B_MA<1>"
				( objectStatus "@baseboard_fab2_lib.baseboard_fab2(sch_1):m_b_ma(1)" )
			)
			( signal "M_B_MA<2>"
				( objectStatus "@baseboard_fab2_lib.baseboard_fab2(sch_1):m_b_ma(2)" )
			)
			( signal "M_B_MA<3>"
				( objectStatus "@baseboard_fab2_lib.baseboard_fab2(sch_1):m_b_ma(3)" )
			)
			( signal "M_B_MA<4>"
				( objectStatus "@baseboard_fab2_lib.baseboard_fab2(sch_1):m_b_ma(4)" )
			)
			( signal "M_B_MA<5>"
				( objectStatus "@baseboard_fab2_lib.baseboard_fab2(sch_1):m_b_ma(5)" )
			)
			( signal "M_B_MA<6>"
				( objectStatus "@baseboard_fab2_lib.baseboard_fab2(sch_1):m_b_ma(6)" )
			)
			( signal "M_B_MA<7>"
				( objectStatus "@baseboard_fab2_lib.baseboard_fab2(sch_1):m_b_ma(7)" )
			)
			( signal "M_B_MA<8>"
				( objectStatus "@baseboard_fab2_lib.baseboard_fab2(sch_1):m_b_ma(8)" )
			)
			( signal "M_B_MA<9>"
				( objectStatus "@baseboard_fab2_lib.baseboard_fab2(sch_1):m_b_ma(9)" )
			)
			( signal "M_B_MA<10>"
				( objectStatus "@baseboard_fab2_lib.baseboard_fab2(sch_1):m_b_ma(10)" )
			)
			( signal "M_B_MA<11>"
				( objectStatus "@baseboard_fab2_lib.baseboard_fab2(sch_1):m_b_ma(11)" )
			)
			( signal "M_B_MA<12>"
				( objectStatus "@baseboard_fab2_lib.baseboard_fab2(sch_1):m_b_ma(12)" )
			)
			( signal "M_B_MA<13>"
				( objectStatus "@baseboard_fab2_lib.baseboard_fab2(sch_1):m_b_ma(13)" )
			)
			( signal "M_B_MA<14>"
				( objectStatus "@baseboard_fab2_lib.baseboard_fab2(sch_1):m_b_ma(14)" )
			)
			( signal "M_B_MA<15>"
				( objectStatus "@baseboard_fab2_lib.baseboard_fab2(sch_1):m_b_ma(15)" )
			)
			( signal "M_B_MA<16>"
				( objectStatus "@baseboard_fab2_lib.baseboard_fab2(sch_1):m_b_ma(16)" )
			)
			( signal "M_B_MA<17>"
				( objectStatus "@baseboard_fab2_lib.baseboard_fab2(sch_1):m_b_ma(17)" )
			)
			( signal "M_B_ODT<0>"
				( objectStatus "@baseboard_fab2_lib.baseboard_fab2(sch_1):m_b_odt(0)" )
			)
			( signal "M_B_ODT<1>"
				( objectStatus "@baseboard_fab2_lib.baseboard_fab2(sch_1):m_b_odt(1)" )
			)
			( signal "M_B_ODT<2>"
				( objectStatus "@baseboard_fab2_lib.baseboard_fab2(sch_1):m_b_odt(2)" )
			)
			( signal "M_B_ODT<3>"
				( objectStatus "@baseboard_fab2_lib.baseboard_fab2(sch_1):m_b_odt(3)" )
			)
			( signal "M_B_PAR"
				( objectStatus "@baseboard_fab2_lib.baseboard_fab2(sch_1):m_b_par" )
			)
			( signal "M_C_ACT_N"
				( objectStatus "@baseboard_fab2_lib.baseboard_fab2(sch_1):m_c_act_n" )
			)
			( signal "M_C_ALERT_N"
				( objectStatus "@baseboard_fab2_lib.baseboard_fab2(sch_1):m_c_alert_n" )
			)
			( signal "M_C_BA<0>"
				( objectStatus "@baseboard_fab2_lib.baseboard_fab2(sch_1):m_c_ba(0)" )
			)
			( signal "M_C_BA<1>"
				( objectStatus "@baseboard_fab2_lib.baseboard_fab2(sch_1):m_c_ba(1)" )
			)
			( signal "M_C_BG<0>"
				( objectStatus "@baseboard_fab2_lib.baseboard_fab2(sch_1):m_c_bg(0)" )
			)
			( signal "M_C_BG<1>"
				( objectStatus "@baseboard_fab2_lib.baseboard_fab2(sch_1):m_c_bg(1)" )
			)
			( signal "M_C_C<2>"
				( objectStatus "@baseboard_fab2_lib.baseboard_fab2(sch_1):m_c_c(2)" )
			)
			( signal "M_C_CKE<0>"
				( objectStatus "@baseboard_fab2_lib.baseboard_fab2(sch_1):m_c_cke(0)" )
			)
			( signal "M_C_CKE<1>"
				( objectStatus "@baseboard_fab2_lib.baseboard_fab2(sch_1):m_c_cke(1)" )
			)
			( signal "M_C_CKE<2>"
				( objectStatus "@baseboard_fab2_lib.baseboard_fab2(sch_1):m_c_cke(2)" )
			)
			( signal "M_C_CKE<3>"
				( objectStatus "@baseboard_fab2_lib.baseboard_fab2(sch_1):m_c_cke(3)" )
			)
			( signal "M_C_CLK_DN<0>"
				( objectStatus "@baseboard_fab2_lib.baseboard_fab2(sch_1):m_c_clk_dn(0)" )
			)
			( signal "M_C_CLK_DN<1>"
				( objectStatus "@baseboard_fab2_lib.baseboard_fab2(sch_1):m_c_clk_dn(1)" )
			)
			( signal "M_C_CLK_DN<2>"
				( objectStatus "@baseboard_fab2_lib.baseboard_fab2(sch_1):m_c_clk_dn(2)" )
			)
			( signal "M_C_CLK_DN<3>"
				( objectStatus "@baseboard_fab2_lib.baseboard_fab2(sch_1):m_c_clk_dn(3)" )
			)
			( signal "M_C_CLK_DP<0>"
				( objectStatus "@baseboard_fab2_lib.baseboard_fab2(sch_1):m_c_clk_dp(0)" )
			)
			( signal "M_C_CLK_DP<1>"
				( objectStatus "@baseboard_fab2_lib.baseboard_fab2(sch_1):m_c_clk_dp(1)" )
			)
			( signal "M_C_CLK_DP<2>"
				( objectStatus "@baseboard_fab2_lib.baseboard_fab2(sch_1):m_c_clk_dp(2)" )
			)
			( signal "M_C_CLK_DP<3>"
				( objectStatus "@baseboard_fab2_lib.baseboard_fab2(sch_1):m_c_clk_dp(3)" )
			)
			( signal "M_C_CS_N<0>"
				( objectStatus "@baseboard_fab2_lib.baseboard_fab2(sch_1):m_c_cs_n(0)" )
			)
			( signal "M_C_CS_N<1>"
				( objectStatus "@baseboard_fab2_lib.baseboard_fab2(sch_1):m_c_cs_n(1)" )
			)
			( signal "M_C_CS_N<2>"
				( objectStatus "@baseboard_fab2_lib.baseboard_fab2(sch_1):m_c_cs_n(2)" )
			)
			( signal "M_C_CS_N<3>"
				( objectStatus "@baseboard_fab2_lib.baseboard_fab2(sch_1):m_c_cs_n(3)" )
			)
			( signal "M_C_CS_N<4>"
				( objectStatus "@baseboard_fab2_lib.baseboard_fab2(sch_1):m_c_cs_n(4)" )
			)
			( signal "M_C_CS_N<5>"
				( objectStatus "@baseboard_fab2_lib.baseboard_fab2(sch_1):m_c_cs_n(5)" )
			)
			( signal "M_C_CS_N<6>"
				( objectStatus "@baseboard_fab2_lib.baseboard_fab2(sch_1):m_c_cs_n(6)" )
			)
			( signal "M_C_CS_N<7>"
				( objectStatus "@baseboard_fab2_lib.baseboard_fab2(sch_1):m_c_cs_n(7)" )
			)
			( signal "M_C_DQ<0>"
				( objectStatus "@baseboard_fab2_lib.baseboard_fab2(sch_1):m_c_dq(0)" )
			)
			( signal "M_C_DQ<1>"
				( objectStatus "@baseboard_fab2_lib.baseboard_fab2(sch_1):m_c_dq(1)" )
			)
			( signal "M_C_DQ<2>"
				( objectStatus "@baseboard_fab2_lib.baseboard_fab2(sch_1):m_c_dq(2)" )
			)
			( signal "M_C_DQ<3>"
				( objectStatus "@baseboard_fab2_lib.baseboard_fab2(sch_1):m_c_dq(3)" )
			)
			( signal "M_C_DQ<4>"
				( objectStatus "@baseboard_fab2_lib.baseboard_fab2(sch_1):m_c_dq(4)" )
			)
			( signal "M_C_DQ<5>"
				( objectStatus "@baseboard_fab2_lib.baseboard_fab2(sch_1):m_c_dq(5)" )
			)
			( signal "M_C_DQ<6>"
				( objectStatus "@baseboard_fab2_lib.baseboard_fab2(sch_1):m_c_dq(6)" )
			)
			( signal "M_C_DQ<7>"
				( objectStatus "@baseboard_fab2_lib.baseboard_fab2(sch_1):m_c_dq(7)" )
			)
			( signal "M_C_DQ<8>"
				( objectStatus "@baseboard_fab2_lib.baseboard_fab2(sch_1):m_c_dq(8)" )
			)
			( signal "M_C_DQ<9>"
				( objectStatus "@baseboard_fab2_lib.baseboard_fab2(sch_1):m_c_dq(9)" )
			)
			( signal "M_C_DQ<10>"
				( objectStatus "@baseboard_fab2_lib.baseboard_fab2(sch_1):m_c_dq(10)" )
			)
			( signal "M_C_DQ<11>"
				( objectStatus "@baseboard_fab2_lib.baseboard_fab2(sch_1):m_c_dq(11)" )
			)
			( signal "M_C_DQ<12>"
				( objectStatus "@baseboard_fab2_lib.baseboard_fab2(sch_1):m_c_dq(12)" )
			)
			( signal "M_C_DQ<13>"
				( objectStatus "@baseboard_fab2_lib.baseboard_fab2(sch_1):m_c_dq(13)" )
			)
			( signal "M_C_DQ<14>"
				( objectStatus "@baseboard_fab2_lib.baseboard_fab2(sch_1):m_c_dq(14)" )
			)
			( signal "M_C_DQ<15>"
				( objectStatus "@baseboard_fab2_lib.baseboard_fab2(sch_1):m_c_dq(15)" )
			)
			( signal "M_C_DQ<16>"
				( objectStatus "@baseboard_fab2_lib.baseboard_fab2(sch_1):m_c_dq(16)" )
			)
			( signal "M_C_DQ<17>"
				( objectStatus "@baseboard_fab2_lib.baseboard_fab2(sch_1):m_c_dq(17)" )
			)
			( signal "M_C_DQ<18>"
				( objectStatus "@baseboard_fab2_lib.baseboard_fab2(sch_1):m_c_dq(18)" )
			)
			( signal "M_C_DQ<19>"
				( objectStatus "@baseboard_fab2_lib.baseboard_fab2(sch_1):m_c_dq(19)" )
			)
			( signal "M_C_DQ<20>"
				( objectStatus "@baseboard_fab2_lib.baseboard_fab2(sch_1):m_c_dq(20)" )
			)
			( signal "M_C_DQ<21>"
				( objectStatus "@baseboard_fab2_lib.baseboard_fab2(sch_1):m_c_dq(21)" )
			)
			( signal "M_C_DQ<22>"
				( objectStatus "@baseboard_fab2_lib.baseboard_fab2(sch_1):m_c_dq(22)" )
			)
			( signal "M_C_DQ<23>"
				( objectStatus "@baseboard_fab2_lib.baseboard_fab2(sch_1):m_c_dq(23)" )
			)
			( signal "M_C_DQ<24>"
				( objectStatus "@baseboard_fab2_lib.baseboard_fab2(sch_1):m_c_dq(24)" )
			)
			( signal "M_C_DQ<25>"
				( objectStatus "@baseboard_fab2_lib.baseboard_fab2(sch_1):m_c_dq(25)" )
			)
			( signal "M_C_DQ<26>"
				( objectStatus "@baseboard_fab2_lib.baseboard_fab2(sch_1):m_c_dq(26)" )
			)
			( signal "M_C_DQ<27>"
				( objectStatus "@baseboard_fab2_lib.baseboard_fab2(sch_1):m_c_dq(27)" )
			)
			( signal "M_C_DQ<28>"
				( objectStatus "@baseboard_fab2_lib.baseboard_fab2(sch_1):m_c_dq(28)" )
			)
			( signal "M_C_DQ<29>"
				( objectStatus "@baseboard_fab2_lib.baseboard_fab2(sch_1):m_c_dq(29)" )
			)
			( signal "M_C_DQ<30>"
				( objectStatus "@baseboard_fab2_lib.baseboard_fab2(sch_1):m_c_dq(30)" )
			)
			( signal "M_C_DQ<31>"
				( objectStatus "@baseboard_fab2_lib.baseboard_fab2(sch_1):m_c_dq(31)" )
			)
			( signal "M_C_DQ<32>"
				( objectStatus "@baseboard_fab2_lib.baseboard_fab2(sch_1):m_c_dq(32)" )
			)
			( signal "M_C_DQ<33>"
				( objectStatus "@baseboard_fab2_lib.baseboard_fab2(sch_1):m_c_dq(33)" )
			)
			( signal "M_C_DQ<34>"
				( objectStatus "@baseboard_fab2_lib.baseboard_fab2(sch_1):m_c_dq(34)" )
			)
			( signal "M_C_DQ<35>"
				( objectStatus "@baseboard_fab2_lib.baseboard_fab2(sch_1):m_c_dq(35)" )
			)
			( signal "M_C_DQ<36>"
				( objectStatus "@baseboard_fab2_lib.baseboard_fab2(sch_1):m_c_dq(36)" )
			)
			( signal "M_C_DQ<37>"
				( objectStatus "@baseboard_fab2_lib.baseboard_fab2(sch_1):m_c_dq(37)" )
			)
			( signal "M_C_DQ<38>"
				( objectStatus "@baseboard_fab2_lib.baseboard_fab2(sch_1):m_c_dq(38)" )
			)
			( signal "M_C_DQ<39>"
				( objectStatus "@baseboard_fab2_lib.baseboard_fab2(sch_1):m_c_dq(39)" )
			)
			( signal "M_C_DQ<40>"
				( objectStatus "@baseboard_fab2_lib.baseboard_fab2(sch_1):m_c_dq(40)" )
			)
			( signal "M_C_DQ<41>"
				( objectStatus "@baseboard_fab2_lib.baseboard_fab2(sch_1):m_c_dq(41)" )
			)
			( signal "M_C_DQ<42>"
				( objectStatus "@baseboard_fab2_lib.baseboard_fab2(sch_1):m_c_dq(42)" )
			)
			( signal "M_C_DQ<43>"
				( objectStatus "@baseboard_fab2_lib.baseboard_fab2(sch_1):m_c_dq(43)" )
			)
			( signal "M_C_DQ<44>"
				( objectStatus "@baseboard_fab2_lib.baseboard_fab2(sch_1):m_c_dq(44)" )
			)
			( signal "M_C_DQ<45>"
				( objectStatus "@baseboard_fab2_lib.baseboard_fab2(sch_1):m_c_dq(45)" )
			)
			( signal "M_C_DQ<46>"
				( objectStatus "@baseboard_fab2_lib.baseboard_fab2(sch_1):m_c_dq(46)" )
			)
			( signal "M_C_DQ<47>"
				( objectStatus "@baseboard_fab2_lib.baseboard_fab2(sch_1):m_c_dq(47)" )
			)
			( signal "M_C_DQ<48>"
				( objectStatus "@baseboard_fab2_lib.baseboard_fab2(sch_1):m_c_dq(48)" )
			)
			( signal "M_C_DQ<49>"
				( objectStatus "@baseboard_fab2_lib.baseboard_fab2(sch_1):m_c_dq(49)" )
			)
			( signal "M_C_DQ<50>"
				( objectStatus "@baseboard_fab2_lib.baseboard_fab2(sch_1):m_c_dq(50)" )
			)
			( signal "M_C_DQ<51>"
				( objectStatus "@baseboard_fab2_lib.baseboard_fab2(sch_1):m_c_dq(51)" )
			)
			( signal "M_C_DQ<52>"
				( objectStatus "@baseboard_fab2_lib.baseboard_fab2(sch_1):m_c_dq(52)" )
			)
			( signal "M_C_DQ<53>"
				( objectStatus "@baseboard_fab2_lib.baseboard_fab2(sch_1):m_c_dq(53)" )
			)
			( signal "M_C_DQ<54>"
				( objectStatus "@baseboard_fab2_lib.baseboard_fab2(sch_1):m_c_dq(54)" )
			)
			( signal "M_C_DQ<55>"
				( objectStatus "@baseboard_fab2_lib.baseboard_fab2(sch_1):m_c_dq(55)" )
			)
			( signal "M_C_DQ<56>"
				( objectStatus "@baseboard_fab2_lib.baseboard_fab2(sch_1):m_c_dq(56)" )
			)
			( signal "M_C_DQ<57>"
				( objectStatus "@baseboard_fab2_lib.baseboard_fab2(sch_1):m_c_dq(57)" )
			)
			( signal "M_C_DQ<58>"
				( objectStatus "@baseboard_fab2_lib.baseboard_fab2(sch_1):m_c_dq(58)" )
			)
			( signal "M_C_DQ<59>"
				( objectStatus "@baseboard_fab2_lib.baseboard_fab2(sch_1):m_c_dq(59)" )
			)
			( signal "M_C_DQ<60>"
				( objectStatus "@baseboard_fab2_lib.baseboard_fab2(sch_1):m_c_dq(60)" )
			)
			( signal "M_C_DQ<61>"
				( objectStatus "@baseboard_fab2_lib.baseboard_fab2(sch_1):m_c_dq(61)" )
			)
			( signal "M_C_DQ<62>"
				( objectStatus "@baseboard_fab2_lib.baseboard_fab2(sch_1):m_c_dq(62)" )
			)
			( signal "M_C_DQ<63>"
				( objectStatus "@baseboard_fab2_lib.baseboard_fab2(sch_1):m_c_dq(63)" )
			)
			( signal "M_C_DQS_DN<0>"
				( objectStatus "@baseboard_fab2_lib.baseboard_fab2(sch_1):m_c_dqs_dn(0)" )
			)
			( signal "M_C_DQS_DN<1>"
				( objectStatus "@baseboard_fab2_lib.baseboard_fab2(sch_1):m_c_dqs_dn(1)" )
			)
			( signal "M_C_DQS_DN<2>"
				( objectStatus "@baseboard_fab2_lib.baseboard_fab2(sch_1):m_c_dqs_dn(2)" )
			)
			( signal "M_C_DQS_DN<3>"
				( objectStatus "@baseboard_fab2_lib.baseboard_fab2(sch_1):m_c_dqs_dn(3)" )
			)
			( signal "M_C_DQS_DN<4>"
				( objectStatus "@baseboard_fab2_lib.baseboard_fab2(sch_1):m_c_dqs_dn(4)" )
			)
			( signal "M_C_DQS_DN<5>"
				( objectStatus "@baseboard_fab2_lib.baseboard_fab2(sch_1):m_c_dqs_dn(5)" )
			)
			( signal "M_C_DQS_DN<6>"
				( objectStatus "@baseboard_fab2_lib.baseboard_fab2(sch_1):m_c_dqs_dn(6)" )
			)
			( signal "M_C_DQS_DN<7>"
				( objectStatus "@baseboard_fab2_lib.baseboard_fab2(sch_1):m_c_dqs_dn(7)" )
			)
			( signal "M_C_DQS_DN<8>"
				( objectStatus "@baseboard_fab2_lib.baseboard_fab2(sch_1):m_c_dqs_dn(8)" )
			)
			( signal "M_C_DQS_DN<9>"
				( objectStatus "@baseboard_fab2_lib.baseboard_fab2(sch_1):m_c_dqs_dn(9)" )
			)
			( signal "M_C_DQS_DN<10>"
				( objectStatus "@baseboard_fab2_lib.baseboard_fab2(sch_1):m_c_dqs_dn(10)" )
			)
			( signal "M_C_DQS_DN<11>"
				( objectStatus "@baseboard_fab2_lib.baseboard_fab2(sch_1):m_c_dqs_dn(11)" )
			)
			( signal "M_C_DQS_DN<12>"
				( objectStatus "@baseboard_fab2_lib.baseboard_fab2(sch_1):m_c_dqs_dn(12)" )
			)
			( signal "M_C_DQS_DN<13>"
				( objectStatus "@baseboard_fab2_lib.baseboard_fab2(sch_1):m_c_dqs_dn(13)" )
			)
			( signal "M_C_DQS_DN<14>"
				( objectStatus "@baseboard_fab2_lib.baseboard_fab2(sch_1):m_c_dqs_dn(14)" )
			)
			( signal "M_C_DQS_DN<15>"
				( objectStatus "@baseboard_fab2_lib.baseboard_fab2(sch_1):m_c_dqs_dn(15)" )
			)
			( signal "M_C_DQS_DN<16>"
				( objectStatus "@baseboard_fab2_lib.baseboard_fab2(sch_1):m_c_dqs_dn(16)" )
			)
			( signal "M_C_DQS_DN<17>"
				( objectStatus "@baseboard_fab2_lib.baseboard_fab2(sch_1):m_c_dqs_dn(17)" )
			)
			( signal "M_C_DQS_DP<0>"
				( objectStatus "@baseboard_fab2_lib.baseboard_fab2(sch_1):m_c_dqs_dp(0)" )
			)
			( signal "M_C_DQS_DP<1>"
				( objectStatus "@baseboard_fab2_lib.baseboard_fab2(sch_1):m_c_dqs_dp(1)" )
			)
			( signal "M_C_DQS_DP<2>"
				( objectStatus "@baseboard_fab2_lib.baseboard_fab2(sch_1):m_c_dqs_dp(2)" )
			)
			( signal "M_C_DQS_DP<3>"
				( objectStatus "@baseboard_fab2_lib.baseboard_fab2(sch_1):m_c_dqs_dp(3)" )
			)
			( signal "M_C_DQS_DP<4>"
				( objectStatus "@baseboard_fab2_lib.baseboard_fab2(sch_1):m_c_dqs_dp(4)" )
			)
			( signal "M_C_DQS_DP<5>"
				( objectStatus "@baseboard_fab2_lib.baseboard_fab2(sch_1):m_c_dqs_dp(5)" )
			)
			( signal "M_C_DQS_DP<6>"
				( objectStatus "@baseboard_fab2_lib.baseboard_fab2(sch_1):m_c_dqs_dp(6)" )
			)
			( signal "M_C_DQS_DP<7>"
				( objectStatus "@baseboard_fab2_lib.baseboard_fab2(sch_1):m_c_dqs_dp(7)" )
			)
			( signal "M_C_DQS_DP<8>"
				( objectStatus "@baseboard_fab2_lib.baseboard_fab2(sch_1):m_c_dqs_dp(8)" )
			)
			( signal "M_C_DQS_DP<9>"
				( objectStatus "@baseboard_fab2_lib.baseboard_fab2(sch_1):m_c_dqs_dp(9)" )
			)
			( signal "M_C_DQS_DP<10>"
				( objectStatus "@baseboard_fab2_lib.baseboard_fab2(sch_1):m_c_dqs_dp(10)" )
			)
			( signal "M_C_DQS_DP<11>"
				( objectStatus "@baseboard_fab2_lib.baseboard_fab2(sch_1):m_c_dqs_dp(11)" )
			)
			( signal "M_C_DQS_DP<12>"
				( objectStatus "@baseboard_fab2_lib.baseboard_fab2(sch_1):m_c_dqs_dp(12)" )
			)
			( signal "M_C_DQS_DP<13>"
				( objectStatus "@baseboard_fab2_lib.baseboard_fab2(sch_1):m_c_dqs_dp(13)" )
			)
			( signal "M_C_DQS_DP<14>"
				( objectStatus "@baseboard_fab2_lib.baseboard_fab2(sch_1):m_c_dqs_dp(14)" )
			)
			( signal "M_C_DQS_DP<15>"
				( objectStatus "@baseboard_fab2_lib.baseboard_fab2(sch_1):m_c_dqs_dp(15)" )
			)
			( signal "M_C_DQS_DP<16>"
				( objectStatus "@baseboard_fab2_lib.baseboard_fab2(sch_1):m_c_dqs_dp(16)" )
			)
			( signal "M_C_DQS_DP<17>"
				( objectStatus "@baseboard_fab2_lib.baseboard_fab2(sch_1):m_c_dqs_dp(17)" )
			)
			( signal "M_C_ECC<0>"
				( objectStatus "@baseboard_fab2_lib.baseboard_fab2(sch_1):m_c_ecc(0)" )
			)
			( signal "M_C_ECC<1>"
				( objectStatus "@baseboard_fab2_lib.baseboard_fab2(sch_1):m_c_ecc(1)" )
			)
			( signal "M_C_ECC<2>"
				( objectStatus "@baseboard_fab2_lib.baseboard_fab2(sch_1):m_c_ecc(2)" )
			)
			( signal "M_C_ECC<3>"
				( objectStatus "@baseboard_fab2_lib.baseboard_fab2(sch_1):m_c_ecc(3)" )
			)
			( signal "M_C_ECC<4>"
				( objectStatus "@baseboard_fab2_lib.baseboard_fab2(sch_1):m_c_ecc(4)" )
			)
			( signal "M_C_ECC<5>"
				( objectStatus "@baseboard_fab2_lib.baseboard_fab2(sch_1):m_c_ecc(5)" )
			)
			( signal "M_C_ECC<6>"
				( objectStatus "@baseboard_fab2_lib.baseboard_fab2(sch_1):m_c_ecc(6)" )
			)
			( signal "M_C_ECC<7>"
				( objectStatus "@baseboard_fab2_lib.baseboard_fab2(sch_1):m_c_ecc(7)" )
			)
			( signal "M_C_MA<0>"
				( objectStatus "@baseboard_fab2_lib.baseboard_fab2(sch_1):m_c_ma(0)" )
			)
			( signal "M_C_MA<1>"
				( objectStatus "@baseboard_fab2_lib.baseboard_fab2(sch_1):m_c_ma(1)" )
			)
			( signal "M_C_MA<2>"
				( objectStatus "@baseboard_fab2_lib.baseboard_fab2(sch_1):m_c_ma(2)" )
			)
			( signal "M_C_MA<3>"
				( objectStatus "@baseboard_fab2_lib.baseboard_fab2(sch_1):m_c_ma(3)" )
			)
			( signal "M_C_MA<4>"
				( objectStatus "@baseboard_fab2_lib.baseboard_fab2(sch_1):m_c_ma(4)" )
			)
			( signal "M_C_MA<5>"
				( objectStatus "@baseboard_fab2_lib.baseboard_fab2(sch_1):m_c_ma(5)" )
			)
			( signal "M_C_MA<6>"
				( objectStatus "@baseboard_fab2_lib.baseboard_fab2(sch_1):m_c_ma(6)" )
			)
			( signal "M_C_MA<7>"
				( objectStatus "@baseboard_fab2_lib.baseboard_fab2(sch_1):m_c_ma(7)" )
			)
			( signal "M_C_MA<8>"
				( objectStatus "@baseboard_fab2_lib.baseboard_fab2(sch_1):m_c_ma(8)" )
			)
			( signal "M_C_MA<9>"
				( objectStatus "@baseboard_fab2_lib.baseboard_fab2(sch_1):m_c_ma(9)" )
			)
			( signal "M_C_MA<10>"
				( objectStatus "@baseboard_fab2_lib.baseboard_fab2(sch_1):m_c_ma(10)" )
			)
			( signal "M_C_MA<11>"
				( objectStatus "@baseboard_fab2_lib.baseboard_fab2(sch_1):m_c_ma(11)" )
			)
			( signal "M_C_MA<12>"
				( objectStatus "@baseboard_fab2_lib.baseboard_fab2(sch_1):m_c_ma(12)" )
			)
			( signal "M_C_MA<13>"
				( objectStatus "@baseboard_fab2_lib.baseboard_fab2(sch_1):m_c_ma(13)" )
			)
			( signal "M_C_MA<14>"
				( objectStatus "@baseboard_fab2_lib.baseboard_fab2(sch_1):m_c_ma(14)" )
			)
			( signal "M_C_MA<15>"
				( objectStatus "@baseboard_fab2_lib.baseboard_fab2(sch_1):m_c_ma(15)" )
			)
			( signal "M_C_MA<16>"
				( objectStatus "@baseboard_fab2_lib.baseboard_fab2(sch_1):m_c_ma(16)" )
			)
			( signal "M_C_MA<17>"
				( objectStatus "@baseboard_fab2_lib.baseboard_fab2(sch_1):m_c_ma(17)" )
			)
			( signal "M_C_ODT<0>"
				( objectStatus "@baseboard_fab2_lib.baseboard_fab2(sch_1):m_c_odt(0)" )
			)
			( signal "M_C_ODT<1>"
				( objectStatus "@baseboard_fab2_lib.baseboard_fab2(sch_1):m_c_odt(1)" )
			)
			( signal "M_C_ODT<2>"
				( objectStatus "@baseboard_fab2_lib.baseboard_fab2(sch_1):m_c_odt(2)" )
			)
			( signal "M_C_ODT<3>"
				( objectStatus "@baseboard_fab2_lib.baseboard_fab2(sch_1):m_c_odt(3)" )
			)
			( signal "M_C_PAR"
				( objectStatus "@baseboard_fab2_lib.baseboard_fab2(sch_1):m_c_par" )
			)
			( signal "M_D_ACT_N"
				( objectStatus "@baseboard_fab2_lib.baseboard_fab2(sch_1):m_d_act_n" )
			)
			( signal "M_D_ALERT_N"
				( objectStatus "@baseboard_fab2_lib.baseboard_fab2(sch_1):m_d_alert_n" )
			)
			( signal "M_D_BA<0>"
				( objectStatus "@baseboard_fab2_lib.baseboard_fab2(sch_1):m_d_ba(0)" )
			)
			( signal "M_D_BA<1>"
				( objectStatus "@baseboard_fab2_lib.baseboard_fab2(sch_1):m_d_ba(1)" )
			)
			( signal "M_D_BG<0>"
				( objectStatus "@baseboard_fab2_lib.baseboard_fab2(sch_1):m_d_bg(0)" )
			)
			( signal "M_D_BG<1>"
				( objectStatus "@baseboard_fab2_lib.baseboard_fab2(sch_1):m_d_bg(1)" )
			)
			( signal "M_D_C<2>"
				( objectStatus "@baseboard_fab2_lib.baseboard_fab2(sch_1):m_d_c(2)" )
			)
			( signal "M_D_CKE<0>"
				( objectStatus "@baseboard_fab2_lib.baseboard_fab2(sch_1):m_d_cke(0)" )
			)
			( signal "M_D_CKE<1>"
				( objectStatus "@baseboard_fab2_lib.baseboard_fab2(sch_1):m_d_cke(1)" )
			)
			( signal "M_D_CKE<2>"
				( objectStatus "@baseboard_fab2_lib.baseboard_fab2(sch_1):m_d_cke(2)" )
			)
			( signal "M_D_CKE<3>"
				( objectStatus "@baseboard_fab2_lib.baseboard_fab2(sch_1):m_d_cke(3)" )
			)
			( signal "M_D_CLK_DN<0>"
				( objectStatus "@baseboard_fab2_lib.baseboard_fab2(sch_1):m_d_clk_dn(0)" )
			)
			( signal "M_D_CLK_DN<1>"
				( objectStatus "@baseboard_fab2_lib.baseboard_fab2(sch_1):m_d_clk_dn(1)" )
			)
			( signal "M_D_CLK_DN<2>"
				( objectStatus "@baseboard_fab2_lib.baseboard_fab2(sch_1):m_d_clk_dn(2)" )
			)
			( signal "M_D_CLK_DN<3>"
				( objectStatus "@baseboard_fab2_lib.baseboard_fab2(sch_1):m_d_clk_dn(3)" )
			)
			( signal "M_D_CLK_DP<0>"
				( objectStatus "@baseboard_fab2_lib.baseboard_fab2(sch_1):m_d_clk_dp(0)" )
			)
			( signal "M_D_CLK_DP<1>"
				( objectStatus "@baseboard_fab2_lib.baseboard_fab2(sch_1):m_d_clk_dp(1)" )
			)
			( signal "M_D_CLK_DP<2>"
				( objectStatus "@baseboard_fab2_lib.baseboard_fab2(sch_1):m_d_clk_dp(2)" )
			)
			( signal "M_D_CLK_DP<3>"
				( objectStatus "@baseboard_fab2_lib.baseboard_fab2(sch_1):m_d_clk_dp(3)" )
			)
			( signal "M_D_CS_N<0>"
				( objectStatus "@baseboard_fab2_lib.baseboard_fab2(sch_1):m_d_cs_n(0)" )
			)
			( signal "M_D_CS_N<1>"
				( objectStatus "@baseboard_fab2_lib.baseboard_fab2(sch_1):m_d_cs_n(1)" )
			)
			( signal "M_D_CS_N<2>"
				( objectStatus "@baseboard_fab2_lib.baseboard_fab2(sch_1):m_d_cs_n(2)" )
			)
			( signal "M_D_CS_N<3>"
				( objectStatus "@baseboard_fab2_lib.baseboard_fab2(sch_1):m_d_cs_n(3)" )
			)
			( signal "M_D_CS_N<4>"
				( objectStatus "@baseboard_fab2_lib.baseboard_fab2(sch_1):m_d_cs_n(4)" )
			)
			( signal "M_D_CS_N<5>"
				( objectStatus "@baseboard_fab2_lib.baseboard_fab2(sch_1):m_d_cs_n(5)" )
			)
			( signal "M_D_CS_N<6>"
				( objectStatus "@baseboard_fab2_lib.baseboard_fab2(sch_1):m_d_cs_n(6)" )
			)
			( signal "M_D_CS_N<7>"
				( objectStatus "@baseboard_fab2_lib.baseboard_fab2(sch_1):m_d_cs_n(7)" )
			)
			( signal "M_D_DQ<0>"
				( objectStatus "@baseboard_fab2_lib.baseboard_fab2(sch_1):m_d_dq(0)" )
			)
			( signal "M_D_DQ<1>"
				( objectStatus "@baseboard_fab2_lib.baseboard_fab2(sch_1):m_d_dq(1)" )
			)
			( signal "M_D_DQ<2>"
				( objectStatus "@baseboard_fab2_lib.baseboard_fab2(sch_1):m_d_dq(2)" )
			)
			( signal "M_D_DQ<3>"
				( objectStatus "@baseboard_fab2_lib.baseboard_fab2(sch_1):m_d_dq(3)" )
			)
			( signal "M_D_DQ<4>"
				( objectStatus "@baseboard_fab2_lib.baseboard_fab2(sch_1):m_d_dq(4)" )
			)
			( signal "M_D_DQ<5>"
				( objectStatus "@baseboard_fab2_lib.baseboard_fab2(sch_1):m_d_dq(5)" )
			)
			( signal "M_D_DQ<6>"
				( objectStatus "@baseboard_fab2_lib.baseboard_fab2(sch_1):m_d_dq(6)" )
			)
			( signal "M_D_DQ<7>"
				( objectStatus "@baseboard_fab2_lib.baseboard_fab2(sch_1):m_d_dq(7)" )
			)
			( signal "M_D_DQ<8>"
				( objectStatus "@baseboard_fab2_lib.baseboard_fab2(sch_1):m_d_dq(8)" )
			)
			( signal "M_D_DQ<9>"
				( objectStatus "@baseboard_fab2_lib.baseboard_fab2(sch_1):m_d_dq(9)" )
			)
			( signal "M_D_DQ<10>"
				( objectStatus "@baseboard_fab2_lib.baseboard_fab2(sch_1):m_d_dq(10)" )
			)
			( signal "M_D_DQ<11>"
				( objectStatus "@baseboard_fab2_lib.baseboard_fab2(sch_1):m_d_dq(11)" )
			)
			( signal "M_D_DQ<12>"
				( objectStatus "@baseboard_fab2_lib.baseboard_fab2(sch_1):m_d_dq(12)" )
			)
			( signal "M_D_DQ<13>"
				( objectStatus "@baseboard_fab2_lib.baseboard_fab2(sch_1):m_d_dq(13)" )
			)
			( signal "M_D_DQ<14>"
				( objectStatus "@baseboard_fab2_lib.baseboard_fab2(sch_1):m_d_dq(14)" )
			)
			( signal "M_D_DQ<15>"
				( objectStatus "@baseboard_fab2_lib.baseboard_fab2(sch_1):m_d_dq(15)" )
			)
			( signal "M_D_DQ<16>"
				( objectStatus "@baseboard_fab2_lib.baseboard_fab2(sch_1):m_d_dq(16)" )
			)
			( signal "M_D_DQ<17>"
				( objectStatus "@baseboard_fab2_lib.baseboard_fab2(sch_1):m_d_dq(17)" )
			)
			( signal "M_D_DQ<18>"
				( objectStatus "@baseboard_fab2_lib.baseboard_fab2(sch_1):m_d_dq(18)" )
			)
			( signal "M_D_DQ<19>"
				( objectStatus "@baseboard_fab2_lib.baseboard_fab2(sch_1):m_d_dq(19)" )
			)
			( signal "M_D_DQ<20>"
				( objectStatus "@baseboard_fab2_lib.baseboard_fab2(sch_1):m_d_dq(20)" )
			)
			( signal "M_D_DQ<21>"
				( objectStatus "@baseboard_fab2_lib.baseboard_fab2(sch_1):m_d_dq(21)" )
			)
			( signal "M_D_DQ<22>"
				( objectStatus "@baseboard_fab2_lib.baseboard_fab2(sch_1):m_d_dq(22)" )
			)
			( signal "M_D_DQ<23>"
				( objectStatus "@baseboard_fab2_lib.baseboard_fab2(sch_1):m_d_dq(23)" )
			)
			( signal "M_D_DQ<24>"
				( objectStatus "@baseboard_fab2_lib.baseboard_fab2(sch_1):m_d_dq(24)" )
			)
			( signal "M_D_DQ<25>"
				( objectStatus "@baseboard_fab2_lib.baseboard_fab2(sch_1):m_d_dq(25)" )
			)
			( signal "M_D_DQ<26>"
				( objectStatus "@baseboard_fab2_lib.baseboard_fab2(sch_1):m_d_dq(26)" )
			)
			( signal "M_D_DQ<27>"
				( objectStatus "@baseboard_fab2_lib.baseboard_fab2(sch_1):m_d_dq(27)" )
			)
			( signal "M_D_DQ<28>"
				( objectStatus "@baseboard_fab2_lib.baseboard_fab2(sch_1):m_d_dq(28)" )
			)
			( signal "M_D_DQ<29>"
				( objectStatus "@baseboard_fab2_lib.baseboard_fab2(sch_1):m_d_dq(29)" )
			)
			( signal "M_D_DQ<30>"
				( objectStatus "@baseboard_fab2_lib.baseboard_fab2(sch_1):m_d_dq(30)" )
			)
			( signal "M_D_DQ<31>"
				( objectStatus "@baseboard_fab2_lib.baseboard_fab2(sch_1):m_d_dq(31)" )
			)
			( signal "M_D_DQ<32>"
				( objectStatus "@baseboard_fab2_lib.baseboard_fab2(sch_1):m_d_dq(32)" )
			)
			( signal "M_D_DQ<33>"
				( objectStatus "@baseboard_fab2_lib.baseboard_fab2(sch_1):m_d_dq(33)" )
			)
			( signal "M_D_DQ<34>"
				( objectStatus "@baseboard_fab2_lib.baseboard_fab2(sch_1):m_d_dq(34)" )
			)
			( signal "M_D_DQ<35>"
				( objectStatus "@baseboard_fab2_lib.baseboard_fab2(sch_1):m_d_dq(35)" )
			)
			( signal "M_D_DQ<36>"
				( objectStatus "@baseboard_fab2_lib.baseboard_fab2(sch_1):m_d_dq(36)" )
			)
			( signal "M_D_DQ<37>"
				( objectStatus "@baseboard_fab2_lib.baseboard_fab2(sch_1):m_d_dq(37)" )
			)
			( signal "M_D_DQ<38>"
				( objectStatus "@baseboard_fab2_lib.baseboard_fab2(sch_1):m_d_dq(38)" )
			)
			( signal "M_D_DQ<39>"
				( objectStatus "@baseboard_fab2_lib.baseboard_fab2(sch_1):m_d_dq(39)" )
			)
			( signal "M_D_DQ<40>"
				( objectStatus "@baseboard_fab2_lib.baseboard_fab2(sch_1):m_d_dq(40)" )
			)
			( signal "M_D_DQ<41>"
				( objectStatus "@baseboard_fab2_lib.baseboard_fab2(sch_1):m_d_dq(41)" )
			)
			( signal "M_D_DQ<42>"
				( objectStatus "@baseboard_fab2_lib.baseboard_fab2(sch_1):m_d_dq(42)" )
			)
			( signal "M_D_DQ<43>"
				( objectStatus "@baseboard_fab2_lib.baseboard_fab2(sch_1):m_d_dq(43)" )
			)
			( signal "M_D_DQ<44>"
				( objectStatus "@baseboard_fab2_lib.baseboard_fab2(sch_1):m_d_dq(44)" )
			)
			( signal "M_D_DQ<45>"
				( objectStatus "@baseboard_fab2_lib.baseboard_fab2(sch_1):m_d_dq(45)" )
			)
			( signal "M_D_DQ<46>"
				( objectStatus "@baseboard_fab2_lib.baseboard_fab2(sch_1):m_d_dq(46)" )
			)
			( signal "M_D_DQ<47>"
				( objectStatus "@baseboard_fab2_lib.baseboard_fab2(sch_1):m_d_dq(47)" )
			)
			( signal "M_D_DQ<48>"
				( objectStatus "@baseboard_fab2_lib.baseboard_fab2(sch_1):m_d_dq(48)" )
			)
			( signal "M_D_DQ<49>"
				( objectStatus "@baseboard_fab2_lib.baseboard_fab2(sch_1):m_d_dq(49)" )
			)
			( signal "M_D_DQ<50>"
				( objectStatus "@baseboard_fab2_lib.baseboard_fab2(sch_1):m_d_dq(50)" )
			)
			( signal "M_D_DQ<51>"
				( objectStatus "@baseboard_fab2_lib.baseboard_fab2(sch_1):m_d_dq(51)" )
			)
			( signal "M_D_DQ<52>"
				( objectStatus "@baseboard_fab2_lib.baseboard_fab2(sch_1):m_d_dq(52)" )
			)
			( signal "M_D_DQ<53>"
				( objectStatus "@baseboard_fab2_lib.baseboard_fab2(sch_1):m_d_dq(53)" )
			)
			( signal "M_D_DQ<54>"
				( objectStatus "@baseboard_fab2_lib.baseboard_fab2(sch_1):m_d_dq(54)" )
			)
			( signal "M_D_DQ<55>"
				( objectStatus "@baseboard_fab2_lib.baseboard_fab2(sch_1):m_d_dq(55)" )
			)
			( signal "M_D_DQ<56>"
				( objectStatus "@baseboard_fab2_lib.baseboard_fab2(sch_1):m_d_dq(56)" )
			)
			( signal "M_D_DQ<57>"
				( objectStatus "@baseboard_fab2_lib.baseboard_fab2(sch_1):m_d_dq(57)" )
			)
			( signal "M_D_DQ<58>"
				( objectStatus "@baseboard_fab2_lib.baseboard_fab2(sch_1):m_d_dq(58)" )
			)
			( signal "M_D_DQ<59>"
				( objectStatus "@baseboard_fab2_lib.baseboard_fab2(sch_1):m_d_dq(59)" )
			)
			( signal "M_D_DQ<60>"
				( objectStatus "@baseboard_fab2_lib.baseboard_fab2(sch_1):m_d_dq(60)" )
			)
			( signal "M_D_DQ<61>"
				( objectStatus "@baseboard_fab2_lib.baseboard_fab2(sch_1):m_d_dq(61)" )
			)
			( signal "M_D_DQ<62>"
				( objectStatus "@baseboard_fab2_lib.baseboard_fab2(sch_1):m_d_dq(62)" )
			)
			( signal "M_D_DQ<63>"
				( objectStatus "@baseboard_fab2_lib.baseboard_fab2(sch_1):m_d_dq(63)" )
			)
			( signal "M_D_DQS_DN<0>"
				( objectStatus "@baseboard_fab2_lib.baseboard_fab2(sch_1):m_d_dqs_dn(0)" )
			)
			( signal "M_D_DQS_DN<1>"
				( objectStatus "@baseboard_fab2_lib.baseboard_fab2(sch_1):m_d_dqs_dn(1)" )
			)
			( signal "M_D_DQS_DN<2>"
				( objectStatus "@baseboard_fab2_lib.baseboard_fab2(sch_1):m_d_dqs_dn(2)" )
			)
			( signal "M_D_DQS_DN<3>"
				( objectStatus "@baseboard_fab2_lib.baseboard_fab2(sch_1):m_d_dqs_dn(3)" )
			)
			( signal "M_D_DQS_DN<4>"
				( objectStatus "@baseboard_fab2_lib.baseboard_fab2(sch_1):m_d_dqs_dn(4)" )
			)
			( signal "M_D_DQS_DN<5>"
				( objectStatus "@baseboard_fab2_lib.baseboard_fab2(sch_1):m_d_dqs_dn(5)" )
			)
			( signal "M_D_DQS_DN<6>"
				( objectStatus "@baseboard_fab2_lib.baseboard_fab2(sch_1):m_d_dqs_dn(6)" )
			)
			( signal "M_D_DQS_DN<7>"
				( objectStatus "@baseboard_fab2_lib.baseboard_fab2(sch_1):m_d_dqs_dn(7)" )
			)
			( signal "M_D_DQS_DN<8>"
				( objectStatus "@baseboard_fab2_lib.baseboard_fab2(sch_1):m_d_dqs_dn(8)" )
			)
			( signal "M_D_DQS_DN<9>"
				( objectStatus "@baseboard_fab2_lib.baseboard_fab2(sch_1):m_d_dqs_dn(9)" )
			)
			( signal "M_D_DQS_DN<10>"
				( objectStatus "@baseboard_fab2_lib.baseboard_fab2(sch_1):m_d_dqs_dn(10)" )
			)
			( signal "M_D_DQS_DN<11>"
				( objectStatus "@baseboard_fab2_lib.baseboard_fab2(sch_1):m_d_dqs_dn(11)" )
			)
			( signal "M_D_DQS_DN<12>"
				( objectStatus "@baseboard_fab2_lib.baseboard_fab2(sch_1):m_d_dqs_dn(12)" )
			)
			( signal "M_D_DQS_DN<13>"
				( objectStatus "@baseboard_fab2_lib.baseboard_fab2(sch_1):m_d_dqs_dn(13)" )
			)
			( signal "M_D_DQS_DN<14>"
				( objectStatus "@baseboard_fab2_lib.baseboard_fab2(sch_1):m_d_dqs_dn(14)" )
			)
			( signal "M_D_DQS_DN<15>"
				( objectStatus "@baseboard_fab2_lib.baseboard_fab2(sch_1):m_d_dqs_dn(15)" )
			)
			( signal "M_D_DQS_DN<16>"
				( objectStatus "@baseboard_fab2_lib.baseboard_fab2(sch_1):m_d_dqs_dn(16)" )
			)
			( signal "M_D_DQS_DN<17>"
				( objectStatus "@baseboard_fab2_lib.baseboard_fab2(sch_1):m_d_dqs_dn(17)" )
			)
			( signal "M_D_DQS_DP<0>"
				( objectStatus "@baseboard_fab2_lib.baseboard_fab2(sch_1):m_d_dqs_dp(0)" )
			)
			( signal "M_D_DQS_DP<1>"
				( objectStatus "@baseboard_fab2_lib.baseboard_fab2(sch_1):m_d_dqs_dp(1)" )
			)
			( signal "M_D_DQS_DP<2>"
				( objectStatus "@baseboard_fab2_lib.baseboard_fab2(sch_1):m_d_dqs_dp(2)" )
			)
			( signal "M_D_DQS_DP<3>"
				( objectStatus "@baseboard_fab2_lib.baseboard_fab2(sch_1):m_d_dqs_dp(3)" )
			)
			( signal "M_D_DQS_DP<4>"
				( objectStatus "@baseboard_fab2_lib.baseboard_fab2(sch_1):m_d_dqs_dp(4)" )
			)
			( signal "M_D_DQS_DP<5>"
				( objectStatus "@baseboard_fab2_lib.baseboard_fab2(sch_1):m_d_dqs_dp(5)" )
			)
			( signal "M_D_DQS_DP<6>"
				( objectStatus "@baseboard_fab2_lib.baseboard_fab2(sch_1):m_d_dqs_dp(6)" )
			)
			( signal "M_D_DQS_DP<7>"
				( objectStatus "@baseboard_fab2_lib.baseboard_fab2(sch_1):m_d_dqs_dp(7)" )
			)
			( signal "M_D_DQS_DP<8>"
				( objectStatus "@baseboard_fab2_lib.baseboard_fab2(sch_1):m_d_dqs_dp(8)" )
			)
			( signal "M_D_DQS_DP<9>"
				( objectStatus "@baseboard_fab2_lib.baseboard_fab2(sch_1):m_d_dqs_dp(9)" )
			)
			( signal "M_D_DQS_DP<10>"
				( objectStatus "@baseboard_fab2_lib.baseboard_fab2(sch_1):m_d_dqs_dp(10)" )
			)
			( signal "M_D_DQS_DP<11>"
				( objectStatus "@baseboard_fab2_lib.baseboard_fab2(sch_1):m_d_dqs_dp(11)" )
			)
			( signal "M_D_DQS_DP<12>"
				( objectStatus "@baseboard_fab2_lib.baseboard_fab2(sch_1):m_d_dqs_dp(12)" )
			)
			( signal "M_D_DQS_DP<13>"
				( objectStatus "@baseboard_fab2_lib.baseboard_fab2(sch_1):m_d_dqs_dp(13)" )
			)
			( signal "M_D_DQS_DP<14>"
				( objectStatus "@baseboard_fab2_lib.baseboard_fab2(sch_1):m_d_dqs_dp(14)" )
			)
			( signal "M_D_DQS_DP<15>"
				( objectStatus "@baseboard_fab2_lib.baseboard_fab2(sch_1):m_d_dqs_dp(15)" )
			)
			( signal "M_D_DQS_DP<16>"
				( objectStatus "@baseboard_fab2_lib.baseboard_fab2(sch_1):m_d_dqs_dp(16)" )
			)
			( signal "M_D_DQS_DP<17>"
				( objectStatus "@baseboard_fab2_lib.baseboard_fab2(sch_1):m_d_dqs_dp(17)" )
			)
			( signal "M_D_ECC<0>"
				( objectStatus "@baseboard_fab2_lib.baseboard_fab2(sch_1):m_d_ecc(0)" )
			)
			( signal "M_D_ECC<1>"
				( objectStatus "@baseboard_fab2_lib.baseboard_fab2(sch_1):m_d_ecc(1)" )
			)
			( signal "M_D_ECC<2>"
				( objectStatus "@baseboard_fab2_lib.baseboard_fab2(sch_1):m_d_ecc(2)" )
			)
			( signal "M_D_ECC<3>"
				( objectStatus "@baseboard_fab2_lib.baseboard_fab2(sch_1):m_d_ecc(3)" )
			)
			( signal "M_D_ECC<4>"
				( objectStatus "@baseboard_fab2_lib.baseboard_fab2(sch_1):m_d_ecc(4)" )
			)
			( signal "M_D_ECC<5>"
				( objectStatus "@baseboard_fab2_lib.baseboard_fab2(sch_1):m_d_ecc(5)" )
			)
			( signal "M_D_ECC<6>"
				( objectStatus "@baseboard_fab2_lib.baseboard_fab2(sch_1):m_d_ecc(6)" )
			)
			( signal "M_D_ECC<7>"
				( objectStatus "@baseboard_fab2_lib.baseboard_fab2(sch_1):m_d_ecc(7)" )
			)
			( signal "M_D_MA<0>"
				( objectStatus "@baseboard_fab2_lib.baseboard_fab2(sch_1):m_d_ma(0)" )
			)
			( signal "M_D_MA<1>"
				( objectStatus "@baseboard_fab2_lib.baseboard_fab2(sch_1):m_d_ma(1)" )
			)
			( signal "M_D_MA<2>"
				( objectStatus "@baseboard_fab2_lib.baseboard_fab2(sch_1):m_d_ma(2)" )
			)
			( signal "M_D_MA<3>"
				( objectStatus "@baseboard_fab2_lib.baseboard_fab2(sch_1):m_d_ma(3)" )
			)
			( signal "M_D_MA<4>"
				( objectStatus "@baseboard_fab2_lib.baseboard_fab2(sch_1):m_d_ma(4)" )
			)
			( signal "M_D_MA<5>"
				( objectStatus "@baseboard_fab2_lib.baseboard_fab2(sch_1):m_d_ma(5)" )
			)
			( signal "M_D_MA<6>"
				( objectStatus "@baseboard_fab2_lib.baseboard_fab2(sch_1):m_d_ma(6)" )
			)
			( signal "M_D_MA<7>"
				( objectStatus "@baseboard_fab2_lib.baseboard_fab2(sch_1):m_d_ma(7)" )
			)
			( signal "M_D_MA<8>"
				( objectStatus "@baseboard_fab2_lib.baseboard_fab2(sch_1):m_d_ma(8)" )
			)
			( signal "M_D_MA<9>"
				( objectStatus "@baseboard_fab2_lib.baseboard_fab2(sch_1):m_d_ma(9)" )
			)
			( signal "M_D_MA<10>"
				( objectStatus "@baseboard_fab2_lib.baseboard_fab2(sch_1):m_d_ma(10)" )
			)
			( signal "M_D_MA<11>"
				( objectStatus "@baseboard_fab2_lib.baseboard_fab2(sch_1):m_d_ma(11)" )
			)
			( signal "M_D_MA<12>"
				( objectStatus "@baseboard_fab2_lib.baseboard_fab2(sch_1):m_d_ma(12)" )
			)
			( signal "M_D_MA<13>"
				( objectStatus "@baseboard_fab2_lib.baseboard_fab2(sch_1):m_d_ma(13)" )
			)
			( signal "M_D_MA<14>"
				( objectStatus "@baseboard_fab2_lib.baseboard_fab2(sch_1):m_d_ma(14)" )
			)
			( signal "M_D_MA<15>"
				( objectStatus "@baseboard_fab2_lib.baseboard_fab2(sch_1):m_d_ma(15)" )
			)
			( signal "M_D_MA<16>"
				( objectStatus "@baseboard_fab2_lib.baseboard_fab2(sch_1):m_d_ma(16)" )
			)
			( signal "M_D_MA<17>"
				( objectStatus "@baseboard_fab2_lib.baseboard_fab2(sch_1):m_d_ma(17)" )
			)
			( signal "M_D_ODT<0>"
				( objectStatus "@baseboard_fab2_lib.baseboard_fab2(sch_1):m_d_odt(0)" )
			)
			( signal "M_D_ODT<1>"
				( objectStatus "@baseboard_fab2_lib.baseboard_fab2(sch_1):m_d_odt(1)" )
			)
			( signal "M_D_ODT<2>"
				( objectStatus "@baseboard_fab2_lib.baseboard_fab2(sch_1):m_d_odt(2)" )
			)
			( signal "M_D_ODT<3>"
				( objectStatus "@baseboard_fab2_lib.baseboard_fab2(sch_1):m_d_odt(3)" )
			)
			( signal "M_D_PAR"
				( objectStatus "@baseboard_fab2_lib.baseboard_fab2(sch_1):m_d_par" )
			)
			( signal "M_E_ACT_N"
				( objectStatus "@baseboard_fab2_lib.baseboard_fab2(sch_1):m_e_act_n" )
			)
			( signal "M_E_ALERT_N"
				( objectStatus "@baseboard_fab2_lib.baseboard_fab2(sch_1):m_e_alert_n" )
			)
			( signal "M_E_BA<0>"
				( objectStatus "@baseboard_fab2_lib.baseboard_fab2(sch_1):m_e_ba(0)" )
			)
			( signal "M_E_BA<1>"
				( objectStatus "@baseboard_fab2_lib.baseboard_fab2(sch_1):m_e_ba(1)" )
			)
			( signal "M_E_BG<0>"
				( objectStatus "@baseboard_fab2_lib.baseboard_fab2(sch_1):m_e_bg(0)" )
			)
			( signal "M_E_BG<1>"
				( objectStatus "@baseboard_fab2_lib.baseboard_fab2(sch_1):m_e_bg(1)" )
			)
			( signal "M_E_C<2>"
				( objectStatus "@baseboard_fab2_lib.baseboard_fab2(sch_1):m_e_c(2)" )
			)
			( signal "M_E_CKE<0>"
				( objectStatus "@baseboard_fab2_lib.baseboard_fab2(sch_1):m_e_cke(0)" )
			)
			( signal "M_E_CKE<1>"
				( objectStatus "@baseboard_fab2_lib.baseboard_fab2(sch_1):m_e_cke(1)" )
			)
			( signal "M_E_CKE<2>"
				( objectStatus "@baseboard_fab2_lib.baseboard_fab2(sch_1):m_e_cke(2)" )
			)
			( signal "M_E_CKE<3>"
				( objectStatus "@baseboard_fab2_lib.baseboard_fab2(sch_1):m_e_cke(3)" )
			)
			( signal "M_E_CLK_DN<0>"
				( objectStatus "@baseboard_fab2_lib.baseboard_fab2(sch_1):m_e_clk_dn(0)" )
			)
			( signal "M_E_CLK_DN<1>"
				( objectStatus "@baseboard_fab2_lib.baseboard_fab2(sch_1):m_e_clk_dn(1)" )
			)
			( signal "M_E_CLK_DN<2>"
				( objectStatus "@baseboard_fab2_lib.baseboard_fab2(sch_1):m_e_clk_dn(2)" )
			)
			( signal "M_E_CLK_DN<3>"
				( objectStatus "@baseboard_fab2_lib.baseboard_fab2(sch_1):m_e_clk_dn(3)" )
			)
			( signal "M_E_CLK_DP<0>"
				( objectStatus "@baseboard_fab2_lib.baseboard_fab2(sch_1):m_e_clk_dp(0)" )
			)
			( signal "M_E_CLK_DP<1>"
				( objectStatus "@baseboard_fab2_lib.baseboard_fab2(sch_1):m_e_clk_dp(1)" )
			)
			( signal "M_E_CLK_DP<2>"
				( objectStatus "@baseboard_fab2_lib.baseboard_fab2(sch_1):m_e_clk_dp(2)" )
			)
			( signal "M_E_CLK_DP<3>"
				( objectStatus "@baseboard_fab2_lib.baseboard_fab2(sch_1):m_e_clk_dp(3)" )
			)
			( signal "M_E_CS_N<0>"
				( objectStatus "@baseboard_fab2_lib.baseboard_fab2(sch_1):m_e_cs_n(0)" )
			)
			( signal "M_E_CS_N<1>"
				( objectStatus "@baseboard_fab2_lib.baseboard_fab2(sch_1):m_e_cs_n(1)" )
			)
			( signal "M_E_CS_N<2>"
				( objectStatus "@baseboard_fab2_lib.baseboard_fab2(sch_1):m_e_cs_n(2)" )
			)
			( signal "M_E_CS_N<3>"
				( objectStatus "@baseboard_fab2_lib.baseboard_fab2(sch_1):m_e_cs_n(3)" )
			)
			( signal "M_E_CS_N<4>"
				( objectStatus "@baseboard_fab2_lib.baseboard_fab2(sch_1):m_e_cs_n(4)" )
			)
			( signal "M_E_CS_N<5>"
				( objectStatus "@baseboard_fab2_lib.baseboard_fab2(sch_1):m_e_cs_n(5)" )
			)
			( signal "M_E_CS_N<6>"
				( objectStatus "@baseboard_fab2_lib.baseboard_fab2(sch_1):m_e_cs_n(6)" )
			)
			( signal "M_E_CS_N<7>"
				( objectStatus "@baseboard_fab2_lib.baseboard_fab2(sch_1):m_e_cs_n(7)" )
			)
			( signal "M_E_DQ<0>"
				( objectStatus "@baseboard_fab2_lib.baseboard_fab2(sch_1):m_e_dq(0)" )
			)
			( signal "M_E_DQ<1>"
				( objectStatus "@baseboard_fab2_lib.baseboard_fab2(sch_1):m_e_dq(1)" )
			)
			( signal "M_E_DQ<2>"
				( objectStatus "@baseboard_fab2_lib.baseboard_fab2(sch_1):m_e_dq(2)" )
			)
			( signal "M_E_DQ<3>"
				( objectStatus "@baseboard_fab2_lib.baseboard_fab2(sch_1):m_e_dq(3)" )
			)
			( signal "M_E_DQ<4>"
				( objectStatus "@baseboard_fab2_lib.baseboard_fab2(sch_1):m_e_dq(4)" )
			)
			( signal "M_E_DQ<5>"
				( objectStatus "@baseboard_fab2_lib.baseboard_fab2(sch_1):m_e_dq(5)" )
			)
			( signal "M_E_DQ<6>"
				( objectStatus "@baseboard_fab2_lib.baseboard_fab2(sch_1):m_e_dq(6)" )
			)
			( signal "M_E_DQ<7>"
				( objectStatus "@baseboard_fab2_lib.baseboard_fab2(sch_1):m_e_dq(7)" )
			)
			( signal "M_E_DQ<8>"
				( objectStatus "@baseboard_fab2_lib.baseboard_fab2(sch_1):m_e_dq(8)" )
			)
			( signal "M_E_DQ<9>"
				( objectStatus "@baseboard_fab2_lib.baseboard_fab2(sch_1):m_e_dq(9)" )
			)
			( signal "M_E_DQ<10>"
				( objectStatus "@baseboard_fab2_lib.baseboard_fab2(sch_1):m_e_dq(10)" )
			)
			( signal "M_E_DQ<11>"
				( objectStatus "@baseboard_fab2_lib.baseboard_fab2(sch_1):m_e_dq(11)" )
			)
			( signal "M_E_DQ<12>"
				( objectStatus "@baseboard_fab2_lib.baseboard_fab2(sch_1):m_e_dq(12)" )
			)
			( signal "M_E_DQ<13>"
				( objectStatus "@baseboard_fab2_lib.baseboard_fab2(sch_1):m_e_dq(13)" )
			)
			( signal "M_E_DQ<14>"
				( objectStatus "@baseboard_fab2_lib.baseboard_fab2(sch_1):m_e_dq(14)" )
			)
			( signal "M_E_DQ<15>"
				( objectStatus "@baseboard_fab2_lib.baseboard_fab2(sch_1):m_e_dq(15)" )
			)
			( signal "M_E_DQ<16>"
				( objectStatus "@baseboard_fab2_lib.baseboard_fab2(sch_1):m_e_dq(16)" )
			)
			( signal "M_E_DQ<17>"
				( objectStatus "@baseboard_fab2_lib.baseboard_fab2(sch_1):m_e_dq(17)" )
			)
			( signal "M_E_DQ<18>"
				( objectStatus "@baseboard_fab2_lib.baseboard_fab2(sch_1):m_e_dq(18)" )
			)
			( signal "M_E_DQ<19>"
				( objectStatus "@baseboard_fab2_lib.baseboard_fab2(sch_1):m_e_dq(19)" )
			)
			( signal "M_E_DQ<20>"
				( objectStatus "@baseboard_fab2_lib.baseboard_fab2(sch_1):m_e_dq(20)" )
			)
			( signal "M_E_DQ<21>"
				( objectStatus "@baseboard_fab2_lib.baseboard_fab2(sch_1):m_e_dq(21)" )
			)
			( signal "M_E_DQ<22>"
				( objectStatus "@baseboard_fab2_lib.baseboard_fab2(sch_1):m_e_dq(22)" )
			)
			( signal "M_E_DQ<23>"
				( objectStatus "@baseboard_fab2_lib.baseboard_fab2(sch_1):m_e_dq(23)" )
			)
			( signal "M_E_DQ<24>"
				( objectStatus "@baseboard_fab2_lib.baseboard_fab2(sch_1):m_e_dq(24)" )
			)
			( signal "M_E_DQ<25>"
				( objectStatus "@baseboard_fab2_lib.baseboard_fab2(sch_1):m_e_dq(25)" )
			)
			( signal "M_E_DQ<26>"
				( objectStatus "@baseboard_fab2_lib.baseboard_fab2(sch_1):m_e_dq(26)" )
			)
			( signal "M_E_DQ<27>"
				( objectStatus "@baseboard_fab2_lib.baseboard_fab2(sch_1):m_e_dq(27)" )
			)
			( signal "M_E_DQ<28>"
				( objectStatus "@baseboard_fab2_lib.baseboard_fab2(sch_1):m_e_dq(28)" )
			)
			( signal "M_E_DQ<29>"
				( objectStatus "@baseboard_fab2_lib.baseboard_fab2(sch_1):m_e_dq(29)" )
			)
			( signal "M_E_DQ<30>"
				( objectStatus "@baseboard_fab2_lib.baseboard_fab2(sch_1):m_e_dq(30)" )
			)
			( signal "M_E_DQ<31>"
				( objectStatus "@baseboard_fab2_lib.baseboard_fab2(sch_1):m_e_dq(31)" )
			)
			( signal "M_E_DQ<32>"
				( objectStatus "@baseboard_fab2_lib.baseboard_fab2(sch_1):m_e_dq(32)" )
			)
			( signal "M_E_DQ<33>"
				( objectStatus "@baseboard_fab2_lib.baseboard_fab2(sch_1):m_e_dq(33)" )
			)
			( signal "M_E_DQ<34>"
				( objectStatus "@baseboard_fab2_lib.baseboard_fab2(sch_1):m_e_dq(34)" )
			)
			( signal "M_E_DQ<35>"
				( objectStatus "@baseboard_fab2_lib.baseboard_fab2(sch_1):m_e_dq(35)" )
			)
			( signal "M_E_DQ<36>"
				( objectStatus "@baseboard_fab2_lib.baseboard_fab2(sch_1):m_e_dq(36)" )
			)
			( signal "M_E_DQ<37>"
				( objectStatus "@baseboard_fab2_lib.baseboard_fab2(sch_1):m_e_dq(37)" )
			)
			( signal "M_E_DQ<38>"
				( objectStatus "@baseboard_fab2_lib.baseboard_fab2(sch_1):m_e_dq(38)" )
			)
			( signal "M_E_DQ<39>"
				( objectStatus "@baseboard_fab2_lib.baseboard_fab2(sch_1):m_e_dq(39)" )
			)
			( signal "M_E_DQ<40>"
				( objectStatus "@baseboard_fab2_lib.baseboard_fab2(sch_1):m_e_dq(40)" )
			)
			( signal "M_E_DQ<41>"
				( objectStatus "@baseboard_fab2_lib.baseboard_fab2(sch_1):m_e_dq(41)" )
			)
			( signal "M_E_DQ<42>"
				( objectStatus "@baseboard_fab2_lib.baseboard_fab2(sch_1):m_e_dq(42)" )
			)
			( signal "M_E_DQ<43>"
				( objectStatus "@baseboard_fab2_lib.baseboard_fab2(sch_1):m_e_dq(43)" )
			)
			( signal "M_E_DQ<44>"
				( objectStatus "@baseboard_fab2_lib.baseboard_fab2(sch_1):m_e_dq(44)" )
			)
			( signal "M_E_DQ<45>"
				( objectStatus "@baseboard_fab2_lib.baseboard_fab2(sch_1):m_e_dq(45)" )
			)
			( signal "M_E_DQ<46>"
				( objectStatus "@baseboard_fab2_lib.baseboard_fab2(sch_1):m_e_dq(46)" )
			)
			( signal "M_E_DQ<47>"
				( objectStatus "@baseboard_fab2_lib.baseboard_fab2(sch_1):m_e_dq(47)" )
			)
			( signal "M_E_DQ<48>"
				( objectStatus "@baseboard_fab2_lib.baseboard_fab2(sch_1):m_e_dq(48)" )
			)
			( signal "M_E_DQ<49>"
				( objectStatus "@baseboard_fab2_lib.baseboard_fab2(sch_1):m_e_dq(49)" )
			)
			( signal "M_E_DQ<50>"
				( objectStatus "@baseboard_fab2_lib.baseboard_fab2(sch_1):m_e_dq(50)" )
			)
			( signal "M_E_DQ<51>"
				( objectStatus "@baseboard_fab2_lib.baseboard_fab2(sch_1):m_e_dq(51)" )
			)
			( signal "M_E_DQ<52>"
				( objectStatus "@baseboard_fab2_lib.baseboard_fab2(sch_1):m_e_dq(52)" )
			)
			( signal "M_E_DQ<53>"
				( objectStatus "@baseboard_fab2_lib.baseboard_fab2(sch_1):m_e_dq(53)" )
			)
			( signal "M_E_DQ<54>"
				( objectStatus "@baseboard_fab2_lib.baseboard_fab2(sch_1):m_e_dq(54)" )
			)
			( signal "M_E_DQ<55>"
				( objectStatus "@baseboard_fab2_lib.baseboard_fab2(sch_1):m_e_dq(55)" )
			)
			( signal "M_E_DQ<56>"
				( objectStatus "@baseboard_fab2_lib.baseboard_fab2(sch_1):m_e_dq(56)" )
			)
			( signal "M_E_DQ<57>"
				( objectStatus "@baseboard_fab2_lib.baseboard_fab2(sch_1):m_e_dq(57)" )
			)
			( signal "M_E_DQ<58>"
				( objectStatus "@baseboard_fab2_lib.baseboard_fab2(sch_1):m_e_dq(58)" )
			)
			( signal "M_E_DQ<59>"
				( objectStatus "@baseboard_fab2_lib.baseboard_fab2(sch_1):m_e_dq(59)" )
			)
			( signal "M_E_DQ<60>"
				( objectStatus "@baseboard_fab2_lib.baseboard_fab2(sch_1):m_e_dq(60)" )
			)
			( signal "M_E_DQ<61>"
				( objectStatus "@baseboard_fab2_lib.baseboard_fab2(sch_1):m_e_dq(61)" )
			)
			( signal "M_E_DQ<62>"
				( objectStatus "@baseboard_fab2_lib.baseboard_fab2(sch_1):m_e_dq(62)" )
			)
			( signal "M_E_DQ<63>"
				( objectStatus "@baseboard_fab2_lib.baseboard_fab2(sch_1):m_e_dq(63)" )
			)
			( signal "M_E_DQS_DN<0>"
				( objectStatus "@baseboard_fab2_lib.baseboard_fab2(sch_1):m_e_dqs_dn(0)" )
			)
			( signal "M_E_DQS_DN<1>"
				( objectStatus "@baseboard_fab2_lib.baseboard_fab2(sch_1):m_e_dqs_dn(1)" )
			)
			( signal "M_E_DQS_DN<2>"
				( objectStatus "@baseboard_fab2_lib.baseboard_fab2(sch_1):m_e_dqs_dn(2)" )
			)
			( signal "M_E_DQS_DN<3>"
				( objectStatus "@baseboard_fab2_lib.baseboard_fab2(sch_1):m_e_dqs_dn(3)" )
			)
			( signal "M_E_DQS_DN<4>"
				( objectStatus "@baseboard_fab2_lib.baseboard_fab2(sch_1):m_e_dqs_dn(4)" )
			)
			( signal "M_E_DQS_DN<5>"
				( objectStatus "@baseboard_fab2_lib.baseboard_fab2(sch_1):m_e_dqs_dn(5)" )
			)
			( signal "M_E_DQS_DN<6>"
				( objectStatus "@baseboard_fab2_lib.baseboard_fab2(sch_1):m_e_dqs_dn(6)" )
			)
			( signal "M_E_DQS_DN<7>"
				( objectStatus "@baseboard_fab2_lib.baseboard_fab2(sch_1):m_e_dqs_dn(7)" )
			)
			( signal "M_E_DQS_DN<8>"
				( objectStatus "@baseboard_fab2_lib.baseboard_fab2(sch_1):m_e_dqs_dn(8)" )
			)
			( signal "M_E_DQS_DN<9>"
				( objectStatus "@baseboard_fab2_lib.baseboard_fab2(sch_1):m_e_dqs_dn(9)" )
			)
			( signal "M_E_DQS_DN<10>"
				( objectStatus "@baseboard_fab2_lib.baseboard_fab2(sch_1):m_e_dqs_dn(10)" )
			)
			( signal "M_E_DQS_DN<11>"
				( objectStatus "@baseboard_fab2_lib.baseboard_fab2(sch_1):m_e_dqs_dn(11)" )
			)
			( signal "M_E_DQS_DN<12>"
				( objectStatus "@baseboard_fab2_lib.baseboard_fab2(sch_1):m_e_dqs_dn(12)" )
			)
			( signal "M_E_DQS_DN<13>"
				( objectStatus "@baseboard_fab2_lib.baseboard_fab2(sch_1):m_e_dqs_dn(13)" )
			)
			( signal "M_E_DQS_DN<14>"
				( objectStatus "@baseboard_fab2_lib.baseboard_fab2(sch_1):m_e_dqs_dn(14)" )
			)
			( signal "M_E_DQS_DN<15>"
				( objectStatus "@baseboard_fab2_lib.baseboard_fab2(sch_1):m_e_dqs_dn(15)" )
			)
			( signal "M_E_DQS_DN<16>"
				( objectStatus "@baseboard_fab2_lib.baseboard_fab2(sch_1):m_e_dqs_dn(16)" )
			)
			( signal "M_E_DQS_DN<17>"
				( objectStatus "@baseboard_fab2_lib.baseboard_fab2(sch_1):m_e_dqs_dn(17)" )
			)
			( signal "M_E_DQS_DP<0>"
				( objectStatus "@baseboard_fab2_lib.baseboard_fab2(sch_1):m_e_dqs_dp(0)" )
			)
			( signal "M_E_DQS_DP<1>"
				( objectStatus "@baseboard_fab2_lib.baseboard_fab2(sch_1):m_e_dqs_dp(1)" )
			)
			( signal "M_E_DQS_DP<2>"
				( objectStatus "@baseboard_fab2_lib.baseboard_fab2(sch_1):m_e_dqs_dp(2)" )
			)
			( signal "M_E_DQS_DP<3>"
				( objectStatus "@baseboard_fab2_lib.baseboard_fab2(sch_1):m_e_dqs_dp(3)" )
			)
			( signal "M_E_DQS_DP<4>"
				( objectStatus "@baseboard_fab2_lib.baseboard_fab2(sch_1):m_e_dqs_dp(4)" )
			)
			( signal "M_E_DQS_DP<5>"
				( objectStatus "@baseboard_fab2_lib.baseboard_fab2(sch_1):m_e_dqs_dp(5)" )
			)
			( signal "M_E_DQS_DP<6>"
				( objectStatus "@baseboard_fab2_lib.baseboard_fab2(sch_1):m_e_dqs_dp(6)" )
			)
			( signal "M_E_DQS_DP<7>"
				( objectStatus "@baseboard_fab2_lib.baseboard_fab2(sch_1):m_e_dqs_dp(7)" )
			)
			( signal "M_E_DQS_DP<8>"
				( objectStatus "@baseboard_fab2_lib.baseboard_fab2(sch_1):m_e_dqs_dp(8)" )
			)
			( signal "M_E_DQS_DP<9>"
				( objectStatus "@baseboard_fab2_lib.baseboard_fab2(sch_1):m_e_dqs_dp(9)" )
			)
			( signal "M_E_DQS_DP<10>"
				( objectStatus "@baseboard_fab2_lib.baseboard_fab2(sch_1):m_e_dqs_dp(10)" )
			)
			( signal "M_E_DQS_DP<11>"
				( objectStatus "@baseboard_fab2_lib.baseboard_fab2(sch_1):m_e_dqs_dp(11)" )
			)
			( signal "M_E_DQS_DP<12>"
				( objectStatus "@baseboard_fab2_lib.baseboard_fab2(sch_1):m_e_dqs_dp(12)" )
			)
			( signal "M_E_DQS_DP<13>"
				( objectStatus "@baseboard_fab2_lib.baseboard_fab2(sch_1):m_e_dqs_dp(13)" )
			)
			( signal "M_E_DQS_DP<14>"
				( objectStatus "@baseboard_fab2_lib.baseboard_fab2(sch_1):m_e_dqs_dp(14)" )
			)
			( signal "M_E_DQS_DP<15>"
				( objectStatus "@baseboard_fab2_lib.baseboard_fab2(sch_1):m_e_dqs_dp(15)" )
			)
			( signal "M_E_DQS_DP<16>"
				( objectStatus "@baseboard_fab2_lib.baseboard_fab2(sch_1):m_e_dqs_dp(16)" )
			)
			( signal "M_E_DQS_DP<17>"
				( objectStatus "@baseboard_fab2_lib.baseboard_fab2(sch_1):m_e_dqs_dp(17)" )
			)
			( signal "M_E_ECC<0>"
				( objectStatus "@baseboard_fab2_lib.baseboard_fab2(sch_1):m_e_ecc(0)" )
			)
			( signal "M_E_ECC<1>"
				( objectStatus "@baseboard_fab2_lib.baseboard_fab2(sch_1):m_e_ecc(1)" )
			)
			( signal "M_E_ECC<2>"
				( objectStatus "@baseboard_fab2_lib.baseboard_fab2(sch_1):m_e_ecc(2)" )
			)
			( signal "M_E_ECC<3>"
				( objectStatus "@baseboard_fab2_lib.baseboard_fab2(sch_1):m_e_ecc(3)" )
			)
			( signal "M_E_ECC<4>"
				( objectStatus "@baseboard_fab2_lib.baseboard_fab2(sch_1):m_e_ecc(4)" )
			)
			( signal "M_E_ECC<5>"
				( objectStatus "@baseboard_fab2_lib.baseboard_fab2(sch_1):m_e_ecc(5)" )
			)
			( signal "M_E_ECC<6>"
				( objectStatus "@baseboard_fab2_lib.baseboard_fab2(sch_1):m_e_ecc(6)" )
			)
			( signal "M_E_ECC<7>"
				( objectStatus "@baseboard_fab2_lib.baseboard_fab2(sch_1):m_e_ecc(7)" )
			)
			( signal "M_E_MA<0>"
				( objectStatus "@baseboard_fab2_lib.baseboard_fab2(sch_1):m_e_ma(0)" )
			)
			( signal "M_E_MA<1>"
				( objectStatus "@baseboard_fab2_lib.baseboard_fab2(sch_1):m_e_ma(1)" )
			)
			( signal "M_E_MA<2>"
				( objectStatus "@baseboard_fab2_lib.baseboard_fab2(sch_1):m_e_ma(2)" )
			)
			( signal "M_E_MA<3>"
				( objectStatus "@baseboard_fab2_lib.baseboard_fab2(sch_1):m_e_ma(3)" )
			)
			( signal "M_E_MA<4>"
				( objectStatus "@baseboard_fab2_lib.baseboard_fab2(sch_1):m_e_ma(4)" )
			)
			( signal "M_E_MA<5>"
				( objectStatus "@baseboard_fab2_lib.baseboard_fab2(sch_1):m_e_ma(5)" )
			)
			( signal "M_E_MA<6>"
				( objectStatus "@baseboard_fab2_lib.baseboard_fab2(sch_1):m_e_ma(6)" )
			)
			( signal "M_E_MA<7>"
				( objectStatus "@baseboard_fab2_lib.baseboard_fab2(sch_1):m_e_ma(7)" )
			)
			( signal "M_E_MA<8>"
				( objectStatus "@baseboard_fab2_lib.baseboard_fab2(sch_1):m_e_ma(8)" )
			)
			( signal "M_E_MA<9>"
				( objectStatus "@baseboard_fab2_lib.baseboard_fab2(sch_1):m_e_ma(9)" )
			)
			( signal "M_E_MA<10>"
				( objectStatus "@baseboard_fab2_lib.baseboard_fab2(sch_1):m_e_ma(10)" )
			)
			( signal "M_E_MA<11>"
				( objectStatus "@baseboard_fab2_lib.baseboard_fab2(sch_1):m_e_ma(11)" )
			)
			( signal "M_E_MA<12>"
				( objectStatus "@baseboard_fab2_lib.baseboard_fab2(sch_1):m_e_ma(12)" )
			)
			( signal "M_E_MA<13>"
				( objectStatus "@baseboard_fab2_lib.baseboard_fab2(sch_1):m_e_ma(13)" )
			)
			( signal "M_E_MA<14>"
				( objectStatus "@baseboard_fab2_lib.baseboard_fab2(sch_1):m_e_ma(14)" )
			)
			( signal "M_E_MA<15>"
				( objectStatus "@baseboard_fab2_lib.baseboard_fab2(sch_1):m_e_ma(15)" )
			)
			( signal "M_E_MA<16>"
				( objectStatus "@baseboard_fab2_lib.baseboard_fab2(sch_1):m_e_ma(16)" )
			)
			( signal "M_E_MA<17>"
				( objectStatus "@baseboard_fab2_lib.baseboard_fab2(sch_1):m_e_ma(17)" )
			)
			( signal "M_E_ODT<0>"
				( objectStatus "@baseboard_fab2_lib.baseboard_fab2(sch_1):m_e_odt(0)" )
			)
			( signal "M_E_ODT<1>"
				( objectStatus "@baseboard_fab2_lib.baseboard_fab2(sch_1):m_e_odt(1)" )
			)
			( signal "M_E_ODT<2>"
				( objectStatus "@baseboard_fab2_lib.baseboard_fab2(sch_1):m_e_odt(2)" )
			)
			( signal "M_E_ODT<3>"
				( objectStatus "@baseboard_fab2_lib.baseboard_fab2(sch_1):m_e_odt(3)" )
			)
			( signal "M_E_PAR"
				( objectStatus "@baseboard_fab2_lib.baseboard_fab2(sch_1):m_e_par" )
			)
			( signal "M_F_ACT_N"
				( objectStatus "@baseboard_fab2_lib.baseboard_fab2(sch_1):m_f_act_n" )
			)
			( signal "M_F_ALERT_N"
				( objectStatus "@baseboard_fab2_lib.baseboard_fab2(sch_1):m_f_alert_n" )
			)
			( signal "M_F_BA<0>"
				( objectStatus "@baseboard_fab2_lib.baseboard_fab2(sch_1):m_f_ba(0)" )
			)
			( signal "M_F_BA<1>"
				( objectStatus "@baseboard_fab2_lib.baseboard_fab2(sch_1):m_f_ba(1)" )
			)
			( signal "M_F_BG<0>"
				( objectStatus "@baseboard_fab2_lib.baseboard_fab2(sch_1):m_f_bg(0)" )
			)
			( signal "M_F_BG<1>"
				( objectStatus "@baseboard_fab2_lib.baseboard_fab2(sch_1):m_f_bg(1)" )
			)
			( signal "M_F_C<2>"
				( objectStatus "@baseboard_fab2_lib.baseboard_fab2(sch_1):m_f_c(2)" )
			)
			( signal "M_F_CKE<0>"
				( objectStatus "@baseboard_fab2_lib.baseboard_fab2(sch_1):m_f_cke(0)" )
			)
			( signal "M_F_CKE<1>"
				( objectStatus "@baseboard_fab2_lib.baseboard_fab2(sch_1):m_f_cke(1)" )
			)
			( signal "M_F_CKE<2>"
				( objectStatus "@baseboard_fab2_lib.baseboard_fab2(sch_1):m_f_cke(2)" )
			)
			( signal "M_F_CKE<3>"
				( objectStatus "@baseboard_fab2_lib.baseboard_fab2(sch_1):m_f_cke(3)" )
			)
			( signal "M_F_CLK_DN<0>"
				( objectStatus "@baseboard_fab2_lib.baseboard_fab2(sch_1):m_f_clk_dn(0)" )
			)
			( signal "M_F_CLK_DN<1>"
				( objectStatus "@baseboard_fab2_lib.baseboard_fab2(sch_1):m_f_clk_dn(1)" )
			)
			( signal "M_F_CLK_DN<2>"
				( objectStatus "@baseboard_fab2_lib.baseboard_fab2(sch_1):m_f_clk_dn(2)" )
			)
			( signal "M_F_CLK_DN<3>"
				( objectStatus "@baseboard_fab2_lib.baseboard_fab2(sch_1):m_f_clk_dn(3)" )
			)
			( signal "M_F_CLK_DP<0>"
				( objectStatus "@baseboard_fab2_lib.baseboard_fab2(sch_1):m_f_clk_dp(0)" )
			)
			( signal "M_F_CLK_DP<1>"
				( objectStatus "@baseboard_fab2_lib.baseboard_fab2(sch_1):m_f_clk_dp(1)" )
			)
			( signal "M_F_CLK_DP<2>"
				( objectStatus "@baseboard_fab2_lib.baseboard_fab2(sch_1):m_f_clk_dp(2)" )
			)
			( signal "M_F_CLK_DP<3>"
				( objectStatus "@baseboard_fab2_lib.baseboard_fab2(sch_1):m_f_clk_dp(3)" )
			)
			( signal "M_F_CS_N<0>"
				( objectStatus "@baseboard_fab2_lib.baseboard_fab2(sch_1):m_f_cs_n(0)" )
			)
			( signal "M_F_CS_N<1>"
				( objectStatus "@baseboard_fab2_lib.baseboard_fab2(sch_1):m_f_cs_n(1)" )
			)
			( signal "M_F_CS_N<2>"
				( objectStatus "@baseboard_fab2_lib.baseboard_fab2(sch_1):m_f_cs_n(2)" )
			)
			( signal "M_F_CS_N<3>"
				( objectStatus "@baseboard_fab2_lib.baseboard_fab2(sch_1):m_f_cs_n(3)" )
			)
			( signal "M_F_CS_N<4>"
				( objectStatus "@baseboard_fab2_lib.baseboard_fab2(sch_1):m_f_cs_n(4)" )
			)
			( signal "M_F_CS_N<5>"
				( objectStatus "@baseboard_fab2_lib.baseboard_fab2(sch_1):m_f_cs_n(5)" )
			)
			( signal "M_F_CS_N<6>"
				( objectStatus "@baseboard_fab2_lib.baseboard_fab2(sch_1):m_f_cs_n(6)" )
			)
			( signal "M_F_CS_N<7>"
				( objectStatus "@baseboard_fab2_lib.baseboard_fab2(sch_1):m_f_cs_n(7)" )
			)
			( signal "M_F_DQ<0>"
				( objectStatus "@baseboard_fab2_lib.baseboard_fab2(sch_1):m_f_dq(0)" )
			)
			( signal "M_F_DQ<1>"
				( objectStatus "@baseboard_fab2_lib.baseboard_fab2(sch_1):m_f_dq(1)" )
			)
			( signal "M_F_DQ<2>"
				( objectStatus "@baseboard_fab2_lib.baseboard_fab2(sch_1):m_f_dq(2)" )
			)
			( signal "M_F_DQ<3>"
				( objectStatus "@baseboard_fab2_lib.baseboard_fab2(sch_1):m_f_dq(3)" )
			)
			( signal "M_F_DQ<4>"
				( objectStatus "@baseboard_fab2_lib.baseboard_fab2(sch_1):m_f_dq(4)" )
			)
			( signal "M_F_DQ<5>"
				( objectStatus "@baseboard_fab2_lib.baseboard_fab2(sch_1):m_f_dq(5)" )
			)
			( signal "M_F_DQ<6>"
				( objectStatus "@baseboard_fab2_lib.baseboard_fab2(sch_1):m_f_dq(6)" )
			)
			( signal "M_F_DQ<7>"
				( objectStatus "@baseboard_fab2_lib.baseboard_fab2(sch_1):m_f_dq(7)" )
			)
			( signal "M_F_DQ<8>"
				( objectStatus "@baseboard_fab2_lib.baseboard_fab2(sch_1):m_f_dq(8)" )
			)
			( signal "M_F_DQ<9>"
				( objectStatus "@baseboard_fab2_lib.baseboard_fab2(sch_1):m_f_dq(9)" )
			)
			( signal "M_F_DQ<10>"
				( objectStatus "@baseboard_fab2_lib.baseboard_fab2(sch_1):m_f_dq(10)" )
			)
			( signal "M_F_DQ<11>"
				( objectStatus "@baseboard_fab2_lib.baseboard_fab2(sch_1):m_f_dq(11)" )
			)
			( signal "M_F_DQ<12>"
				( objectStatus "@baseboard_fab2_lib.baseboard_fab2(sch_1):m_f_dq(12)" )
			)
			( signal "M_F_DQ<13>"
				( objectStatus "@baseboard_fab2_lib.baseboard_fab2(sch_1):m_f_dq(13)" )
			)
			( signal "M_F_DQ<14>"
				( objectStatus "@baseboard_fab2_lib.baseboard_fab2(sch_1):m_f_dq(14)" )
			)
			( signal "M_F_DQ<15>"
				( objectStatus "@baseboard_fab2_lib.baseboard_fab2(sch_1):m_f_dq(15)" )
			)
			( signal "M_F_DQ<16>"
				( objectStatus "@baseboard_fab2_lib.baseboard_fab2(sch_1):m_f_dq(16)" )
			)
			( signal "M_F_DQ<17>"
				( objectStatus "@baseboard_fab2_lib.baseboard_fab2(sch_1):m_f_dq(17)" )
			)
			( signal "M_F_DQ<18>"
				( objectStatus "@baseboard_fab2_lib.baseboard_fab2(sch_1):m_f_dq(18)" )
			)
			( signal "M_F_DQ<19>"
				( objectStatus "@baseboard_fab2_lib.baseboard_fab2(sch_1):m_f_dq(19)" )
			)
			( signal "M_F_DQ<20>"
				( objectStatus "@baseboard_fab2_lib.baseboard_fab2(sch_1):m_f_dq(20)" )
			)
			( signal "M_F_DQ<21>"
				( objectStatus "@baseboard_fab2_lib.baseboard_fab2(sch_1):m_f_dq(21)" )
			)
			( signal "M_F_DQ<22>"
				( objectStatus "@baseboard_fab2_lib.baseboard_fab2(sch_1):m_f_dq(22)" )
			)
			( signal "M_F_DQ<23>"
				( objectStatus "@baseboard_fab2_lib.baseboard_fab2(sch_1):m_f_dq(23)" )
			)
			( signal "M_F_DQ<24>"
				( objectStatus "@baseboard_fab2_lib.baseboard_fab2(sch_1):m_f_dq(24)" )
			)
			( signal "M_F_DQ<25>"
				( objectStatus "@baseboard_fab2_lib.baseboard_fab2(sch_1):m_f_dq(25)" )
			)
			( signal "M_F_DQ<26>"
				( objectStatus "@baseboard_fab2_lib.baseboard_fab2(sch_1):m_f_dq(26)" )
			)
			( signal "M_F_DQ<27>"
				( objectStatus "@baseboard_fab2_lib.baseboard_fab2(sch_1):m_f_dq(27)" )
			)
			( signal "M_F_DQ<28>"
				( objectStatus "@baseboard_fab2_lib.baseboard_fab2(sch_1):m_f_dq(28)" )
			)
			( signal "M_F_DQ<29>"
				( objectStatus "@baseboard_fab2_lib.baseboard_fab2(sch_1):m_f_dq(29)" )
			)
			( signal "M_F_DQ<30>"
				( objectStatus "@baseboard_fab2_lib.baseboard_fab2(sch_1):m_f_dq(30)" )
			)
			( signal "M_F_DQ<31>"
				( objectStatus "@baseboard_fab2_lib.baseboard_fab2(sch_1):m_f_dq(31)" )
			)
			( signal "M_F_DQ<32>"
				( objectStatus "@baseboard_fab2_lib.baseboard_fab2(sch_1):m_f_dq(32)" )
			)
			( signal "M_F_DQ<33>"
				( objectStatus "@baseboard_fab2_lib.baseboard_fab2(sch_1):m_f_dq(33)" )
			)
			( signal "M_F_DQ<34>"
				( objectStatus "@baseboard_fab2_lib.baseboard_fab2(sch_1):m_f_dq(34)" )
			)
			( signal "M_F_DQ<35>"
				( objectStatus "@baseboard_fab2_lib.baseboard_fab2(sch_1):m_f_dq(35)" )
			)
			( signal "M_F_DQ<36>"
				( objectStatus "@baseboard_fab2_lib.baseboard_fab2(sch_1):m_f_dq(36)" )
			)
			( signal "M_F_DQ<37>"
				( objectStatus "@baseboard_fab2_lib.baseboard_fab2(sch_1):m_f_dq(37)" )
			)
			( signal "M_F_DQ<38>"
				( objectStatus "@baseboard_fab2_lib.baseboard_fab2(sch_1):m_f_dq(38)" )
			)
			( signal "M_F_DQ<39>"
				( objectStatus "@baseboard_fab2_lib.baseboard_fab2(sch_1):m_f_dq(39)" )
			)
			( signal "M_F_DQ<40>"
				( objectStatus "@baseboard_fab2_lib.baseboard_fab2(sch_1):m_f_dq(40)" )
			)
			( signal "M_F_DQ<41>"
				( objectStatus "@baseboard_fab2_lib.baseboard_fab2(sch_1):m_f_dq(41)" )
			)
			( signal "M_F_DQ<42>"
				( objectStatus "@baseboard_fab2_lib.baseboard_fab2(sch_1):m_f_dq(42)" )
			)
			( signal "M_F_DQ<43>"
				( objectStatus "@baseboard_fab2_lib.baseboard_fab2(sch_1):m_f_dq(43)" )
			)
			( signal "M_F_DQ<44>"
				( objectStatus "@baseboard_fab2_lib.baseboard_fab2(sch_1):m_f_dq(44)" )
			)
			( signal "M_F_DQ<45>"
				( objectStatus "@baseboard_fab2_lib.baseboard_fab2(sch_1):m_f_dq(45)" )
			)
			( signal "M_F_DQ<46>"
				( objectStatus "@baseboard_fab2_lib.baseboard_fab2(sch_1):m_f_dq(46)" )
			)
			( signal "M_F_DQ<47>"
				( objectStatus "@baseboard_fab2_lib.baseboard_fab2(sch_1):m_f_dq(47)" )
			)
			( signal "M_F_DQ<48>"
				( objectStatus "@baseboard_fab2_lib.baseboard_fab2(sch_1):m_f_dq(48)" )
			)
			( signal "M_F_DQ<49>"
				( objectStatus "@baseboard_fab2_lib.baseboard_fab2(sch_1):m_f_dq(49)" )
			)
			( signal "M_F_DQ<50>"
				( objectStatus "@baseboard_fab2_lib.baseboard_fab2(sch_1):m_f_dq(50)" )
			)
			( signal "M_F_DQ<51>"
				( objectStatus "@baseboard_fab2_lib.baseboard_fab2(sch_1):m_f_dq(51)" )
			)
			( signal "M_F_DQ<52>"
				( objectStatus "@baseboard_fab2_lib.baseboard_fab2(sch_1):m_f_dq(52)" )
			)
			( signal "M_F_DQ<53>"
				( objectStatus "@baseboard_fab2_lib.baseboard_fab2(sch_1):m_f_dq(53)" )
			)
			( signal "M_F_DQ<54>"
				( objectStatus "@baseboard_fab2_lib.baseboard_fab2(sch_1):m_f_dq(54)" )
			)
			( signal "M_F_DQ<55>"
				( objectStatus "@baseboard_fab2_lib.baseboard_fab2(sch_1):m_f_dq(55)" )
			)
			( signal "M_F_DQ<56>"
				( objectStatus "@baseboard_fab2_lib.baseboard_fab2(sch_1):m_f_dq(56)" )
			)
			( signal "M_F_DQ<57>"
				( objectStatus "@baseboard_fab2_lib.baseboard_fab2(sch_1):m_f_dq(57)" )
			)
			( signal "M_F_DQ<58>"
				( objectStatus "@baseboard_fab2_lib.baseboard_fab2(sch_1):m_f_dq(58)" )
			)
			( signal "M_F_DQ<59>"
				( objectStatus "@baseboard_fab2_lib.baseboard_fab2(sch_1):m_f_dq(59)" )
			)
			( signal "M_F_DQ<60>"
				( objectStatus "@baseboard_fab2_lib.baseboard_fab2(sch_1):m_f_dq(60)" )
			)
			( signal "M_F_DQ<61>"
				( objectStatus "@baseboard_fab2_lib.baseboard_fab2(sch_1):m_f_dq(61)" )
			)
			( signal "M_F_DQ<62>"
				( objectStatus "@baseboard_fab2_lib.baseboard_fab2(sch_1):m_f_dq(62)" )
			)
			( signal "M_F_DQ<63>"
				( objectStatus "@baseboard_fab2_lib.baseboard_fab2(sch_1):m_f_dq(63)" )
			)
			( signal "M_F_DQS_DN<0>"
				( objectStatus "@baseboard_fab2_lib.baseboard_fab2(sch_1):m_f_dqs_dn(0)" )
			)
			( signal "M_F_DQS_DN<1>"
				( objectStatus "@baseboard_fab2_lib.baseboard_fab2(sch_1):m_f_dqs_dn(1)" )
			)
			( signal "M_F_DQS_DN<2>"
				( objectStatus "@baseboard_fab2_lib.baseboard_fab2(sch_1):m_f_dqs_dn(2)" )
			)
			( signal "M_F_DQS_DN<3>"
				( objectStatus "@baseboard_fab2_lib.baseboard_fab2(sch_1):m_f_dqs_dn(3)" )
			)
			( signal "M_F_DQS_DN<4>"
				( objectStatus "@baseboard_fab2_lib.baseboard_fab2(sch_1):m_f_dqs_dn(4)" )
			)
			( signal "M_F_DQS_DN<5>"
				( objectStatus "@baseboard_fab2_lib.baseboard_fab2(sch_1):m_f_dqs_dn(5)" )
			)
			( signal "M_F_DQS_DN<6>"
				( objectStatus "@baseboard_fab2_lib.baseboard_fab2(sch_1):m_f_dqs_dn(6)" )
			)
			( signal "M_F_DQS_DN<7>"
				( objectStatus "@baseboard_fab2_lib.baseboard_fab2(sch_1):m_f_dqs_dn(7)" )
			)
			( signal "M_F_DQS_DN<8>"
				( objectStatus "@baseboard_fab2_lib.baseboard_fab2(sch_1):m_f_dqs_dn(8)" )
			)
			( signal "M_F_DQS_DN<9>"
				( objectStatus "@baseboard_fab2_lib.baseboard_fab2(sch_1):m_f_dqs_dn(9)" )
			)
			( signal "M_F_DQS_DN<10>"
				( objectStatus "@baseboard_fab2_lib.baseboard_fab2(sch_1):m_f_dqs_dn(10)" )
			)
			( signal "M_F_DQS_DN<11>"
				( objectStatus "@baseboard_fab2_lib.baseboard_fab2(sch_1):m_f_dqs_dn(11)" )
			)
			( signal "M_F_DQS_DN<12>"
				( objectStatus "@baseboard_fab2_lib.baseboard_fab2(sch_1):m_f_dqs_dn(12)" )
			)
			( signal "M_F_DQS_DN<13>"
				( objectStatus "@baseboard_fab2_lib.baseboard_fab2(sch_1):m_f_dqs_dn(13)" )
			)
			( signal "M_F_DQS_DN<14>"
				( objectStatus "@baseboard_fab2_lib.baseboard_fab2(sch_1):m_f_dqs_dn(14)" )
			)
			( signal "M_F_DQS_DN<15>"
				( objectStatus "@baseboard_fab2_lib.baseboard_fab2(sch_1):m_f_dqs_dn(15)" )
			)
			( signal "M_F_DQS_DN<16>"
				( objectStatus "@baseboard_fab2_lib.baseboard_fab2(sch_1):m_f_dqs_dn(16)" )
			)
			( signal "M_F_DQS_DN<17>"
				( objectStatus "@baseboard_fab2_lib.baseboard_fab2(sch_1):m_f_dqs_dn(17)" )
			)
			( signal "M_F_DQS_DP<0>"
				( objectStatus "@baseboard_fab2_lib.baseboard_fab2(sch_1):m_f_dqs_dp(0)" )
			)
			( signal "M_F_DQS_DP<1>"
				( objectStatus "@baseboard_fab2_lib.baseboard_fab2(sch_1):m_f_dqs_dp(1)" )
			)
			( signal "M_F_DQS_DP<2>"
				( objectStatus "@baseboard_fab2_lib.baseboard_fab2(sch_1):m_f_dqs_dp(2)" )
			)
			( signal "M_F_DQS_DP<3>"
				( objectStatus "@baseboard_fab2_lib.baseboard_fab2(sch_1):m_f_dqs_dp(3)" )
			)
			( signal "M_F_DQS_DP<4>"
				( objectStatus "@baseboard_fab2_lib.baseboard_fab2(sch_1):m_f_dqs_dp(4)" )
			)
			( signal "M_F_DQS_DP<5>"
				( objectStatus "@baseboard_fab2_lib.baseboard_fab2(sch_1):m_f_dqs_dp(5)" )
			)
			( signal "M_F_DQS_DP<6>"
				( objectStatus "@baseboard_fab2_lib.baseboard_fab2(sch_1):m_f_dqs_dp(6)" )
			)
			( signal "M_F_DQS_DP<7>"
				( objectStatus "@baseboard_fab2_lib.baseboard_fab2(sch_1):m_f_dqs_dp(7)" )
			)
			( signal "M_F_DQS_DP<8>"
				( objectStatus "@baseboard_fab2_lib.baseboard_fab2(sch_1):m_f_dqs_dp(8)" )
			)
			( signal "M_F_DQS_DP<9>"
				( objectStatus "@baseboard_fab2_lib.baseboard_fab2(sch_1):m_f_dqs_dp(9)" )
			)
			( signal "M_F_DQS_DP<10>"
				( objectStatus "@baseboard_fab2_lib.baseboard_fab2(sch_1):m_f_dqs_dp(10)" )
			)
			( signal "M_F_DQS_DP<11>"
				( objectStatus "@baseboard_fab2_lib.baseboard_fab2(sch_1):m_f_dqs_dp(11)" )
			)
			( signal "M_F_DQS_DP<12>"
				( objectStatus "@baseboard_fab2_lib.baseboard_fab2(sch_1):m_f_dqs_dp(12)" )
			)
			( signal "M_F_DQS_DP<13>"
				( objectStatus "@baseboard_fab2_lib.baseboard_fab2(sch_1):m_f_dqs_dp(13)" )
			)
			( signal "M_F_DQS_DP<14>"
				( objectStatus "@baseboard_fab2_lib.baseboard_fab2(sch_1):m_f_dqs_dp(14)" )
			)
			( signal "M_F_DQS_DP<15>"
				( objectStatus "@baseboard_fab2_lib.baseboard_fab2(sch_1):m_f_dqs_dp(15)" )
			)
			( signal "M_F_DQS_DP<16>"
				( objectStatus "@baseboard_fab2_lib.baseboard_fab2(sch_1):m_f_dqs_dp(16)" )
			)
			( signal "M_F_DQS_DP<17>"
				( objectStatus "@baseboard_fab2_lib.baseboard_fab2(sch_1):m_f_dqs_dp(17)" )
			)
			( signal "M_F_ECC<0>"
				( objectStatus "@baseboard_fab2_lib.baseboard_fab2(sch_1):m_f_ecc(0)" )
			)
			( signal "M_F_ECC<1>"
				( objectStatus "@baseboard_fab2_lib.baseboard_fab2(sch_1):m_f_ecc(1)" )
			)
			( signal "M_F_ECC<2>"
				( objectStatus "@baseboard_fab2_lib.baseboard_fab2(sch_1):m_f_ecc(2)" )
			)
			( signal "M_F_ECC<3>"
				( objectStatus "@baseboard_fab2_lib.baseboard_fab2(sch_1):m_f_ecc(3)" )
			)
			( signal "M_F_ECC<4>"
				( objectStatus "@baseboard_fab2_lib.baseboard_fab2(sch_1):m_f_ecc(4)" )
			)
			( signal "M_F_ECC<5>"
				( objectStatus "@baseboard_fab2_lib.baseboard_fab2(sch_1):m_f_ecc(5)" )
			)
			( signal "M_F_ECC<6>"
				( objectStatus "@baseboard_fab2_lib.baseboard_fab2(sch_1):m_f_ecc(6)" )
			)
			( signal "M_F_ECC<7>"
				( objectStatus "@baseboard_fab2_lib.baseboard_fab2(sch_1):m_f_ecc(7)" )
			)
			( signal "M_F_MA<0>"
				( objectStatus "@baseboard_fab2_lib.baseboard_fab2(sch_1):m_f_ma(0)" )
			)
			( signal "M_F_MA<1>"
				( objectStatus "@baseboard_fab2_lib.baseboard_fab2(sch_1):m_f_ma(1)" )
			)
			( signal "M_F_MA<2>"
				( objectStatus "@baseboard_fab2_lib.baseboard_fab2(sch_1):m_f_ma(2)" )
			)
			( signal "M_F_MA<3>"
				( objectStatus "@baseboard_fab2_lib.baseboard_fab2(sch_1):m_f_ma(3)" )
			)
			( signal "M_F_MA<4>"
				( objectStatus "@baseboard_fab2_lib.baseboard_fab2(sch_1):m_f_ma(4)" )
			)
			( signal "M_F_MA<5>"
				( objectStatus "@baseboard_fab2_lib.baseboard_fab2(sch_1):m_f_ma(5)" )
			)
			( signal "M_F_MA<6>"
				( objectStatus "@baseboard_fab2_lib.baseboard_fab2(sch_1):m_f_ma(6)" )
			)
			( signal "M_F_MA<7>"
				( objectStatus "@baseboard_fab2_lib.baseboard_fab2(sch_1):m_f_ma(7)" )
			)
			( signal "M_F_MA<8>"
				( objectStatus "@baseboard_fab2_lib.baseboard_fab2(sch_1):m_f_ma(8)" )
			)
			( signal "M_F_MA<9>"
				( objectStatus "@baseboard_fab2_lib.baseboard_fab2(sch_1):m_f_ma(9)" )
			)
			( signal "M_F_MA<10>"
				( objectStatus "@baseboard_fab2_lib.baseboard_fab2(sch_1):m_f_ma(10)" )
			)
			( signal "M_F_MA<11>"
				( objectStatus "@baseboard_fab2_lib.baseboard_fab2(sch_1):m_f_ma(11)" )
			)
			( signal "M_F_MA<12>"
				( objectStatus "@baseboard_fab2_lib.baseboard_fab2(sch_1):m_f_ma(12)" )
			)
			( signal "M_F_MA<13>"
				( objectStatus "@baseboard_fab2_lib.baseboard_fab2(sch_1):m_f_ma(13)" )
			)
			( signal "M_F_MA<14>"
				( objectStatus "@baseboard_fab2_lib.baseboard_fab2(sch_1):m_f_ma(14)" )
			)
			( signal "M_F_MA<15>"
				( objectStatus "@baseboard_fab2_lib.baseboard_fab2(sch_1):m_f_ma(15)" )
			)
			( signal "M_F_MA<16>"
				( objectStatus "@baseboard_fab2_lib.baseboard_fab2(sch_1):m_f_ma(16)" )
			)
			( signal "M_F_MA<17>"
				( objectStatus "@baseboard_fab2_lib.baseboard_fab2(sch_1):m_f_ma(17)" )
			)
			( signal "M_F_ODT<0>"
				( objectStatus "@baseboard_fab2_lib.baseboard_fab2(sch_1):m_f_odt(0)" )
			)
			( signal "M_F_ODT<1>"
				( objectStatus "@baseboard_fab2_lib.baseboard_fab2(sch_1):m_f_odt(1)" )
			)
			( signal "M_F_ODT<2>"
				( objectStatus "@baseboard_fab2_lib.baseboard_fab2(sch_1):m_f_odt(2)" )
			)
			( signal "M_F_ODT<3>"
				( objectStatus "@baseboard_fab2_lib.baseboard_fab2(sch_1):m_f_odt(3)" )
			)
			( signal "M_F_PAR"
				( objectStatus "@baseboard_fab2_lib.baseboard_fab2(sch_1):m_f_par" )
			)
			( signal "CLK_100M_CPU0_PE_REFCLK_DN"
				( objectStatus "@baseboard_fab2_lib.baseboard_fab2(sch_1):clk_100m_cpu0_pe_refclk_dn" )
			)
			( signal "CLK_100M_CPU0_PE_REFCLK_DP"
				( objectStatus "@baseboard_fab2_lib.baseboard_fab2(sch_1):clk_100m_cpu0_pe_refclk_dp" )
			)
			( signal "CLK_156M_OSC_CPU0_HFI_DN"
				( objectStatus "@baseboard_fab2_lib.baseboard_fab2(sch_1):clk_156m_osc_cpu0_hfi_dn" )
			)
			( signal "CLK_156M_OSC_CPU0_HFI_DP"
				( objectStatus "@baseboard_fab2_lib.baseboard_fab2(sch_1):clk_156m_osc_cpu0_hfi_dp" )
			)
			( signal "DMI_CPU0_PCH_RX_C_DN<0>"
				( objectStatus "@baseboard_fab2_lib.baseboard_fab2(sch_1):dmi_cpu0_pch_rx_c_dn(0)" )
			)
			( signal "DMI_CPU0_PCH_RX_C_DN<1>"
				( objectStatus "@baseboard_fab2_lib.baseboard_fab2(sch_1):dmi_cpu0_pch_rx_c_dn(1)" )
			)
			( signal "DMI_CPU0_PCH_RX_C_DN<2>"
				( objectStatus "@baseboard_fab2_lib.baseboard_fab2(sch_1):dmi_cpu0_pch_rx_c_dn(2)" )
			)
			( signal "DMI_CPU0_PCH_RX_C_DN<3>"
				( objectStatus "@baseboard_fab2_lib.baseboard_fab2(sch_1):dmi_cpu0_pch_rx_c_dn(3)" )
			)
			( signal "DMI_CPU0_PCH_RX_C_DP<0>"
				( objectStatus "@baseboard_fab2_lib.baseboard_fab2(sch_1):dmi_cpu0_pch_rx_c_dp(0)" )
			)
			( signal "DMI_CPU0_PCH_RX_C_DP<1>"
				( objectStatus "@baseboard_fab2_lib.baseboard_fab2(sch_1):dmi_cpu0_pch_rx_c_dp(1)" )
			)
			( signal "DMI_CPU0_PCH_RX_C_DP<2>"
				( objectStatus "@baseboard_fab2_lib.baseboard_fab2(sch_1):dmi_cpu0_pch_rx_c_dp(2)" )
			)
			( signal "DMI_CPU0_PCH_RX_C_DP<3>"
				( objectStatus "@baseboard_fab2_lib.baseboard_fab2(sch_1):dmi_cpu0_pch_rx_c_dp(3)" )
			)
			( signal "DMI_CPU0_PCH_TX_DN<0>"
				( objectStatus "@baseboard_fab2_lib.baseboard_fab2(sch_1):dmi_cpu0_pch_tx_dn(0)" )
			)
			( signal "DMI_CPU0_PCH_TX_DN<1>"
				( objectStatus "@baseboard_fab2_lib.baseboard_fab2(sch_1):dmi_cpu0_pch_tx_dn(1)" )
			)
			( signal "DMI_CPU0_PCH_TX_DN<2>"
				( objectStatus "@baseboard_fab2_lib.baseboard_fab2(sch_1):dmi_cpu0_pch_tx_dn(2)" )
			)
			( signal "DMI_CPU0_PCH_TX_DN<3>"
				( objectStatus "@baseboard_fab2_lib.baseboard_fab2(sch_1):dmi_cpu0_pch_tx_dn(3)" )
			)
			( signal "DMI_CPU0_PCH_TX_DP<0>"
				( objectStatus "@baseboard_fab2_lib.baseboard_fab2(sch_1):dmi_cpu0_pch_tx_dp(0)" )
			)
			( signal "DMI_CPU0_PCH_TX_DP<1>"
				( objectStatus "@baseboard_fab2_lib.baseboard_fab2(sch_1):dmi_cpu0_pch_tx_dp(1)" )
			)
			( signal "DMI_CPU0_PCH_TX_DP<2>"
				( objectStatus "@baseboard_fab2_lib.baseboard_fab2(sch_1):dmi_cpu0_pch_tx_dp(2)" )
			)
			( signal "DMI_CPU0_PCH_TX_DP<3>"
				( objectStatus "@baseboard_fab2_lib.baseboard_fab2(sch_1):dmi_cpu0_pch_tx_dp(3)" )
			)
			( signal "FM_MODPRST_HFI0_CPU0_LVT2_N"
				( objectStatus "@baseboard_fab2_lib.baseboard_fab2(sch_1):fm_modprst_hfi0_cpu0_lvt2_n" )
			)
			( signal "FM_MODPRST_HFI1_CPU0_LVT2_N"
				( objectStatus "@baseboard_fab2_lib.baseboard_fab2(sch_1):fm_modprst_hfi1_cpu0_lvt2_n" )
			)
			( signal "IRQ_HFI0_CPU0_LVT2_N"
				( objectStatus "@baseboard_fab2_lib.baseboard_fab2(sch_1):irq_hfi0_cpu0_lvt2_n" )
			)
			( signal "IRQ_HFI1_CPU0_LVT2_N"
				( objectStatus "@baseboard_fab2_lib.baseboard_fab2(sch_1):irq_hfi1_cpu0_lvt2_n" )
			)
			( signal "JTAG_MCP_CPU0_TDI"
				( objectStatus "@baseboard_fab2_lib.baseboard_fab2(sch_1):jtag_mcp_cpu0_tdi" )
			)
			( signal "JTAG_MCP_CPU0_TDO"
				( objectStatus "@baseboard_fab2_lib.baseboard_fab2(sch_1):jtag_mcp_cpu0_tdo" )
			)
			( signal "JTAG_MCP_TCK"
				( objectStatus "@baseboard_fab2_lib.baseboard_fab2(sch_1):jtag_mcp_tck" )
			)
			( signal "JTAG_MCP_TMS"
				( objectStatus "@baseboard_fab2_lib.baseboard_fab2(sch_1):jtag_mcp_tms" )
			)
			( signal "JTAG_MCP_TRST_N"
				( objectStatus "@baseboard_fab2_lib.baseboard_fab2(sch_1):jtag_mcp_trst_n" )
			)
			( signal "LED_HFI0_CPU0_N"
				( objectStatus "@baseboard_fab2_lib.baseboard_fab2(sch_1):led_hfi0_cpu0_n" )
			)
			( signal "LED_HFI1_CPU0_N"
				( objectStatus "@baseboard_fab2_lib.baseboard_fab2(sch_1):led_hfi1_cpu0_n" )
			)
			( signal "RST_CD_CPU0_POR_N"
				( objectStatus "@baseboard_fab2_lib.baseboard_fab2(sch_1):rst_cd_cpu0_por_n" )
			)
			( signal "RST_HFI0_CPU0_LVT2_N"
				( objectStatus "@baseboard_fab2_lib.baseboard_fab2(sch_1):rst_hfi0_cpu0_lvt2_n" )
			)
			( signal "RST_HFI1_CPU0_LVT2_N"
				( objectStatus "@baseboard_fab2_lib.baseboard_fab2(sch_1):rst_hfi1_cpu0_lvt2_n" )
			)
			( signal "SMB_HFI0_CPU0_LVC2_SCL"
				( objectStatus "@baseboard_fab2_lib.baseboard_fab2(sch_1):smb_hfi0_cpu0_lvc2_scl" )
			)
			( signal "SMB_HFI0_CPU0_LVC2_SDA"
				( objectStatus "@baseboard_fab2_lib.baseboard_fab2(sch_1):smb_hfi0_cpu0_lvc2_sda" )
			)
			( signal "SMB_HFI1_CPU0_LVC2_SCL"
				( objectStatus "@baseboard_fab2_lib.baseboard_fab2(sch_1):smb_hfi1_cpu0_lvc2_scl" )
			)
			( signal "SMB_HFI1_CPU0_LVC2_SDA"
				( objectStatus "@baseboard_fab2_lib.baseboard_fab2(sch_1):smb_hfi1_cpu0_lvc2_sda" )
			)
			( signal "TP_CPU0_RSVD_172"
				( objectStatus "@baseboard_fab2_lib.baseboard_fab2(sch_1):tp_cpu0_rsvd_172" )
			)
			( signal "TP_CPU0_RSVD_173"
				( objectStatus "@baseboard_fab2_lib.baseboard_fab2(sch_1):tp_cpu0_rsvd_173" )
			)
			( signal "TP_CPU0_RSVD_174"
				( objectStatus "@baseboard_fab2_lib.baseboard_fab2(sch_1):tp_cpu0_rsvd_174" )
			)
			( signal "TP_CPU0_RSVD_175"
				( objectStatus "@baseboard_fab2_lib.baseboard_fab2(sch_1):tp_cpu0_rsvd_175" )
			)
			( signal "TP_CPU0_RSVD_176"
				( objectStatus "@baseboard_fab2_lib.baseboard_fab2(sch_1):tp_cpu0_rsvd_176" )
			)
			( signal "TP_CPU0_RSVD_177"
				( objectStatus "@baseboard_fab2_lib.baseboard_fab2(sch_1):tp_cpu0_rsvd_177" )
			)
			( signal "TP_CPU0_RSVD_178"
				( objectStatus "@baseboard_fab2_lib.baseboard_fab2(sch_1):tp_cpu0_rsvd_178" )
			)
			( signal "TP_CPU0_RSVD_179"
				( objectStatus "@baseboard_fab2_lib.baseboard_fab2(sch_1):tp_cpu0_rsvd_179" )
			)
			( signal "TP_CPU0_RSVD_180"
				( objectStatus "@baseboard_fab2_lib.baseboard_fab2(sch_1):tp_cpu0_rsvd_180" )
			)
			( signal "TP_CPU0_RSVD_181"
				( objectStatus "@baseboard_fab2_lib.baseboard_fab2(sch_1):tp_cpu0_rsvd_181" )
			)
			( signal "TP_CPU0_RSVD_182"
				( objectStatus "@baseboard_fab2_lib.baseboard_fab2(sch_1):tp_cpu0_rsvd_182" )
			)
			( signal "TP_CPU0_RSVD_183"
				( objectStatus "@baseboard_fab2_lib.baseboard_fab2(sch_1):tp_cpu0_rsvd_183" )
			)
			( signal "TP_CPU0_RSVD_184"
				( objectStatus "@baseboard_fab2_lib.baseboard_fab2(sch_1):tp_cpu0_rsvd_184" )
			)
			( signal "TP_CPU0_RSVD_186"
				( objectStatus "@baseboard_fab2_lib.baseboard_fab2(sch_1):tp_cpu0_rsvd_186" )
			)
			( signal "TP_CPU0_RSVD_189"
				( objectStatus "@baseboard_fab2_lib.baseboard_fab2(sch_1):tp_cpu0_rsvd_189" )
			)
			( signal "TP_CPU0_RSVD_190"
				( objectStatus "@baseboard_fab2_lib.baseboard_fab2(sch_1):tp_cpu0_rsvd_190" )
			)
			( signal "P3E_CPU0_PE1_PCH_RXN<8>"
				( objectStatus "@baseboard_fab2_lib.baseboard_fab2(sch_1):p3e_cpu0_pe1_pch_rxn(8)" )
			)
			( signal "P3E_CPU0_PE1_PCH_RXN<9>"
				( objectStatus "@baseboard_fab2_lib.baseboard_fab2(sch_1):p3e_cpu0_pe1_pch_rxn(9)" )
			)
			( signal "P3E_CPU0_PE1_PCH_RXN<10>"
				( objectStatus "@baseboard_fab2_lib.baseboard_fab2(sch_1):p3e_cpu0_pe1_pch_rxn(10)" )
			)
			( signal "P3E_CPU0_PE1_PCH_RXN<11>"
				( objectStatus "@baseboard_fab2_lib.baseboard_fab2(sch_1):p3e_cpu0_pe1_pch_rxn(11)" )
			)
			( signal "P3E_CPU0_PE1_PCH_RXN<12>"
				( objectStatus "@baseboard_fab2_lib.baseboard_fab2(sch_1):p3e_cpu0_pe1_pch_rxn(12)" )
			)
			( signal "P3E_CPU0_PE1_PCH_RXN<13>"
				( objectStatus "@baseboard_fab2_lib.baseboard_fab2(sch_1):p3e_cpu0_pe1_pch_rxn(13)" )
			)
			( signal "P3E_CPU0_PE1_PCH_RXN<14>"
				( objectStatus "@baseboard_fab2_lib.baseboard_fab2(sch_1):p3e_cpu0_pe1_pch_rxn(14)" )
			)
			( signal "P3E_CPU0_PE1_PCH_RXN<15>"
				( objectStatus "@baseboard_fab2_lib.baseboard_fab2(sch_1):p3e_cpu0_pe1_pch_rxn(15)" )
			)
			( signal "P3E_CPU0_PE1_PCH_RXP<8>"
				( objectStatus "@baseboard_fab2_lib.baseboard_fab2(sch_1):p3e_cpu0_pe1_pch_rxp(8)" )
			)
			( signal "P3E_CPU0_PE1_PCH_RXP<9>"
				( objectStatus "@baseboard_fab2_lib.baseboard_fab2(sch_1):p3e_cpu0_pe1_pch_rxp(9)" )
			)
			( signal "P3E_CPU0_PE1_PCH_RXP<10>"
				( objectStatus "@baseboard_fab2_lib.baseboard_fab2(sch_1):p3e_cpu0_pe1_pch_rxp(10)" )
			)
			( signal "P3E_CPU0_PE1_PCH_RXP<11>"
				( objectStatus "@baseboard_fab2_lib.baseboard_fab2(sch_1):p3e_cpu0_pe1_pch_rxp(11)" )
			)
			( signal "P3E_CPU0_PE1_PCH_RXP<12>"
				( objectStatus "@baseboard_fab2_lib.baseboard_fab2(sch_1):p3e_cpu0_pe1_pch_rxp(12)" )
			)
			( signal "P3E_CPU0_PE1_PCH_RXP<13>"
				( objectStatus "@baseboard_fab2_lib.baseboard_fab2(sch_1):p3e_cpu0_pe1_pch_rxp(13)" )
			)
			( signal "P3E_CPU0_PE1_PCH_RXP<14>"
				( objectStatus "@baseboard_fab2_lib.baseboard_fab2(sch_1):p3e_cpu0_pe1_pch_rxp(14)" )
			)
			( signal "P3E_CPU0_PE1_PCH_RXP<15>"
				( objectStatus "@baseboard_fab2_lib.baseboard_fab2(sch_1):p3e_cpu0_pe1_pch_rxp(15)" )
			)
			( signal "P3E_CPU0_PE1_PCH_TXN<8>"
				( objectStatus "@baseboard_fab2_lib.baseboard_fab2(sch_1):p3e_cpu0_pe1_pch_txn(8)" )
			)
			( signal "P3E_CPU0_PE1_PCH_TXN<9>"
				( objectStatus "@baseboard_fab2_lib.baseboard_fab2(sch_1):p3e_cpu0_pe1_pch_txn(9)" )
			)
			( signal "P3E_CPU0_PE1_PCH_TXN<10>"
				( objectStatus "@baseboard_fab2_lib.baseboard_fab2(sch_1):p3e_cpu0_pe1_pch_txn(10)" )
			)
			( signal "P3E_CPU0_PE1_PCH_TXN<11>"
				( objectStatus "@baseboard_fab2_lib.baseboard_fab2(sch_1):p3e_cpu0_pe1_pch_txn(11)" )
			)
			( signal "P3E_CPU0_PE1_PCH_TXN<12>"
				( objectStatus "@baseboard_fab2_lib.baseboard_fab2(sch_1):p3e_cpu0_pe1_pch_txn(12)" )
			)
			( signal "P3E_CPU0_PE1_PCH_TXN<13>"
				( objectStatus "@baseboard_fab2_lib.baseboard_fab2(sch_1):p3e_cpu0_pe1_pch_txn(13)" )
			)
			( signal "P3E_CPU0_PE1_PCH_TXN<14>"
				( objectStatus "@baseboard_fab2_lib.baseboard_fab2(sch_1):p3e_cpu0_pe1_pch_txn(14)" )
			)
			( signal "P3E_CPU0_PE1_PCH_TXN<15>"
				( objectStatus "@baseboard_fab2_lib.baseboard_fab2(sch_1):p3e_cpu0_pe1_pch_txn(15)" )
			)
			( signal "P3E_CPU0_PE1_PCH_TXP<8>"
				( objectStatus "@baseboard_fab2_lib.baseboard_fab2(sch_1):p3e_cpu0_pe1_pch_txp(8)" )
			)
			( signal "P3E_CPU0_PE1_PCH_TXP<9>"
				( objectStatus "@baseboard_fab2_lib.baseboard_fab2(sch_1):p3e_cpu0_pe1_pch_txp(9)" )
			)
			( signal "P3E_CPU0_PE1_PCH_TXP<10>"
				( objectStatus "@baseboard_fab2_lib.baseboard_fab2(sch_1):p3e_cpu0_pe1_pch_txp(10)" )
			)
			( signal "P3E_CPU0_PE1_PCH_TXP<11>"
				( objectStatus "@baseboard_fab2_lib.baseboard_fab2(sch_1):p3e_cpu0_pe1_pch_txp(11)" )
			)
			( signal "P3E_CPU0_PE1_PCH_TXP<12>"
				( objectStatus "@baseboard_fab2_lib.baseboard_fab2(sch_1):p3e_cpu0_pe1_pch_txp(12)" )
			)
			( signal "P3E_CPU0_PE1_PCH_TXP<13>"
				( objectStatus "@baseboard_fab2_lib.baseboard_fab2(sch_1):p3e_cpu0_pe1_pch_txp(13)" )
			)
			( signal "P3E_CPU0_PE1_PCH_TXP<14>"
				( objectStatus "@baseboard_fab2_lib.baseboard_fab2(sch_1):p3e_cpu0_pe1_pch_txp(14)" )
			)
			( signal "P3E_CPU0_PE1_PCH_TXP<15>"
				( objectStatus "@baseboard_fab2_lib.baseboard_fab2(sch_1):p3e_cpu0_pe1_pch_txp(15)" )
			)
			( signal "P3E_CPU0_PE1_SS_RXN<0>"
				( objectStatus "@baseboard_fab2_lib.baseboard_fab2(sch_1):p3e_cpu0_pe1_ss_rxn(0)" )
			)
			( signal "P3E_CPU0_PE1_SS_RXN<1>"
				( objectStatus "@baseboard_fab2_lib.baseboard_fab2(sch_1):p3e_cpu0_pe1_ss_rxn(1)" )
			)
			( signal "P3E_CPU0_PE1_SS_RXN<2>"
				( objectStatus "@baseboard_fab2_lib.baseboard_fab2(sch_1):p3e_cpu0_pe1_ss_rxn(2)" )
			)
			( signal "P3E_CPU0_PE1_SS_RXN<3>"
				( objectStatus "@baseboard_fab2_lib.baseboard_fab2(sch_1):p3e_cpu0_pe1_ss_rxn(3)" )
			)
			( signal "P3E_CPU0_PE1_SS_RXN<4>"
				( objectStatus "@baseboard_fab2_lib.baseboard_fab2(sch_1):p3e_cpu0_pe1_ss_rxn(4)" )
			)
			( signal "P3E_CPU0_PE1_SS_RXN<5>"
				( objectStatus "@baseboard_fab2_lib.baseboard_fab2(sch_1):p3e_cpu0_pe1_ss_rxn(5)" )
			)
			( signal "P3E_CPU0_PE1_SS_RXN<6>"
				( objectStatus "@baseboard_fab2_lib.baseboard_fab2(sch_1):p3e_cpu0_pe1_ss_rxn(6)" )
			)
			( signal "P3E_CPU0_PE1_SS_RXN<7>"
				( objectStatus "@baseboard_fab2_lib.baseboard_fab2(sch_1):p3e_cpu0_pe1_ss_rxn(7)" )
			)
			( signal "P3E_CPU0_PE1_SS_RXP<0>"
				( objectStatus "@baseboard_fab2_lib.baseboard_fab2(sch_1):p3e_cpu0_pe1_ss_rxp(0)" )
			)
			( signal "P3E_CPU0_PE1_SS_RXP<1>"
				( objectStatus "@baseboard_fab2_lib.baseboard_fab2(sch_1):p3e_cpu0_pe1_ss_rxp(1)" )
			)
			( signal "P3E_CPU0_PE1_SS_RXP<2>"
				( objectStatus "@baseboard_fab2_lib.baseboard_fab2(sch_1):p3e_cpu0_pe1_ss_rxp(2)" )
			)
			( signal "P3E_CPU0_PE1_SS_RXP<3>"
				( objectStatus "@baseboard_fab2_lib.baseboard_fab2(sch_1):p3e_cpu0_pe1_ss_rxp(3)" )
			)
			( signal "P3E_CPU0_PE1_SS_RXP<4>"
				( objectStatus "@baseboard_fab2_lib.baseboard_fab2(sch_1):p3e_cpu0_pe1_ss_rxp(4)" )
			)
			( signal "P3E_CPU0_PE1_SS_RXP<5>"
				( objectStatus "@baseboard_fab2_lib.baseboard_fab2(sch_1):p3e_cpu0_pe1_ss_rxp(5)" )
			)
			( signal "P3E_CPU0_PE1_SS_RXP<6>"
				( objectStatus "@baseboard_fab2_lib.baseboard_fab2(sch_1):p3e_cpu0_pe1_ss_rxp(6)" )
			)
			( signal "P3E_CPU0_PE1_SS_RXP<7>"
				( objectStatus "@baseboard_fab2_lib.baseboard_fab2(sch_1):p3e_cpu0_pe1_ss_rxp(7)" )
			)
			( signal "P3E_CPU0_PE1_SS_TXN<0>"
				( objectStatus "@baseboard_fab2_lib.baseboard_fab2(sch_1):p3e_cpu0_pe1_ss_txn(0)" )
			)
			( signal "P3E_CPU0_PE1_SS_TXN<1>"
				( objectStatus "@baseboard_fab2_lib.baseboard_fab2(sch_1):p3e_cpu0_pe1_ss_txn(1)" )
			)
			( signal "P3E_CPU0_PE1_SS_TXN<2>"
				( objectStatus "@baseboard_fab2_lib.baseboard_fab2(sch_1):p3e_cpu0_pe1_ss_txn(2)" )
			)
			( signal "P3E_CPU0_PE1_SS_TXN<3>"
				( objectStatus "@baseboard_fab2_lib.baseboard_fab2(sch_1):p3e_cpu0_pe1_ss_txn(3)" )
			)
			( signal "P3E_CPU0_PE1_SS_TXN<4>"
				( objectStatus "@baseboard_fab2_lib.baseboard_fab2(sch_1):p3e_cpu0_pe1_ss_txn(4)" )
			)
			( signal "P3E_CPU0_PE1_SS_TXN<5>"
				( objectStatus "@baseboard_fab2_lib.baseboard_fab2(sch_1):p3e_cpu0_pe1_ss_txn(5)" )
			)
			( signal "P3E_CPU0_PE1_SS_TXN<6>"
				( objectStatus "@baseboard_fab2_lib.baseboard_fab2(sch_1):p3e_cpu0_pe1_ss_txn(6)" )
			)
			( signal "P3E_CPU0_PE1_SS_TXN<7>"
				( objectStatus "@baseboard_fab2_lib.baseboard_fab2(sch_1):p3e_cpu0_pe1_ss_txn(7)" )
			)
			( signal "P3E_CPU0_PE1_SS_TXP<0>"
				( objectStatus "@baseboard_fab2_lib.baseboard_fab2(sch_1):p3e_cpu0_pe1_ss_txp(0)" )
			)
			( signal "P3E_CPU0_PE1_SS_TXP<1>"
				( objectStatus "@baseboard_fab2_lib.baseboard_fab2(sch_1):p3e_cpu0_pe1_ss_txp(1)" )
			)
			( signal "P3E_CPU0_PE1_SS_TXP<2>"
				( objectStatus "@baseboard_fab2_lib.baseboard_fab2(sch_1):p3e_cpu0_pe1_ss_txp(2)" )
			)
			( signal "P3E_CPU0_PE1_SS_TXP<3>"
				( objectStatus "@baseboard_fab2_lib.baseboard_fab2(sch_1):p3e_cpu0_pe1_ss_txp(3)" )
			)
			( signal "P3E_CPU0_PE1_SS_TXP<4>"
				( objectStatus "@baseboard_fab2_lib.baseboard_fab2(sch_1):p3e_cpu0_pe1_ss_txp(4)" )
			)
			( signal "P3E_CPU0_PE1_SS_TXP<5>"
				( objectStatus "@baseboard_fab2_lib.baseboard_fab2(sch_1):p3e_cpu0_pe1_ss_txp(5)" )
			)
			( signal "P3E_CPU0_PE1_SS_TXP<6>"
				( objectStatus "@baseboard_fab2_lib.baseboard_fab2(sch_1):p3e_cpu0_pe1_ss_txp(6)" )
			)
			( signal "P3E_CPU0_PE1_SS_TXP<7>"
				( objectStatus "@baseboard_fab2_lib.baseboard_fab2(sch_1):p3e_cpu0_pe1_ss_txp(7)" )
			)
			( signal "P3E_CPU0_PE2_SS_RXN<0>"
				( objectStatus "@baseboard_fab2_lib.baseboard_fab2(sch_1):p3e_cpu0_pe2_ss_rxn(0)" )
			)
			( signal "P3E_CPU0_PE2_SS_RXN<1>"
				( objectStatus "@baseboard_fab2_lib.baseboard_fab2(sch_1):p3e_cpu0_pe2_ss_rxn(1)" )
			)
			( signal "P3E_CPU0_PE2_SS_RXN<2>"
				( objectStatus "@baseboard_fab2_lib.baseboard_fab2(sch_1):p3e_cpu0_pe2_ss_rxn(2)" )
			)
			( signal "P3E_CPU0_PE2_SS_RXN<3>"
				( objectStatus "@baseboard_fab2_lib.baseboard_fab2(sch_1):p3e_cpu0_pe2_ss_rxn(3)" )
			)
			( signal "P3E_CPU0_PE2_SS_RXN<4>"
				( objectStatus "@baseboard_fab2_lib.baseboard_fab2(sch_1):p3e_cpu0_pe2_ss_rxn(4)" )
			)
			( signal "P3E_CPU0_PE2_SS_RXN<5>"
				( objectStatus "@baseboard_fab2_lib.baseboard_fab2(sch_1):p3e_cpu0_pe2_ss_rxn(5)" )
			)
			( signal "P3E_CPU0_PE2_SS_RXN<6>"
				( objectStatus "@baseboard_fab2_lib.baseboard_fab2(sch_1):p3e_cpu0_pe2_ss_rxn(6)" )
			)
			( signal "P3E_CPU0_PE2_SS_RXN<7>"
				( objectStatus "@baseboard_fab2_lib.baseboard_fab2(sch_1):p3e_cpu0_pe2_ss_rxn(7)" )
			)
			( signal "P3E_CPU0_PE2_SS_RXN<8>"
				( objectStatus "@baseboard_fab2_lib.baseboard_fab2(sch_1):p3e_cpu0_pe2_ss_rxn(8)" )
			)
			( signal "P3E_CPU0_PE2_SS_RXN<9>"
				( objectStatus "@baseboard_fab2_lib.baseboard_fab2(sch_1):p3e_cpu0_pe2_ss_rxn(9)" )
			)
			( signal "P3E_CPU0_PE2_SS_RXN<10>"
				( objectStatus "@baseboard_fab2_lib.baseboard_fab2(sch_1):p3e_cpu0_pe2_ss_rxn(10)" )
			)
			( signal "P3E_CPU0_PE2_SS_RXN<11>"
				( objectStatus "@baseboard_fab2_lib.baseboard_fab2(sch_1):p3e_cpu0_pe2_ss_rxn(11)" )
			)
			( signal "P3E_CPU0_PE2_SS_RXN<12>"
				( objectStatus "@baseboard_fab2_lib.baseboard_fab2(sch_1):p3e_cpu0_pe2_ss_rxn(12)" )
			)
			( signal "P3E_CPU0_PE2_SS_RXN<13>"
				( objectStatus "@baseboard_fab2_lib.baseboard_fab2(sch_1):p3e_cpu0_pe2_ss_rxn(13)" )
			)
			( signal "P3E_CPU0_PE2_SS_RXN<14>"
				( objectStatus "@baseboard_fab2_lib.baseboard_fab2(sch_1):p3e_cpu0_pe2_ss_rxn(14)" )
			)
			( signal "P3E_CPU0_PE2_SS_RXN<15>"
				( objectStatus "@baseboard_fab2_lib.baseboard_fab2(sch_1):p3e_cpu0_pe2_ss_rxn(15)" )
			)
			( signal "P3E_CPU0_PE2_SS_RXP<0>"
				( objectStatus "@baseboard_fab2_lib.baseboard_fab2(sch_1):p3e_cpu0_pe2_ss_rxp(0)" )
			)
			( signal "P3E_CPU0_PE2_SS_RXP<1>"
				( objectStatus "@baseboard_fab2_lib.baseboard_fab2(sch_1):p3e_cpu0_pe2_ss_rxp(1)" )
			)
			( signal "P3E_CPU0_PE2_SS_RXP<2>"
				( objectStatus "@baseboard_fab2_lib.baseboard_fab2(sch_1):p3e_cpu0_pe2_ss_rxp(2)" )
			)
			( signal "P3E_CPU0_PE2_SS_RXP<3>"
				( objectStatus "@baseboard_fab2_lib.baseboard_fab2(sch_1):p3e_cpu0_pe2_ss_rxp(3)" )
			)
			( signal "P3E_CPU0_PE2_SS_RXP<4>"
				( objectStatus "@baseboard_fab2_lib.baseboard_fab2(sch_1):p3e_cpu0_pe2_ss_rxp(4)" )
			)
			( signal "P3E_CPU0_PE2_SS_RXP<5>"
				( objectStatus "@baseboard_fab2_lib.baseboard_fab2(sch_1):p3e_cpu0_pe2_ss_rxp(5)" )
			)
			( signal "P3E_CPU0_PE2_SS_RXP<6>"
				( objectStatus "@baseboard_fab2_lib.baseboard_fab2(sch_1):p3e_cpu0_pe2_ss_rxp(6)" )
			)
			( signal "P3E_CPU0_PE2_SS_RXP<7>"
				( objectStatus "@baseboard_fab2_lib.baseboard_fab2(sch_1):p3e_cpu0_pe2_ss_rxp(7)" )
			)
			( signal "P3E_CPU0_PE2_SS_RXP<8>"
				( objectStatus "@baseboard_fab2_lib.baseboard_fab2(sch_1):p3e_cpu0_pe2_ss_rxp(8)" )
			)
			( signal "P3E_CPU0_PE2_SS_RXP<9>"
				( objectStatus "@baseboard_fab2_lib.baseboard_fab2(sch_1):p3e_cpu0_pe2_ss_rxp(9)" )
			)
			( signal "P3E_CPU0_PE2_SS_RXP<10>"
				( objectStatus "@baseboard_fab2_lib.baseboard_fab2(sch_1):p3e_cpu0_pe2_ss_rxp(10)" )
			)
			( signal "P3E_CPU0_PE2_SS_RXP<11>"
				( objectStatus "@baseboard_fab2_lib.baseboard_fab2(sch_1):p3e_cpu0_pe2_ss_rxp(11)" )
			)
			( signal "P3E_CPU0_PE2_SS_RXP<12>"
				( objectStatus "@baseboard_fab2_lib.baseboard_fab2(sch_1):p3e_cpu0_pe2_ss_rxp(12)" )
			)
			( signal "P3E_CPU0_PE2_SS_RXP<13>"
				( objectStatus "@baseboard_fab2_lib.baseboard_fab2(sch_1):p3e_cpu0_pe2_ss_rxp(13)" )
			)
			( signal "P3E_CPU0_PE2_SS_RXP<14>"
				( objectStatus "@baseboard_fab2_lib.baseboard_fab2(sch_1):p3e_cpu0_pe2_ss_rxp(14)" )
			)
			( signal "P3E_CPU0_PE2_SS_RXP<15>"
				( objectStatus "@baseboard_fab2_lib.baseboard_fab2(sch_1):p3e_cpu0_pe2_ss_rxp(15)" )
			)
			( signal "P3E_CPU0_PE2_SS_TXN<0>"
				( objectStatus "@baseboard_fab2_lib.baseboard_fab2(sch_1):p3e_cpu0_pe2_ss_txn(0)" )
			)
			( signal "P3E_CPU0_PE2_SS_TXN<1>"
				( objectStatus "@baseboard_fab2_lib.baseboard_fab2(sch_1):p3e_cpu0_pe2_ss_txn(1)" )
			)
			( signal "P3E_CPU0_PE2_SS_TXN<2>"
				( objectStatus "@baseboard_fab2_lib.baseboard_fab2(sch_1):p3e_cpu0_pe2_ss_txn(2)" )
			)
			( signal "P3E_CPU0_PE2_SS_TXN<3>"
				( objectStatus "@baseboard_fab2_lib.baseboard_fab2(sch_1):p3e_cpu0_pe2_ss_txn(3)" )
			)
			( signal "P3E_CPU0_PE2_SS_TXN<4>"
				( objectStatus "@baseboard_fab2_lib.baseboard_fab2(sch_1):p3e_cpu0_pe2_ss_txn(4)" )
			)
			( signal "P3E_CPU0_PE2_SS_TXN<5>"
				( objectStatus "@baseboard_fab2_lib.baseboard_fab2(sch_1):p3e_cpu0_pe2_ss_txn(5)" )
			)
			( signal "P3E_CPU0_PE2_SS_TXN<6>"
				( objectStatus "@baseboard_fab2_lib.baseboard_fab2(sch_1):p3e_cpu0_pe2_ss_txn(6)" )
			)
			( signal "P3E_CPU0_PE2_SS_TXN<7>"
				( objectStatus "@baseboard_fab2_lib.baseboard_fab2(sch_1):p3e_cpu0_pe2_ss_txn(7)" )
			)
			( signal "P3E_CPU0_PE2_SS_TXN<8>"
				( objectStatus "@baseboard_fab2_lib.baseboard_fab2(sch_1):p3e_cpu0_pe2_ss_txn(8)" )
			)
			( signal "P3E_CPU0_PE2_SS_TXN<9>"
				( objectStatus "@baseboard_fab2_lib.baseboard_fab2(sch_1):p3e_cpu0_pe2_ss_txn(9)" )
			)
			( signal "P3E_CPU0_PE2_SS_TXN<10>"
				( objectStatus "@baseboard_fab2_lib.baseboard_fab2(sch_1):p3e_cpu0_pe2_ss_txn(10)" )
			)
			( signal "P3E_CPU0_PE2_SS_TXN<11>"
				( objectStatus "@baseboard_fab2_lib.baseboard_fab2(sch_1):p3e_cpu0_pe2_ss_txn(11)" )
			)
			( signal "P3E_CPU0_PE2_SS_TXN<12>"
				( objectStatus "@baseboard_fab2_lib.baseboard_fab2(sch_1):p3e_cpu0_pe2_ss_txn(12)" )
			)
			( signal "P3E_CPU0_PE2_SS_TXN<13>"
				( objectStatus "@baseboard_fab2_lib.baseboard_fab2(sch_1):p3e_cpu0_pe2_ss_txn(13)" )
			)
			( signal "P3E_CPU0_PE2_SS_TXN<14>"
				( objectStatus "@baseboard_fab2_lib.baseboard_fab2(sch_1):p3e_cpu0_pe2_ss_txn(14)" )
			)
			( signal "P3E_CPU0_PE2_SS_TXN<15>"
				( objectStatus "@baseboard_fab2_lib.baseboard_fab2(sch_1):p3e_cpu0_pe2_ss_txn(15)" )
			)
			( signal "P3E_CPU0_PE2_SS_TXP<0>"
				( objectStatus "@baseboard_fab2_lib.baseboard_fab2(sch_1):p3e_cpu0_pe2_ss_txp(0)" )
			)
			( signal "P3E_CPU0_PE2_SS_TXP<1>"
				( objectStatus "@baseboard_fab2_lib.baseboard_fab2(sch_1):p3e_cpu0_pe2_ss_txp(1)" )
			)
			( signal "P3E_CPU0_PE2_SS_TXP<2>"
				( objectStatus "@baseboard_fab2_lib.baseboard_fab2(sch_1):p3e_cpu0_pe2_ss_txp(2)" )
			)
			( signal "P3E_CPU0_PE2_SS_TXP<3>"
				( objectStatus "@baseboard_fab2_lib.baseboard_fab2(sch_1):p3e_cpu0_pe2_ss_txp(3)" )
			)
			( signal "P3E_CPU0_PE2_SS_TXP<4>"
				( objectStatus "@baseboard_fab2_lib.baseboard_fab2(sch_1):p3e_cpu0_pe2_ss_txp(4)" )
			)
			( signal "P3E_CPU0_PE2_SS_TXP<5>"
				( objectStatus "@baseboard_fab2_lib.baseboard_fab2(sch_1):p3e_cpu0_pe2_ss_txp(5)" )
			)
			( signal "P3E_CPU0_PE2_SS_TXP<6>"
				( objectStatus "@baseboard_fab2_lib.baseboard_fab2(sch_1):p3e_cpu0_pe2_ss_txp(6)" )
			)
			( signal "P3E_CPU0_PE2_SS_TXP<7>"
				( objectStatus "@baseboard_fab2_lib.baseboard_fab2(sch_1):p3e_cpu0_pe2_ss_txp(7)" )
			)
			( signal "P3E_CPU0_PE2_SS_TXP<8>"
				( objectStatus "@baseboard_fab2_lib.baseboard_fab2(sch_1):p3e_cpu0_pe2_ss_txp(8)" )
			)
			( signal "P3E_CPU0_PE2_SS_TXP<9>"
				( objectStatus "@baseboard_fab2_lib.baseboard_fab2(sch_1):p3e_cpu0_pe2_ss_txp(9)" )
			)
			( signal "P3E_CPU0_PE2_SS_TXP<10>"
				( objectStatus "@baseboard_fab2_lib.baseboard_fab2(sch_1):p3e_cpu0_pe2_ss_txp(10)" )
			)
			( signal "P3E_CPU0_PE2_SS_TXP<11>"
				( objectStatus "@baseboard_fab2_lib.baseboard_fab2(sch_1):p3e_cpu0_pe2_ss_txp(11)" )
			)
			( signal "P3E_CPU0_PE2_SS_TXP<12>"
				( objectStatus "@baseboard_fab2_lib.baseboard_fab2(sch_1):p3e_cpu0_pe2_ss_txp(12)" )
			)
			( signal "P3E_CPU0_PE2_SS_TXP<13>"
				( objectStatus "@baseboard_fab2_lib.baseboard_fab2(sch_1):p3e_cpu0_pe2_ss_txp(13)" )
			)
			( signal "P3E_CPU0_PE2_SS_TXP<14>"
				( objectStatus "@baseboard_fab2_lib.baseboard_fab2(sch_1):p3e_cpu0_pe2_ss_txp(14)" )
			)
			( signal "P3E_CPU0_PE2_SS_TXP<15>"
				( objectStatus "@baseboard_fab2_lib.baseboard_fab2(sch_1):p3e_cpu0_pe2_ss_txp(15)" )
			)
			( signal "P3E_CPU0_PE3_OCP_RXN<0>"
				( objectStatus "@baseboard_fab2_lib.baseboard_fab2(sch_1):p3e_cpu0_pe3_ocp_rxn(0)" )
			)
			( signal "P3E_CPU0_PE3_OCP_RXN<1>"
				( objectStatus "@baseboard_fab2_lib.baseboard_fab2(sch_1):p3e_cpu0_pe3_ocp_rxn(1)" )
			)
			( signal "P3E_CPU0_PE3_OCP_RXN<2>"
				( objectStatus "@baseboard_fab2_lib.baseboard_fab2(sch_1):p3e_cpu0_pe3_ocp_rxn(2)" )
			)
			( signal "P3E_CPU0_PE3_OCP_RXN<3>"
				( objectStatus "@baseboard_fab2_lib.baseboard_fab2(sch_1):p3e_cpu0_pe3_ocp_rxn(3)" )
			)
			( signal "P3E_CPU0_PE3_OCP_RXN<4>"
				( objectStatus "@baseboard_fab2_lib.baseboard_fab2(sch_1):p3e_cpu0_pe3_ocp_rxn(4)" )
			)
			( signal "P3E_CPU0_PE3_OCP_RXN<5>"
				( objectStatus "@baseboard_fab2_lib.baseboard_fab2(sch_1):p3e_cpu0_pe3_ocp_rxn(5)" )
			)
			( signal "P3E_CPU0_PE3_OCP_RXN<6>"
				( objectStatus "@baseboard_fab2_lib.baseboard_fab2(sch_1):p3e_cpu0_pe3_ocp_rxn(6)" )
			)
			( signal "P3E_CPU0_PE3_OCP_RXN<7>"
				( objectStatus "@baseboard_fab2_lib.baseboard_fab2(sch_1):p3e_cpu0_pe3_ocp_rxn(7)" )
			)
			( signal "P3E_CPU0_PE3_OCP_RXN<8>"
				( objectStatus "@baseboard_fab2_lib.baseboard_fab2(sch_1):p3e_cpu0_pe3_ocp_rxn(8)" )
			)
			( signal "P3E_CPU0_PE3_OCP_RXN<9>"
				( objectStatus "@baseboard_fab2_lib.baseboard_fab2(sch_1):p3e_cpu0_pe3_ocp_rxn(9)" )
			)
			( signal "P3E_CPU0_PE3_OCP_RXN<10>"
				( objectStatus "@baseboard_fab2_lib.baseboard_fab2(sch_1):p3e_cpu0_pe3_ocp_rxn(10)" )
			)
			( signal "P3E_CPU0_PE3_OCP_RXN<11>"
				( objectStatus "@baseboard_fab2_lib.baseboard_fab2(sch_1):p3e_cpu0_pe3_ocp_rxn(11)" )
			)
			( signal "P3E_CPU0_PE3_OCP_RXN<12>"
				( objectStatus "@baseboard_fab2_lib.baseboard_fab2(sch_1):p3e_cpu0_pe3_ocp_rxn(12)" )
			)
			( signal "P3E_CPU0_PE3_OCP_RXN<13>"
				( objectStatus "@baseboard_fab2_lib.baseboard_fab2(sch_1):p3e_cpu0_pe3_ocp_rxn(13)" )
			)
			( signal "P3E_CPU0_PE3_OCP_RXN<14>"
				( objectStatus "@baseboard_fab2_lib.baseboard_fab2(sch_1):p3e_cpu0_pe3_ocp_rxn(14)" )
			)
			( signal "P3E_CPU0_PE3_OCP_RXN<15>"
				( objectStatus "@baseboard_fab2_lib.baseboard_fab2(sch_1):p3e_cpu0_pe3_ocp_rxn(15)" )
			)
			( signal "P3E_CPU0_PE3_OCP_RXP<0>"
				( objectStatus "@baseboard_fab2_lib.baseboard_fab2(sch_1):p3e_cpu0_pe3_ocp_rxp(0)" )
			)
			( signal "P3E_CPU0_PE3_OCP_RXP<1>"
				( objectStatus "@baseboard_fab2_lib.baseboard_fab2(sch_1):p3e_cpu0_pe3_ocp_rxp(1)" )
			)
			( signal "P3E_CPU0_PE3_OCP_RXP<2>"
				( objectStatus "@baseboard_fab2_lib.baseboard_fab2(sch_1):p3e_cpu0_pe3_ocp_rxp(2)" )
			)
			( signal "P3E_CPU0_PE3_OCP_RXP<3>"
				( objectStatus "@baseboard_fab2_lib.baseboard_fab2(sch_1):p3e_cpu0_pe3_ocp_rxp(3)" )
			)
			( signal "P3E_CPU0_PE3_OCP_RXP<4>"
				( objectStatus "@baseboard_fab2_lib.baseboard_fab2(sch_1):p3e_cpu0_pe3_ocp_rxp(4)" )
			)
			( signal "P3E_CPU0_PE3_OCP_RXP<5>"
				( objectStatus "@baseboard_fab2_lib.baseboard_fab2(sch_1):p3e_cpu0_pe3_ocp_rxp(5)" )
			)
			( signal "P3E_CPU0_PE3_OCP_RXP<6>"
				( objectStatus "@baseboard_fab2_lib.baseboard_fab2(sch_1):p3e_cpu0_pe3_ocp_rxp(6)" )
			)
			( signal "P3E_CPU0_PE3_OCP_RXP<7>"
				( objectStatus "@baseboard_fab2_lib.baseboard_fab2(sch_1):p3e_cpu0_pe3_ocp_rxp(7)" )
			)
			( signal "P3E_CPU0_PE3_OCP_RXP<8>"
				( objectStatus "@baseboard_fab2_lib.baseboard_fab2(sch_1):p3e_cpu0_pe3_ocp_rxp(8)" )
			)
			( signal "P3E_CPU0_PE3_OCP_RXP<9>"
				( objectStatus "@baseboard_fab2_lib.baseboard_fab2(sch_1):p3e_cpu0_pe3_ocp_rxp(9)" )
			)
			( signal "P3E_CPU0_PE3_OCP_RXP<10>"
				( objectStatus "@baseboard_fab2_lib.baseboard_fab2(sch_1):p3e_cpu0_pe3_ocp_rxp(10)" )
			)
			( signal "P3E_CPU0_PE3_OCP_RXP<11>"
				( objectStatus "@baseboard_fab2_lib.baseboard_fab2(sch_1):p3e_cpu0_pe3_ocp_rxp(11)" )
			)
			( signal "P3E_CPU0_PE3_OCP_RXP<12>"
				( objectStatus "@baseboard_fab2_lib.baseboard_fab2(sch_1):p3e_cpu0_pe3_ocp_rxp(12)" )
			)
			( signal "P3E_CPU0_PE3_OCP_RXP<13>"
				( objectStatus "@baseboard_fab2_lib.baseboard_fab2(sch_1):p3e_cpu0_pe3_ocp_rxp(13)" )
			)
			( signal "P3E_CPU0_PE3_OCP_RXP<14>"
				( objectStatus "@baseboard_fab2_lib.baseboard_fab2(sch_1):p3e_cpu0_pe3_ocp_rxp(14)" )
			)
			( signal "P3E_CPU0_PE3_OCP_RXP<15>"
				( objectStatus "@baseboard_fab2_lib.baseboard_fab2(sch_1):p3e_cpu0_pe3_ocp_rxp(15)" )
			)
			( signal "P3E_CPU0_PE3_OCP_TXN<0>"
				( objectStatus "@baseboard_fab2_lib.baseboard_fab2(sch_1):p3e_cpu0_pe3_ocp_txn(0)" )
			)
			( signal "P3E_CPU0_PE3_OCP_TXN<1>"
				( objectStatus "@baseboard_fab2_lib.baseboard_fab2(sch_1):p3e_cpu0_pe3_ocp_txn(1)" )
			)
			( signal "P3E_CPU0_PE3_OCP_TXN<2>"
				( objectStatus "@baseboard_fab2_lib.baseboard_fab2(sch_1):p3e_cpu0_pe3_ocp_txn(2)" )
			)
			( signal "P3E_CPU0_PE3_OCP_TXN<3>"
				( objectStatus "@baseboard_fab2_lib.baseboard_fab2(sch_1):p3e_cpu0_pe3_ocp_txn(3)" )
			)
			( signal "P3E_CPU0_PE3_OCP_TXN<4>"
				( objectStatus "@baseboard_fab2_lib.baseboard_fab2(sch_1):p3e_cpu0_pe3_ocp_txn(4)" )
			)
			( signal "P3E_CPU0_PE3_OCP_TXN<5>"
				( objectStatus "@baseboard_fab2_lib.baseboard_fab2(sch_1):p3e_cpu0_pe3_ocp_txn(5)" )
			)
			( signal "P3E_CPU0_PE3_OCP_TXN<6>"
				( objectStatus "@baseboard_fab2_lib.baseboard_fab2(sch_1):p3e_cpu0_pe3_ocp_txn(6)" )
			)
			( signal "P3E_CPU0_PE3_OCP_TXN<7>"
				( objectStatus "@baseboard_fab2_lib.baseboard_fab2(sch_1):p3e_cpu0_pe3_ocp_txn(7)" )
			)
			( signal "P3E_CPU0_PE3_OCP_TXN<8>"
				( objectStatus "@baseboard_fab2_lib.baseboard_fab2(sch_1):p3e_cpu0_pe3_ocp_txn(8)" )
			)
			( signal "P3E_CPU0_PE3_OCP_TXN<9>"
				( objectStatus "@baseboard_fab2_lib.baseboard_fab2(sch_1):p3e_cpu0_pe3_ocp_txn(9)" )
			)
			( signal "P3E_CPU0_PE3_OCP_TXN<10>"
				( objectStatus "@baseboard_fab2_lib.baseboard_fab2(sch_1):p3e_cpu0_pe3_ocp_txn(10)" )
			)
			( signal "P3E_CPU0_PE3_OCP_TXN<11>"
				( objectStatus "@baseboard_fab2_lib.baseboard_fab2(sch_1):p3e_cpu0_pe3_ocp_txn(11)" )
			)
			( signal "P3E_CPU0_PE3_OCP_TXN<12>"
				( objectStatus "@baseboard_fab2_lib.baseboard_fab2(sch_1):p3e_cpu0_pe3_ocp_txn(12)" )
			)
			( signal "P3E_CPU0_PE3_OCP_TXN<13>"
				( objectStatus "@baseboard_fab2_lib.baseboard_fab2(sch_1):p3e_cpu0_pe3_ocp_txn(13)" )
			)
			( signal "P3E_CPU0_PE3_OCP_TXN<14>"
				( objectStatus "@baseboard_fab2_lib.baseboard_fab2(sch_1):p3e_cpu0_pe3_ocp_txn(14)" )
			)
			( signal "P3E_CPU0_PE3_OCP_TXN<15>"
				( objectStatus "@baseboard_fab2_lib.baseboard_fab2(sch_1):p3e_cpu0_pe3_ocp_txn(15)" )
			)
			( signal "P3E_CPU0_PE3_OCP_TXP<0>"
				( objectStatus "@baseboard_fab2_lib.baseboard_fab2(sch_1):p3e_cpu0_pe3_ocp_txp(0)" )
			)
			( signal "P3E_CPU0_PE3_OCP_TXP<1>"
				( objectStatus "@baseboard_fab2_lib.baseboard_fab2(sch_1):p3e_cpu0_pe3_ocp_txp(1)" )
			)
			( signal "P3E_CPU0_PE3_OCP_TXP<2>"
				( objectStatus "@baseboard_fab2_lib.baseboard_fab2(sch_1):p3e_cpu0_pe3_ocp_txp(2)" )
			)
			( signal "P3E_CPU0_PE3_OCP_TXP<3>"
				( objectStatus "@baseboard_fab2_lib.baseboard_fab2(sch_1):p3e_cpu0_pe3_ocp_txp(3)" )
			)
			( signal "P3E_CPU0_PE3_OCP_TXP<4>"
				( objectStatus "@baseboard_fab2_lib.baseboard_fab2(sch_1):p3e_cpu0_pe3_ocp_txp(4)" )
			)
			( signal "P3E_CPU0_PE3_OCP_TXP<5>"
				( objectStatus "@baseboard_fab2_lib.baseboard_fab2(sch_1):p3e_cpu0_pe3_ocp_txp(5)" )
			)
			( signal "P3E_CPU0_PE3_OCP_TXP<6>"
				( objectStatus "@baseboard_fab2_lib.baseboard_fab2(sch_1):p3e_cpu0_pe3_ocp_txp(6)" )
			)
			( signal "P3E_CPU0_PE3_OCP_TXP<7>"
				( objectStatus "@baseboard_fab2_lib.baseboard_fab2(sch_1):p3e_cpu0_pe3_ocp_txp(7)" )
			)
			( signal "P3E_CPU0_PE3_OCP_TXP<8>"
				( objectStatus "@baseboard_fab2_lib.baseboard_fab2(sch_1):p3e_cpu0_pe3_ocp_txp(8)" )
			)
			( signal "P3E_CPU0_PE3_OCP_TXP<9>"
				( objectStatus "@baseboard_fab2_lib.baseboard_fab2(sch_1):p3e_cpu0_pe3_ocp_txp(9)" )
			)
			( signal "P3E_CPU0_PE3_OCP_TXP<10>"
				( objectStatus "@baseboard_fab2_lib.baseboard_fab2(sch_1):p3e_cpu0_pe3_ocp_txp(10)" )
			)
			( signal "P3E_CPU0_PE3_OCP_TXP<11>"
				( objectStatus "@baseboard_fab2_lib.baseboard_fab2(sch_1):p3e_cpu0_pe3_ocp_txp(11)" )
			)
			( signal "P3E_CPU0_PE3_OCP_TXP<12>"
				( objectStatus "@baseboard_fab2_lib.baseboard_fab2(sch_1):p3e_cpu0_pe3_ocp_txp(12)" )
			)
			( signal "P3E_CPU0_PE3_OCP_TXP<13>"
				( objectStatus "@baseboard_fab2_lib.baseboard_fab2(sch_1):p3e_cpu0_pe3_ocp_txp(13)" )
			)
			( signal "P3E_CPU0_PE3_OCP_TXP<14>"
				( objectStatus "@baseboard_fab2_lib.baseboard_fab2(sch_1):p3e_cpu0_pe3_ocp_txp(14)" )
			)
			( signal "P3E_CPU0_PE3_OCP_TXP<15>"
				( objectStatus "@baseboard_fab2_lib.baseboard_fab2(sch_1):p3e_cpu0_pe3_ocp_txp(15)" )
			)
			( signal "UPI_CPU0_CPU1_P0P0_DN<0>"
				( objectStatus "@baseboard_fab2_lib.baseboard_fab2(sch_1):upi_cpu0_cpu1_p0p0_dn(0)" )
			)
			( signal "UPI_CPU0_CPU1_P0P0_DN<1>"
				( objectStatus "@baseboard_fab2_lib.baseboard_fab2(sch_1):upi_cpu0_cpu1_p0p0_dn(1)" )
			)
			( signal "UPI_CPU0_CPU1_P0P0_DN<2>"
				( objectStatus "@baseboard_fab2_lib.baseboard_fab2(sch_1):upi_cpu0_cpu1_p0p0_dn(2)" )
			)
			( signal "UPI_CPU0_CPU1_P0P0_DN<3>"
				( objectStatus "@baseboard_fab2_lib.baseboard_fab2(sch_1):upi_cpu0_cpu1_p0p0_dn(3)" )
			)
			( signal "UPI_CPU0_CPU1_P0P0_DN<4>"
				( objectStatus "@baseboard_fab2_lib.baseboard_fab2(sch_1):upi_cpu0_cpu1_p0p0_dn(4)" )
			)
			( signal "UPI_CPU0_CPU1_P0P0_DN<5>"
				( objectStatus "@baseboard_fab2_lib.baseboard_fab2(sch_1):upi_cpu0_cpu1_p0p0_dn(5)" )
			)
			( signal "UPI_CPU0_CPU1_P0P0_DN<6>"
				( objectStatus "@baseboard_fab2_lib.baseboard_fab2(sch_1):upi_cpu0_cpu1_p0p0_dn(6)" )
			)
			( signal "UPI_CPU0_CPU1_P0P0_DN<7>"
				( objectStatus "@baseboard_fab2_lib.baseboard_fab2(sch_1):upi_cpu0_cpu1_p0p0_dn(7)" )
			)
			( signal "UPI_CPU0_CPU1_P0P0_DN<8>"
				( objectStatus "@baseboard_fab2_lib.baseboard_fab2(sch_1):upi_cpu0_cpu1_p0p0_dn(8)" )
			)
			( signal "UPI_CPU0_CPU1_P0P0_DN<9>"
				( objectStatus "@baseboard_fab2_lib.baseboard_fab2(sch_1):upi_cpu0_cpu1_p0p0_dn(9)" )
			)
			( signal "UPI_CPU0_CPU1_P0P0_DN<10>"
				( objectStatus "@baseboard_fab2_lib.baseboard_fab2(sch_1):upi_cpu0_cpu1_p0p0_dn(10)" )
			)
			( signal "UPI_CPU0_CPU1_P0P0_DN<11>"
				( objectStatus "@baseboard_fab2_lib.baseboard_fab2(sch_1):upi_cpu0_cpu1_p0p0_dn(11)" )
			)
			( signal "UPI_CPU0_CPU1_P0P0_DN<12>"
				( objectStatus "@baseboard_fab2_lib.baseboard_fab2(sch_1):upi_cpu0_cpu1_p0p0_dn(12)" )
			)
			( signal "UPI_CPU0_CPU1_P0P0_DN<13>"
				( objectStatus "@baseboard_fab2_lib.baseboard_fab2(sch_1):upi_cpu0_cpu1_p0p0_dn(13)" )
			)
			( signal "UPI_CPU0_CPU1_P0P0_DN<14>"
				( objectStatus "@baseboard_fab2_lib.baseboard_fab2(sch_1):upi_cpu0_cpu1_p0p0_dn(14)" )
			)
			( signal "UPI_CPU0_CPU1_P0P0_DN<15>"
				( objectStatus "@baseboard_fab2_lib.baseboard_fab2(sch_1):upi_cpu0_cpu1_p0p0_dn(15)" )
			)
			( signal "UPI_CPU0_CPU1_P0P0_DN<16>"
				( objectStatus "@baseboard_fab2_lib.baseboard_fab2(sch_1):upi_cpu0_cpu1_p0p0_dn(16)" )
			)
			( signal "UPI_CPU0_CPU1_P0P0_DN<17>"
				( objectStatus "@baseboard_fab2_lib.baseboard_fab2(sch_1):upi_cpu0_cpu1_p0p0_dn(17)" )
			)
			( signal "UPI_CPU0_CPU1_P0P0_DN<18>"
				( objectStatus "@baseboard_fab2_lib.baseboard_fab2(sch_1):upi_cpu0_cpu1_p0p0_dn(18)" )
			)
			( signal "UPI_CPU0_CPU1_P0P0_DN<19>"
				( objectStatus "@baseboard_fab2_lib.baseboard_fab2(sch_1):upi_cpu0_cpu1_p0p0_dn(19)" )
			)
			( signal "UPI_CPU0_CPU1_P0P0_DP<0>"
				( objectStatus "@baseboard_fab2_lib.baseboard_fab2(sch_1):upi_cpu0_cpu1_p0p0_dp(0)" )
			)
			( signal "UPI_CPU0_CPU1_P0P0_DP<1>"
				( objectStatus "@baseboard_fab2_lib.baseboard_fab2(sch_1):upi_cpu0_cpu1_p0p0_dp(1)" )
			)
			( signal "UPI_CPU0_CPU1_P0P0_DP<2>"
				( objectStatus "@baseboard_fab2_lib.baseboard_fab2(sch_1):upi_cpu0_cpu1_p0p0_dp(2)" )
			)
			( signal "UPI_CPU0_CPU1_P0P0_DP<3>"
				( objectStatus "@baseboard_fab2_lib.baseboard_fab2(sch_1):upi_cpu0_cpu1_p0p0_dp(3)" )
			)
			( signal "UPI_CPU0_CPU1_P0P0_DP<4>"
				( objectStatus "@baseboard_fab2_lib.baseboard_fab2(sch_1):upi_cpu0_cpu1_p0p0_dp(4)" )
			)
			( signal "UPI_CPU0_CPU1_P0P0_DP<5>"
				( objectStatus "@baseboard_fab2_lib.baseboard_fab2(sch_1):upi_cpu0_cpu1_p0p0_dp(5)" )
			)
			( signal "UPI_CPU0_CPU1_P0P0_DP<6>"
				( objectStatus "@baseboard_fab2_lib.baseboard_fab2(sch_1):upi_cpu0_cpu1_p0p0_dp(6)" )
			)
			( signal "UPI_CPU0_CPU1_P0P0_DP<7>"
				( objectStatus "@baseboard_fab2_lib.baseboard_fab2(sch_1):upi_cpu0_cpu1_p0p0_dp(7)" )
			)
			( signal "UPI_CPU0_CPU1_P0P0_DP<8>"
				( objectStatus "@baseboard_fab2_lib.baseboard_fab2(sch_1):upi_cpu0_cpu1_p0p0_dp(8)" )
			)
			( signal "UPI_CPU0_CPU1_P0P0_DP<9>"
				( objectStatus "@baseboard_fab2_lib.baseboard_fab2(sch_1):upi_cpu0_cpu1_p0p0_dp(9)" )
			)
			( signal "UPI_CPU0_CPU1_P0P0_DP<10>"
				( objectStatus "@baseboard_fab2_lib.baseboard_fab2(sch_1):upi_cpu0_cpu1_p0p0_dp(10)" )
			)
			( signal "UPI_CPU0_CPU1_P0P0_DP<11>"
				( objectStatus "@baseboard_fab2_lib.baseboard_fab2(sch_1):upi_cpu0_cpu1_p0p0_dp(11)" )
			)
			( signal "UPI_CPU0_CPU1_P0P0_DP<12>"
				( objectStatus "@baseboard_fab2_lib.baseboard_fab2(sch_1):upi_cpu0_cpu1_p0p0_dp(12)" )
			)
			( signal "UPI_CPU0_CPU1_P0P0_DP<13>"
				( objectStatus "@baseboard_fab2_lib.baseboard_fab2(sch_1):upi_cpu0_cpu1_p0p0_dp(13)" )
			)
			( signal "UPI_CPU0_CPU1_P0P0_DP<14>"
				( objectStatus "@baseboard_fab2_lib.baseboard_fab2(sch_1):upi_cpu0_cpu1_p0p0_dp(14)" )
			)
			( signal "UPI_CPU0_CPU1_P0P0_DP<15>"
				( objectStatus "@baseboard_fab2_lib.baseboard_fab2(sch_1):upi_cpu0_cpu1_p0p0_dp(15)" )
			)
			( signal "UPI_CPU0_CPU1_P0P0_DP<16>"
				( objectStatus "@baseboard_fab2_lib.baseboard_fab2(sch_1):upi_cpu0_cpu1_p0p0_dp(16)" )
			)
			( signal "UPI_CPU0_CPU1_P0P0_DP<17>"
				( objectStatus "@baseboard_fab2_lib.baseboard_fab2(sch_1):upi_cpu0_cpu1_p0p0_dp(17)" )
			)
			( signal "UPI_CPU0_CPU1_P0P0_DP<18>"
				( objectStatus "@baseboard_fab2_lib.baseboard_fab2(sch_1):upi_cpu0_cpu1_p0p0_dp(18)" )
			)
			( signal "UPI_CPU0_CPU1_P0P0_DP<19>"
				( objectStatus "@baseboard_fab2_lib.baseboard_fab2(sch_1):upi_cpu0_cpu1_p0p0_dp(19)" )
			)
			( signal "UPI_CPU1_CPU0_P0P0_DN<0>"
				( objectStatus "@baseboard_fab2_lib.baseboard_fab2(sch_1):upi_cpu1_cpu0_p0p0_dn(0)" )
			)
			( signal "UPI_CPU1_CPU0_P0P0_DN<1>"
				( objectStatus "@baseboard_fab2_lib.baseboard_fab2(sch_1):upi_cpu1_cpu0_p0p0_dn(1)" )
			)
			( signal "UPI_CPU1_CPU0_P0P0_DN<2>"
				( objectStatus "@baseboard_fab2_lib.baseboard_fab2(sch_1):upi_cpu1_cpu0_p0p0_dn(2)" )
			)
			( signal "UPI_CPU1_CPU0_P0P0_DN<3>"
				( objectStatus "@baseboard_fab2_lib.baseboard_fab2(sch_1):upi_cpu1_cpu0_p0p0_dn(3)" )
			)
			( signal "UPI_CPU1_CPU0_P0P0_DN<4>"
				( objectStatus "@baseboard_fab2_lib.baseboard_fab2(sch_1):upi_cpu1_cpu0_p0p0_dn(4)" )
			)
			( signal "UPI_CPU1_CPU0_P0P0_DN<5>"
				( objectStatus "@baseboard_fab2_lib.baseboard_fab2(sch_1):upi_cpu1_cpu0_p0p0_dn(5)" )
			)
			( signal "UPI_CPU1_CPU0_P0P0_DN<6>"
				( objectStatus "@baseboard_fab2_lib.baseboard_fab2(sch_1):upi_cpu1_cpu0_p0p0_dn(6)" )
			)
			( signal "UPI_CPU1_CPU0_P0P0_DN<7>"
				( objectStatus "@baseboard_fab2_lib.baseboard_fab2(sch_1):upi_cpu1_cpu0_p0p0_dn(7)" )
			)
			( signal "UPI_CPU1_CPU0_P0P0_DN<8>"
				( objectStatus "@baseboard_fab2_lib.baseboard_fab2(sch_1):upi_cpu1_cpu0_p0p0_dn(8)" )
			)
			( signal "UPI_CPU1_CPU0_P0P0_DN<9>"
				( objectStatus "@baseboard_fab2_lib.baseboard_fab2(sch_1):upi_cpu1_cpu0_p0p0_dn(9)" )
			)
			( signal "UPI_CPU1_CPU0_P0P0_DN<10>"
				( objectStatus "@baseboard_fab2_lib.baseboard_fab2(sch_1):upi_cpu1_cpu0_p0p0_dn(10)" )
			)
			( signal "UPI_CPU1_CPU0_P0P0_DN<11>"
				( objectStatus "@baseboard_fab2_lib.baseboard_fab2(sch_1):upi_cpu1_cpu0_p0p0_dn(11)" )
			)
			( signal "UPI_CPU1_CPU0_P0P0_DN<12>"
				( objectStatus "@baseboard_fab2_lib.baseboard_fab2(sch_1):upi_cpu1_cpu0_p0p0_dn(12)" )
			)
			( signal "UPI_CPU1_CPU0_P0P0_DN<13>"
				( objectStatus "@baseboard_fab2_lib.baseboard_fab2(sch_1):upi_cpu1_cpu0_p0p0_dn(13)" )
			)
			( signal "UPI_CPU1_CPU0_P0P0_DN<14>"
				( objectStatus "@baseboard_fab2_lib.baseboard_fab2(sch_1):upi_cpu1_cpu0_p0p0_dn(14)" )
			)
			( signal "UPI_CPU1_CPU0_P0P0_DN<15>"
				( objectStatus "@baseboard_fab2_lib.baseboard_fab2(sch_1):upi_cpu1_cpu0_p0p0_dn(15)" )
			)
			( signal "UPI_CPU1_CPU0_P0P0_DN<16>"
				( objectStatus "@baseboard_fab2_lib.baseboard_fab2(sch_1):upi_cpu1_cpu0_p0p0_dn(16)" )
			)
			( signal "UPI_CPU1_CPU0_P0P0_DN<17>"
				( objectStatus "@baseboard_fab2_lib.baseboard_fab2(sch_1):upi_cpu1_cpu0_p0p0_dn(17)" )
			)
			( signal "UPI_CPU1_CPU0_P0P0_DN<18>"
				( objectStatus "@baseboard_fab2_lib.baseboard_fab2(sch_1):upi_cpu1_cpu0_p0p0_dn(18)" )
			)
			( signal "UPI_CPU1_CPU0_P0P0_DN<19>"
				( objectStatus "@baseboard_fab2_lib.baseboard_fab2(sch_1):upi_cpu1_cpu0_p0p0_dn(19)" )
			)
			( signal "UPI_CPU1_CPU0_P0P0_DP<0>"
				( objectStatus "@baseboard_fab2_lib.baseboard_fab2(sch_1):upi_cpu1_cpu0_p0p0_dp(0)" )
			)
			( signal "UPI_CPU1_CPU0_P0P0_DP<1>"
				( objectStatus "@baseboard_fab2_lib.baseboard_fab2(sch_1):upi_cpu1_cpu0_p0p0_dp(1)" )
			)
			( signal "UPI_CPU1_CPU0_P0P0_DP<2>"
				( objectStatus "@baseboard_fab2_lib.baseboard_fab2(sch_1):upi_cpu1_cpu0_p0p0_dp(2)" )
			)
			( signal "UPI_CPU1_CPU0_P0P0_DP<3>"
				( objectStatus "@baseboard_fab2_lib.baseboard_fab2(sch_1):upi_cpu1_cpu0_p0p0_dp(3)" )
			)
			( signal "UPI_CPU1_CPU0_P0P0_DP<4>"
				( objectStatus "@baseboard_fab2_lib.baseboard_fab2(sch_1):upi_cpu1_cpu0_p0p0_dp(4)" )
			)
			( signal "UPI_CPU1_CPU0_P0P0_DP<5>"
				( objectStatus "@baseboard_fab2_lib.baseboard_fab2(sch_1):upi_cpu1_cpu0_p0p0_dp(5)" )
			)
			( signal "UPI_CPU1_CPU0_P0P0_DP<6>"
				( objectStatus "@baseboard_fab2_lib.baseboard_fab2(sch_1):upi_cpu1_cpu0_p0p0_dp(6)" )
			)
			( signal "UPI_CPU1_CPU0_P0P0_DP<7>"
				( objectStatus "@baseboard_fab2_lib.baseboard_fab2(sch_1):upi_cpu1_cpu0_p0p0_dp(7)" )
			)
			( signal "UPI_CPU1_CPU0_P0P0_DP<8>"
				( objectStatus "@baseboard_fab2_lib.baseboard_fab2(sch_1):upi_cpu1_cpu0_p0p0_dp(8)" )
			)
			( signal "UPI_CPU1_CPU0_P0P0_DP<9>"
				( objectStatus "@baseboard_fab2_lib.baseboard_fab2(sch_1):upi_cpu1_cpu0_p0p0_dp(9)" )
			)
			( signal "UPI_CPU1_CPU0_P0P0_DP<10>"
				( objectStatus "@baseboard_fab2_lib.baseboard_fab2(sch_1):upi_cpu1_cpu0_p0p0_dp(10)" )
			)
			( signal "UPI_CPU1_CPU0_P0P0_DP<11>"
				( objectStatus "@baseboard_fab2_lib.baseboard_fab2(sch_1):upi_cpu1_cpu0_p0p0_dp(11)" )
			)
			( signal "UPI_CPU1_CPU0_P0P0_DP<12>"
				( objectStatus "@baseboard_fab2_lib.baseboard_fab2(sch_1):upi_cpu1_cpu0_p0p0_dp(12)" )
			)
			( signal "UPI_CPU1_CPU0_P0P0_DP<13>"
				( objectStatus "@baseboard_fab2_lib.baseboard_fab2(sch_1):upi_cpu1_cpu0_p0p0_dp(13)" )
			)
			( signal "UPI_CPU1_CPU0_P0P0_DP<14>"
				( objectStatus "@baseboard_fab2_lib.baseboard_fab2(sch_1):upi_cpu1_cpu0_p0p0_dp(14)" )
			)
			( signal "UPI_CPU1_CPU0_P0P0_DP<15>"
				( objectStatus "@baseboard_fab2_lib.baseboard_fab2(sch_1):upi_cpu1_cpu0_p0p0_dp(15)" )
			)
			( signal "UPI_CPU1_CPU0_P0P0_DP<16>"
				( objectStatus "@baseboard_fab2_lib.baseboard_fab2(sch_1):upi_cpu1_cpu0_p0p0_dp(16)" )
			)
			( signal "UPI_CPU1_CPU0_P0P0_DP<17>"
				( objectStatus "@baseboard_fab2_lib.baseboard_fab2(sch_1):upi_cpu1_cpu0_p0p0_dp(17)" )
			)
			( signal "UPI_CPU1_CPU0_P0P0_DP<18>"
				( objectStatus "@baseboard_fab2_lib.baseboard_fab2(sch_1):upi_cpu1_cpu0_p0p0_dp(18)" )
			)
			( signal "UPI_CPU1_CPU0_P0P0_DP<19>"
				( objectStatus "@baseboard_fab2_lib.baseboard_fab2(sch_1):upi_cpu1_cpu0_p0p0_dp(19)" )
			)
			( signal "UPI_CPU0_CPU1_P1P1_DN<0>"
				( objectStatus "@baseboard_fab2_lib.baseboard_fab2(sch_1):upi_cpu0_cpu1_p1p1_dn(0)" )
			)
			( signal "UPI_CPU0_CPU1_P1P1_DN<1>"
				( objectStatus "@baseboard_fab2_lib.baseboard_fab2(sch_1):upi_cpu0_cpu1_p1p1_dn(1)" )
			)
			( signal "UPI_CPU0_CPU1_P1P1_DN<2>"
				( objectStatus "@baseboard_fab2_lib.baseboard_fab2(sch_1):upi_cpu0_cpu1_p1p1_dn(2)" )
			)
			( signal "UPI_CPU0_CPU1_P1P1_DN<3>"
				( objectStatus "@baseboard_fab2_lib.baseboard_fab2(sch_1):upi_cpu0_cpu1_p1p1_dn(3)" )
			)
			( signal "UPI_CPU0_CPU1_P1P1_DN<4>"
				( objectStatus "@baseboard_fab2_lib.baseboard_fab2(sch_1):upi_cpu0_cpu1_p1p1_dn(4)" )
			)
			( signal "UPI_CPU0_CPU1_P1P1_DN<5>"
				( objectStatus "@baseboard_fab2_lib.baseboard_fab2(sch_1):upi_cpu0_cpu1_p1p1_dn(5)" )
			)
			( signal "UPI_CPU0_CPU1_P1P1_DN<6>"
				( objectStatus "@baseboard_fab2_lib.baseboard_fab2(sch_1):upi_cpu0_cpu1_p1p1_dn(6)" )
			)
			( signal "UPI_CPU0_CPU1_P1P1_DN<7>"
				( objectStatus "@baseboard_fab2_lib.baseboard_fab2(sch_1):upi_cpu0_cpu1_p1p1_dn(7)" )
			)
			( signal "UPI_CPU0_CPU1_P1P1_DN<8>"
				( objectStatus "@baseboard_fab2_lib.baseboard_fab2(sch_1):upi_cpu0_cpu1_p1p1_dn(8)" )
			)
			( signal "UPI_CPU0_CPU1_P1P1_DN<9>"
				( objectStatus "@baseboard_fab2_lib.baseboard_fab2(sch_1):upi_cpu0_cpu1_p1p1_dn(9)" )
			)
			( signal "UPI_CPU0_CPU1_P1P1_DN<10>"
				( objectStatus "@baseboard_fab2_lib.baseboard_fab2(sch_1):upi_cpu0_cpu1_p1p1_dn(10)" )
			)
			( signal "UPI_CPU0_CPU1_P1P1_DN<11>"
				( objectStatus "@baseboard_fab2_lib.baseboard_fab2(sch_1):upi_cpu0_cpu1_p1p1_dn(11)" )
			)
			( signal "UPI_CPU0_CPU1_P1P1_DN<12>"
				( objectStatus "@baseboard_fab2_lib.baseboard_fab2(sch_1):upi_cpu0_cpu1_p1p1_dn(12)" )
			)
			( signal "UPI_CPU0_CPU1_P1P1_DN<13>"
				( objectStatus "@baseboard_fab2_lib.baseboard_fab2(sch_1):upi_cpu0_cpu1_p1p1_dn(13)" )
			)
			( signal "UPI_CPU0_CPU1_P1P1_DN<14>"
				( objectStatus "@baseboard_fab2_lib.baseboard_fab2(sch_1):upi_cpu0_cpu1_p1p1_dn(14)" )
			)
			( signal "UPI_CPU0_CPU1_P1P1_DN<15>"
				( objectStatus "@baseboard_fab2_lib.baseboard_fab2(sch_1):upi_cpu0_cpu1_p1p1_dn(15)" )
			)
			( signal "UPI_CPU0_CPU1_P1P1_DN<16>"
				( objectStatus "@baseboard_fab2_lib.baseboard_fab2(sch_1):upi_cpu0_cpu1_p1p1_dn(16)" )
			)
			( signal "UPI_CPU0_CPU1_P1P1_DN<17>"
				( objectStatus "@baseboard_fab2_lib.baseboard_fab2(sch_1):upi_cpu0_cpu1_p1p1_dn(17)" )
			)
			( signal "UPI_CPU0_CPU1_P1P1_DN<18>"
				( objectStatus "@baseboard_fab2_lib.baseboard_fab2(sch_1):upi_cpu0_cpu1_p1p1_dn(18)" )
			)
			( signal "UPI_CPU0_CPU1_P1P1_DN<19>"
				( objectStatus "@baseboard_fab2_lib.baseboard_fab2(sch_1):upi_cpu0_cpu1_p1p1_dn(19)" )
			)
			( signal "UPI_CPU0_CPU1_P1P1_DP<0>"
				( objectStatus "@baseboard_fab2_lib.baseboard_fab2(sch_1):upi_cpu0_cpu1_p1p1_dp(0)" )
			)
			( signal "UPI_CPU0_CPU1_P1P1_DP<1>"
				( objectStatus "@baseboard_fab2_lib.baseboard_fab2(sch_1):upi_cpu0_cpu1_p1p1_dp(1)" )
			)
			( signal "UPI_CPU0_CPU1_P1P1_DP<2>"
				( objectStatus "@baseboard_fab2_lib.baseboard_fab2(sch_1):upi_cpu0_cpu1_p1p1_dp(2)" )
			)
			( signal "UPI_CPU0_CPU1_P1P1_DP<3>"
				( objectStatus "@baseboard_fab2_lib.baseboard_fab2(sch_1):upi_cpu0_cpu1_p1p1_dp(3)" )
			)
			( signal "UPI_CPU0_CPU1_P1P1_DP<4>"
				( objectStatus "@baseboard_fab2_lib.baseboard_fab2(sch_1):upi_cpu0_cpu1_p1p1_dp(4)" )
			)
			( signal "UPI_CPU0_CPU1_P1P1_DP<5>"
				( objectStatus "@baseboard_fab2_lib.baseboard_fab2(sch_1):upi_cpu0_cpu1_p1p1_dp(5)" )
			)
			( signal "UPI_CPU0_CPU1_P1P1_DP<6>"
				( objectStatus "@baseboard_fab2_lib.baseboard_fab2(sch_1):upi_cpu0_cpu1_p1p1_dp(6)" )
			)
			( signal "UPI_CPU0_CPU1_P1P1_DP<7>"
				( objectStatus "@baseboard_fab2_lib.baseboard_fab2(sch_1):upi_cpu0_cpu1_p1p1_dp(7)" )
			)
			( signal "UPI_CPU0_CPU1_P1P1_DP<8>"
				( objectStatus "@baseboard_fab2_lib.baseboard_fab2(sch_1):upi_cpu0_cpu1_p1p1_dp(8)" )
			)
			( signal "UPI_CPU0_CPU1_P1P1_DP<9>"
				( objectStatus "@baseboard_fab2_lib.baseboard_fab2(sch_1):upi_cpu0_cpu1_p1p1_dp(9)" )
			)
			( signal "UPI_CPU0_CPU1_P1P1_DP<10>"
				( objectStatus "@baseboard_fab2_lib.baseboard_fab2(sch_1):upi_cpu0_cpu1_p1p1_dp(10)" )
			)
			( signal "UPI_CPU0_CPU1_P1P1_DP<11>"
				( objectStatus "@baseboard_fab2_lib.baseboard_fab2(sch_1):upi_cpu0_cpu1_p1p1_dp(11)" )
			)
			( signal "UPI_CPU0_CPU1_P1P1_DP<12>"
				( objectStatus "@baseboard_fab2_lib.baseboard_fab2(sch_1):upi_cpu0_cpu1_p1p1_dp(12)" )
			)
			( signal "UPI_CPU0_CPU1_P1P1_DP<13>"
				( objectStatus "@baseboard_fab2_lib.baseboard_fab2(sch_1):upi_cpu0_cpu1_p1p1_dp(13)" )
			)
			( signal "UPI_CPU0_CPU1_P1P1_DP<14>"
				( objectStatus "@baseboard_fab2_lib.baseboard_fab2(sch_1):upi_cpu0_cpu1_p1p1_dp(14)" )
			)
			( signal "UPI_CPU0_CPU1_P1P1_DP<15>"
				( objectStatus "@baseboard_fab2_lib.baseboard_fab2(sch_1):upi_cpu0_cpu1_p1p1_dp(15)" )
			)
			( signal "UPI_CPU0_CPU1_P1P1_DP<16>"
				( objectStatus "@baseboard_fab2_lib.baseboard_fab2(sch_1):upi_cpu0_cpu1_p1p1_dp(16)" )
			)
			( signal "UPI_CPU0_CPU1_P1P1_DP<17>"
				( objectStatus "@baseboard_fab2_lib.baseboard_fab2(sch_1):upi_cpu0_cpu1_p1p1_dp(17)" )
			)
			( signal "UPI_CPU0_CPU1_P1P1_DP<18>"
				( objectStatus "@baseboard_fab2_lib.baseboard_fab2(sch_1):upi_cpu0_cpu1_p1p1_dp(18)" )
			)
			( signal "UPI_CPU0_CPU1_P1P1_DP<19>"
				( objectStatus "@baseboard_fab2_lib.baseboard_fab2(sch_1):upi_cpu0_cpu1_p1p1_dp(19)" )
			)
			( signal "UPI_CPU1_CPU0_P1P1_DN<0>"
				( objectStatus "@baseboard_fab2_lib.baseboard_fab2(sch_1):upi_cpu1_cpu0_p1p1_dn(0)" )
			)
			( signal "UPI_CPU1_CPU0_P1P1_DN<1>"
				( objectStatus "@baseboard_fab2_lib.baseboard_fab2(sch_1):upi_cpu1_cpu0_p1p1_dn(1)" )
			)
			( signal "UPI_CPU1_CPU0_P1P1_DN<2>"
				( objectStatus "@baseboard_fab2_lib.baseboard_fab2(sch_1):upi_cpu1_cpu0_p1p1_dn(2)" )
			)
			( signal "UPI_CPU1_CPU0_P1P1_DN<3>"
				( objectStatus "@baseboard_fab2_lib.baseboard_fab2(sch_1):upi_cpu1_cpu0_p1p1_dn(3)" )
			)
			( signal "UPI_CPU1_CPU0_P1P1_DN<4>"
				( objectStatus "@baseboard_fab2_lib.baseboard_fab2(sch_1):upi_cpu1_cpu0_p1p1_dn(4)" )
			)
			( signal "UPI_CPU1_CPU0_P1P1_DN<5>"
				( objectStatus "@baseboard_fab2_lib.baseboard_fab2(sch_1):upi_cpu1_cpu0_p1p1_dn(5)" )
			)
			( signal "UPI_CPU1_CPU0_P1P1_DN<6>"
				( objectStatus "@baseboard_fab2_lib.baseboard_fab2(sch_1):upi_cpu1_cpu0_p1p1_dn(6)" )
			)
			( signal "UPI_CPU1_CPU0_P1P1_DN<7>"
				( objectStatus "@baseboard_fab2_lib.baseboard_fab2(sch_1):upi_cpu1_cpu0_p1p1_dn(7)" )
			)
			( signal "UPI_CPU1_CPU0_P1P1_DN<8>"
				( objectStatus "@baseboard_fab2_lib.baseboard_fab2(sch_1):upi_cpu1_cpu0_p1p1_dn(8)" )
			)
			( signal "UPI_CPU1_CPU0_P1P1_DN<9>"
				( objectStatus "@baseboard_fab2_lib.baseboard_fab2(sch_1):upi_cpu1_cpu0_p1p1_dn(9)" )
			)
			( signal "UPI_CPU1_CPU0_P1P1_DN<10>"
				( objectStatus "@baseboard_fab2_lib.baseboard_fab2(sch_1):upi_cpu1_cpu0_p1p1_dn(10)" )
			)
			( signal "UPI_CPU1_CPU0_P1P1_DN<11>"
				( objectStatus "@baseboard_fab2_lib.baseboard_fab2(sch_1):upi_cpu1_cpu0_p1p1_dn(11)" )
			)
			( signal "UPI_CPU1_CPU0_P1P1_DN<12>"
				( objectStatus "@baseboard_fab2_lib.baseboard_fab2(sch_1):upi_cpu1_cpu0_p1p1_dn(12)" )
			)
			( signal "UPI_CPU1_CPU0_P1P1_DN<13>"
				( objectStatus "@baseboard_fab2_lib.baseboard_fab2(sch_1):upi_cpu1_cpu0_p1p1_dn(13)" )
			)
			( signal "UPI_CPU1_CPU0_P1P1_DN<14>"
				( objectStatus "@baseboard_fab2_lib.baseboard_fab2(sch_1):upi_cpu1_cpu0_p1p1_dn(14)" )
			)
			( signal "UPI_CPU1_CPU0_P1P1_DN<15>"
				( objectStatus "@baseboard_fab2_lib.baseboard_fab2(sch_1):upi_cpu1_cpu0_p1p1_dn(15)" )
			)
			( signal "UPI_CPU1_CPU0_P1P1_DN<16>"
				( objectStatus "@baseboard_fab2_lib.baseboard_fab2(sch_1):upi_cpu1_cpu0_p1p1_dn(16)" )
			)
			( signal "UPI_CPU1_CPU0_P1P1_DN<17>"
				( objectStatus "@baseboard_fab2_lib.baseboard_fab2(sch_1):upi_cpu1_cpu0_p1p1_dn(17)" )
			)
			( signal "UPI_CPU1_CPU0_P1P1_DN<18>"
				( objectStatus "@baseboard_fab2_lib.baseboard_fab2(sch_1):upi_cpu1_cpu0_p1p1_dn(18)" )
			)
			( signal "UPI_CPU1_CPU0_P1P1_DN<19>"
				( objectStatus "@baseboard_fab2_lib.baseboard_fab2(sch_1):upi_cpu1_cpu0_p1p1_dn(19)" )
			)
			( signal "UPI_CPU1_CPU0_P1P1_DP<0>"
				( objectStatus "@baseboard_fab2_lib.baseboard_fab2(sch_1):upi_cpu1_cpu0_p1p1_dp(0)" )
			)
			( signal "UPI_CPU1_CPU0_P1P1_DP<1>"
				( objectStatus "@baseboard_fab2_lib.baseboard_fab2(sch_1):upi_cpu1_cpu0_p1p1_dp(1)" )
			)
			( signal "UPI_CPU1_CPU0_P1P1_DP<2>"
				( objectStatus "@baseboard_fab2_lib.baseboard_fab2(sch_1):upi_cpu1_cpu0_p1p1_dp(2)" )
			)
			( signal "UPI_CPU1_CPU0_P1P1_DP<3>"
				( objectStatus "@baseboard_fab2_lib.baseboard_fab2(sch_1):upi_cpu1_cpu0_p1p1_dp(3)" )
			)
			( signal "UPI_CPU1_CPU0_P1P1_DP<4>"
				( objectStatus "@baseboard_fab2_lib.baseboard_fab2(sch_1):upi_cpu1_cpu0_p1p1_dp(4)" )
			)
			( signal "UPI_CPU1_CPU0_P1P1_DP<5>"
				( objectStatus "@baseboard_fab2_lib.baseboard_fab2(sch_1):upi_cpu1_cpu0_p1p1_dp(5)" )
			)
			( signal "UPI_CPU1_CPU0_P1P1_DP<6>"
				( objectStatus "@baseboard_fab2_lib.baseboard_fab2(sch_1):upi_cpu1_cpu0_p1p1_dp(6)" )
			)
			( signal "UPI_CPU1_CPU0_P1P1_DP<7>"
				( objectStatus "@baseboard_fab2_lib.baseboard_fab2(sch_1):upi_cpu1_cpu0_p1p1_dp(7)" )
			)
			( signal "UPI_CPU1_CPU0_P1P1_DP<8>"
				( objectStatus "@baseboard_fab2_lib.baseboard_fab2(sch_1):upi_cpu1_cpu0_p1p1_dp(8)" )
			)
			( signal "UPI_CPU1_CPU0_P1P1_DP<9>"
				( objectStatus "@baseboard_fab2_lib.baseboard_fab2(sch_1):upi_cpu1_cpu0_p1p1_dp(9)" )
			)
			( signal "UPI_CPU1_CPU0_P1P1_DP<10>"
				( objectStatus "@baseboard_fab2_lib.baseboard_fab2(sch_1):upi_cpu1_cpu0_p1p1_dp(10)" )
			)
			( signal "UPI_CPU1_CPU0_P1P1_DP<11>"
				( objectStatus "@baseboard_fab2_lib.baseboard_fab2(sch_1):upi_cpu1_cpu0_p1p1_dp(11)" )
			)
			( signal "UPI_CPU1_CPU0_P1P1_DP<12>"
				( objectStatus "@baseboard_fab2_lib.baseboard_fab2(sch_1):upi_cpu1_cpu0_p1p1_dp(12)" )
			)
			( signal "UPI_CPU1_CPU0_P1P1_DP<13>"
				( objectStatus "@baseboard_fab2_lib.baseboard_fab2(sch_1):upi_cpu1_cpu0_p1p1_dp(13)" )
			)
			( signal "UPI_CPU1_CPU0_P1P1_DP<14>"
				( objectStatus "@baseboard_fab2_lib.baseboard_fab2(sch_1):upi_cpu1_cpu0_p1p1_dp(14)" )
			)
			( signal "UPI_CPU1_CPU0_P1P1_DP<15>"
				( objectStatus "@baseboard_fab2_lib.baseboard_fab2(sch_1):upi_cpu1_cpu0_p1p1_dp(15)" )
			)
			( signal "UPI_CPU1_CPU0_P1P1_DP<16>"
				( objectStatus "@baseboard_fab2_lib.baseboard_fab2(sch_1):upi_cpu1_cpu0_p1p1_dp(16)" )
			)
			( signal "UPI_CPU1_CPU0_P1P1_DP<17>"
				( objectStatus "@baseboard_fab2_lib.baseboard_fab2(sch_1):upi_cpu1_cpu0_p1p1_dp(17)" )
			)
			( signal "UPI_CPU1_CPU0_P1P1_DP<18>"
				( objectStatus "@baseboard_fab2_lib.baseboard_fab2(sch_1):upi_cpu1_cpu0_p1p1_dp(18)" )
			)
			( signal "UPI_CPU1_CPU0_P1P1_DP<19>"
				( objectStatus "@baseboard_fab2_lib.baseboard_fab2(sch_1):upi_cpu1_cpu0_p1p1_dp(19)" )
			)
			( signal "TP_CPU0_UPI2_RSVD_CA12"
				( objectStatus "@baseboard_fab2_lib.baseboard_fab2(sch_1):tp_cpu0_upi2_rsvd_ca12" )
			)
			( signal "TP_CPU0_UPI2_RSVD_CB11"
				( objectStatus "@baseboard_fab2_lib.baseboard_fab2(sch_1):tp_cpu0_upi2_rsvd_cb11" )
			)
			( signal "TP_CPU0_UPI2_RSVD_CC10"
				( objectStatus "@baseboard_fab2_lib.baseboard_fab2(sch_1):tp_cpu0_upi2_rsvd_cc10" )
			)
			( signal "TP_CPU0_UPI2_RSVD_CC12"
				( objectStatus "@baseboard_fab2_lib.baseboard_fab2(sch_1):tp_cpu0_upi2_rsvd_cc12" )
			)
			( signal "TP_CPU0_UPI2_RSVD_CD11"
				( objectStatus "@baseboard_fab2_lib.baseboard_fab2(sch_1):tp_cpu0_upi2_rsvd_cd11" )
			)
			( signal "TP_CPU0_UPI2_RSVD_CE12"
				( objectStatus "@baseboard_fab2_lib.baseboard_fab2(sch_1):tp_cpu0_upi2_rsvd_ce12" )
			)
			( signal "TP_CPU0_UPI2_RSVD_CF11"
				( objectStatus "@baseboard_fab2_lib.baseboard_fab2(sch_1):tp_cpu0_upi2_rsvd_cf11" )
			)
			( signal "TP_CPU0_UPI2_RSVD_CF13"
				( objectStatus "@baseboard_fab2_lib.baseboard_fab2(sch_1):tp_cpu0_upi2_rsvd_cf13" )
			)
			( signal "TP_CPU0_UPI2_RSVD_CG12"
				( objectStatus "@baseboard_fab2_lib.baseboard_fab2(sch_1):tp_cpu0_upi2_rsvd_cg12" )
			)
			( signal "TP_CPU0_UPI2_RSVD_CH11"
				( objectStatus "@baseboard_fab2_lib.baseboard_fab2(sch_1):tp_cpu0_upi2_rsvd_ch11" )
			)
			( signal "TP_CPU0_UPI2_RSVD_CH13"
				( objectStatus "@baseboard_fab2_lib.baseboard_fab2(sch_1):tp_cpu0_upi2_rsvd_ch13" )
			)
			( signal "TP_CPU0_UPI2_RSVD_CJ14"
				( objectStatus "@baseboard_fab2_lib.baseboard_fab2(sch_1):tp_cpu0_upi2_rsvd_cj14" )
			)
			( signal "TP_CPU0_UPI2_RSVD_CK13"
				( objectStatus "@baseboard_fab2_lib.baseboard_fab2(sch_1):tp_cpu0_upi2_rsvd_ck13" )
			)
			( signal "TP_CPU0_UPI2_RSVD_CM13"
				( objectStatus "@baseboard_fab2_lib.baseboard_fab2(sch_1):tp_cpu0_upi2_rsvd_cm13" )
			)
			( signal "TP_CPU0_UPI2_RSVD_CR14"
				( objectStatus "@baseboard_fab2_lib.baseboard_fab2(sch_1):tp_cpu0_upi2_rsvd_cr14" )
			)
			( signal "TP_CPU0_UPI2_RSVD_CU14"
				( objectStatus "@baseboard_fab2_lib.baseboard_fab2(sch_1):tp_cpu0_upi2_rsvd_cu14" )
			)
			( signal "TP_CPU0_UPI2_RSVD_CV13"
				( objectStatus "@baseboard_fab2_lib.baseboard_fab2(sch_1):tp_cpu0_upi2_rsvd_cv13" )
			)
			( signal "TP_CPU0_UPI2_RSVD_CW14"
				( objectStatus "@baseboard_fab2_lib.baseboard_fab2(sch_1):tp_cpu0_upi2_rsvd_cw14" )
			)
			( signal "TP_CPU0_UPI2_RSVD_CW16"
				( objectStatus "@baseboard_fab2_lib.baseboard_fab2(sch_1):tp_cpu0_upi2_rsvd_cw16" )
			)
			( signal "TP_CPU0_UPI2_RSVD_DA16"
				( objectStatus "@baseboard_fab2_lib.baseboard_fab2(sch_1):tp_cpu0_upi2_rsvd_da16" )
			)
			( signal "TP_CPU0_UPI2_RSVD_DB15"
				( objectStatus "@baseboard_fab2_lib.baseboard_fab2(sch_1):tp_cpu0_upi2_rsvd_db15" )
			)
			( signal "TP_CPU0_UPI2_RSVD_DC16"
				( objectStatus "@baseboard_fab2_lib.baseboard_fab2(sch_1):tp_cpu0_upi2_rsvd_dc16" )
			)
			( signal "TP_CPU0_UPI2_RSVD_DD15"
				( objectStatus "@baseboard_fab2_lib.baseboard_fab2(sch_1):tp_cpu0_upi2_rsvd_dd15" )
			)
			( signal "TP_CPU0_UPI2_RSVD_DD17"
				( objectStatus "@baseboard_fab2_lib.baseboard_fab2(sch_1):tp_cpu0_upi2_rsvd_dd17" )
			)
			( signal "TP_CPU0_UPI2_RSVD_DE16"
				( objectStatus "@baseboard_fab2_lib.baseboard_fab2(sch_1):tp_cpu0_upi2_rsvd_de16" )
			)
			( signal "TP_CPU0_UPI2_RSVD_DF15"
				( objectStatus "@baseboard_fab2_lib.baseboard_fab2(sch_1):tp_cpu0_upi2_rsvd_df15" )
			)
			( signal "TP_CPU0_UPI2_RSVD_DF17"
				( objectStatus "@baseboard_fab2_lib.baseboard_fab2(sch_1):tp_cpu0_upi2_rsvd_df17" )
			)
			( signal "TP_CPU0_UPI2_RSVD_DG18"
				( objectStatus "@baseboard_fab2_lib.baseboard_fab2(sch_1):tp_cpu0_upi2_rsvd_dg18" )
			)
			( signal "TP_CPU0_UPI2_RSVD_DG20"
				( objectStatus "@baseboard_fab2_lib.baseboard_fab2(sch_1):tp_cpu0_upi2_rsvd_dg20" )
			)
			( signal "TP_CPU0_UPI2_RSVD_DH17"
				( objectStatus "@baseboard_fab2_lib.baseboard_fab2(sch_1):tp_cpu0_upi2_rsvd_dh17" )
			)
			( signal "TP_CPU0_UPI2_RSVD_DH19"
				( objectStatus "@baseboard_fab2_lib.baseboard_fab2(sch_1):tp_cpu0_upi2_rsvd_dh19" )
			)
			( signal "TP_CPU0_UPI2_RSVD_DJ18"
				( objectStatus "@baseboard_fab2_lib.baseboard_fab2(sch_1):tp_cpu0_upi2_rsvd_dj18" )
			)
			( signal "TP_CPU0_UPI2_RSVD_DJ20"
				( objectStatus "@baseboard_fab2_lib.baseboard_fab2(sch_1):tp_cpu0_upi2_rsvd_dj20" )
			)
			( signal "TP_CPU0_UPI2_RSVD_DK17"
				( objectStatus "@baseboard_fab2_lib.baseboard_fab2(sch_1):tp_cpu0_upi2_rsvd_dk17" )
			)
			( signal "TP_CPU0_UPI2_RSVD_DK19"
				( objectStatus "@baseboard_fab2_lib.baseboard_fab2(sch_1):tp_cpu0_upi2_rsvd_dk19" )
			)
			( signal "TP_CPU0_UPI2_RSVD_DL20"
				( objectStatus "@baseboard_fab2_lib.baseboard_fab2(sch_1):tp_cpu0_upi2_rsvd_dl20" )
			)
			( signal "TP_CPU0_UPI2_RSVD_DM21"
				( objectStatus "@baseboard_fab2_lib.baseboard_fab2(sch_1):tp_cpu0_upi2_rsvd_dm21" )
			)
			( signal "TP_CPU0_UPI2_RSVD_DN20"
				( objectStatus "@baseboard_fab2_lib.baseboard_fab2(sch_1):tp_cpu0_upi2_rsvd_dn20" )
			)
			( signal "TP_CPU0_UPI2_RSVD_DP21"
				( objectStatus "@baseboard_fab2_lib.baseboard_fab2(sch_1):tp_cpu0_upi2_rsvd_dp21" )
			)
			( signal "TP_CPU0_UPI2_RSVD_DT21"
				( objectStatus "@baseboard_fab2_lib.baseboard_fab2(sch_1):tp_cpu0_upi2_rsvd_dt21" )
			)
			( signal "CLK_100M_CPU0_RC_REFCLK1_DN"
				( objectStatus "@baseboard_fab2_lib.baseboard_fab2(sch_1):clk_100m_cpu0_rc_refclk1_dn" )
			)
			( signal "CLK_100M_CPU0_RC_REFCLK1_DP"
				( objectStatus "@baseboard_fab2_lib.baseboard_fab2(sch_1):clk_100m_cpu0_rc_refclk1_dp" )
			)
			( signal "TP_CPU0_RSVD_100"
				( objectStatus "@baseboard_fab2_lib.baseboard_fab2(sch_1):tp_cpu0_rsvd_100" )
			)
			( signal "TP_CPU0_RSVD_101"
				( objectStatus "@baseboard_fab2_lib.baseboard_fab2(sch_1):tp_cpu0_rsvd_101" )
			)
			( signal "TP_CPU0_RSVD_105"
				( objectStatus "@baseboard_fab2_lib.baseboard_fab2(sch_1):tp_cpu0_rsvd_105" )
			)
			( signal "TP_CPU0_RSVD_106"
				( objectStatus "@baseboard_fab2_lib.baseboard_fab2(sch_1):tp_cpu0_rsvd_106" )
			)
			( signal "TP_CPU0_RSVD_108"
				( objectStatus "@baseboard_fab2_lib.baseboard_fab2(sch_1):tp_cpu0_rsvd_108" )
			)
			( signal "TP_CPU0_RSVD_111"
				( objectStatus "@baseboard_fab2_lib.baseboard_fab2(sch_1):tp_cpu0_rsvd_111" )
			)
			( signal "TP_CPU0_RSVD_113"
				( objectStatus "@baseboard_fab2_lib.baseboard_fab2(sch_1):tp_cpu0_rsvd_113" )
			)
			( signal "TP_CPU0_RSVD_114"
				( objectStatus "@baseboard_fab2_lib.baseboard_fab2(sch_1):tp_cpu0_rsvd_114" )
			)
			( signal "TP_CPU0_RSVD_117"
				( objectStatus "@baseboard_fab2_lib.baseboard_fab2(sch_1):tp_cpu0_rsvd_117" )
			)
			( signal "TP_CPU0_RSVD_119"
				( objectStatus "@baseboard_fab2_lib.baseboard_fab2(sch_1):tp_cpu0_rsvd_119" )
			)
			( signal "TP_CPU0_RSVD_121"
				( objectStatus "@baseboard_fab2_lib.baseboard_fab2(sch_1):tp_cpu0_rsvd_121" )
			)
			( signal "TP_CPU0_RSVD_123"
				( objectStatus "@baseboard_fab2_lib.baseboard_fab2(sch_1):tp_cpu0_rsvd_123" )
			)
			( signal "TP_CPU0_RSVD_124"
				( objectStatus "@baseboard_fab2_lib.baseboard_fab2(sch_1):tp_cpu0_rsvd_124" )
			)
			( signal "TP_CPU0_RSVD_144"
				( objectStatus "@baseboard_fab2_lib.baseboard_fab2(sch_1):tp_cpu0_rsvd_144" )
			)
			( signal "TP_CPU0_RSVD_145"
				( objectStatus "@baseboard_fab2_lib.baseboard_fab2(sch_1):tp_cpu0_rsvd_145" )
			)
			( signal "TP_CPU0_RSVD_146"
				( objectStatus "@baseboard_fab2_lib.baseboard_fab2(sch_1):tp_cpu0_rsvd_146" )
			)
			( signal "TP_CPU0_RSVD_147"
				( objectStatus "@baseboard_fab2_lib.baseboard_fab2(sch_1):tp_cpu0_rsvd_147" )
			)
			( signal "TP_CPU0_RSVD_148"
				( objectStatus "@baseboard_fab2_lib.baseboard_fab2(sch_1):tp_cpu0_rsvd_148" )
			)
			( signal "TP_CPU0_RSVD_149"
				( objectStatus "@baseboard_fab2_lib.baseboard_fab2(sch_1):tp_cpu0_rsvd_149" )
			)
			( signal "TP_CPU0_RSVD_150"
				( objectStatus "@baseboard_fab2_lib.baseboard_fab2(sch_1):tp_cpu0_rsvd_150" )
			)
			( signal "TP_CPU0_RSVD_151"
				( objectStatus "@baseboard_fab2_lib.baseboard_fab2(sch_1):tp_cpu0_rsvd_151" )
			)
			( signal "TP_CPU0_RSVD_152"
				( objectStatus "@baseboard_fab2_lib.baseboard_fab2(sch_1):tp_cpu0_rsvd_152" )
			)
			( signal "TP_CPU0_RSVD_154"
				( objectStatus "@baseboard_fab2_lib.baseboard_fab2(sch_1):tp_cpu0_rsvd_154" )
			)
			( signal "TP_CPU0_RSVD_155"
				( objectStatus "@baseboard_fab2_lib.baseboard_fab2(sch_1):tp_cpu0_rsvd_155" )
			)
			( signal "TP_CPU0_RSVD_156"
				( objectStatus "@baseboard_fab2_lib.baseboard_fab2(sch_1):tp_cpu0_rsvd_156" )
			)
			( signal "TP_CPU0_RSVD_157"
				( objectStatus "@baseboard_fab2_lib.baseboard_fab2(sch_1):tp_cpu0_rsvd_157" )
			)
			( signal "TP_CPU0_RSVD_158"
				( objectStatus "@baseboard_fab2_lib.baseboard_fab2(sch_1):tp_cpu0_rsvd_158" )
			)
			( signal "TP_CPU0_RSVD_159"
				( objectStatus "@baseboard_fab2_lib.baseboard_fab2(sch_1):tp_cpu0_rsvd_159" )
			)
			( signal "TP_CPU0_RSVD_160"
				( objectStatus "@baseboard_fab2_lib.baseboard_fab2(sch_1):tp_cpu0_rsvd_160" )
			)
			( signal "TP_CPU0_RSVD_161"
				( objectStatus "@baseboard_fab2_lib.baseboard_fab2(sch_1):tp_cpu0_rsvd_161" )
			)
			( signal "TP_CPU0_RSVD_162"
				( objectStatus "@baseboard_fab2_lib.baseboard_fab2(sch_1):tp_cpu0_rsvd_162" )
			)
			( signal "TP_CPU0_RSVD_163"
				( objectStatus "@baseboard_fab2_lib.baseboard_fab2(sch_1):tp_cpu0_rsvd_163" )
			)
			( signal "TP_CPU0_RSVD_164"
				( objectStatus "@baseboard_fab2_lib.baseboard_fab2(sch_1):tp_cpu0_rsvd_164" )
			)
			( signal "TP_CPU0_RSVD_166"
				( objectStatus "@baseboard_fab2_lib.baseboard_fab2(sch_1):tp_cpu0_rsvd_166" )
			)
			( signal "TP_CPU0_RSVD_167"
				( objectStatus "@baseboard_fab2_lib.baseboard_fab2(sch_1):tp_cpu0_rsvd_167" )
			)
			( signal "TP_CPU0_RSVD_168"
				( objectStatus "@baseboard_fab2_lib.baseboard_fab2(sch_1):tp_cpu0_rsvd_168" )
			)
			( signal "TP_CPU0_RSVD_169"
				( objectStatus "@baseboard_fab2_lib.baseboard_fab2(sch_1):tp_cpu0_rsvd_169" )
			)
			( signal "TP_CPU0_RSVD_170"
				( objectStatus "@baseboard_fab2_lib.baseboard_fab2(sch_1):tp_cpu0_rsvd_170" )
			)
			( signal "TP_CPU0_RSVD_171"
				( objectStatus "@baseboard_fab2_lib.baseboard_fab2(sch_1):tp_cpu0_rsvd_171" )
			)
			( signal "TP_CPU0_RSVD_255"
				( objectStatus "@baseboard_fab2_lib.baseboard_fab2(sch_1):tp_cpu0_rsvd_255" )
			)
			( signal "TP_CPU0_RSVD_82"
				( objectStatus "@baseboard_fab2_lib.baseboard_fab2(sch_1):tp_cpu0_rsvd_82" )
			)
			( signal "TP_CPU0_RSVD_85"
				( objectStatus "@baseboard_fab2_lib.baseboard_fab2(sch_1):tp_cpu0_rsvd_85" )
			)
			( signal "TP_CPU0_RSVD_90"
				( objectStatus "@baseboard_fab2_lib.baseboard_fab2(sch_1):tp_cpu0_rsvd_90" )
			)
			( signal "TP_CPU0_RSVD_91"
				( objectStatus "@baseboard_fab2_lib.baseboard_fab2(sch_1):tp_cpu0_rsvd_91" )
			)
			( signal "TP_CPU0_RSVD_94"
				( objectStatus "@baseboard_fab2_lib.baseboard_fab2(sch_1):tp_cpu0_rsvd_94" )
			)
			( signal "TP_CPU0_RSVD_95"
				( objectStatus "@baseboard_fab2_lib.baseboard_fab2(sch_1):tp_cpu0_rsvd_95" )
			)
			( signal "TP_CPU0_RSVD_97"
				( objectStatus "@baseboard_fab2_lib.baseboard_fab2(sch_1):tp_cpu0_rsvd_97" )
			)
			( signal "TP_CPU0_RSVD_99"
				( objectStatus "@baseboard_fab2_lib.baseboard_fab2(sch_1):tp_cpu0_rsvd_99" )
			)
			( signal "TP_CPU0_TEST_10"
				( objectStatus "@baseboard_fab2_lib.baseboard_fab2(sch_1):tp_cpu0_test_10" )
			)
			( signal "TP_CPU0_TEST_6"
				( objectStatus "@baseboard_fab2_lib.baseboard_fab2(sch_1):tp_cpu0_test_6" )
			)
			( signal "TP_CPU0_TEST_7"
				( objectStatus "@baseboard_fab2_lib.baseboard_fab2(sch_1):tp_cpu0_test_7" )
			)
			( signal "TP_CPU0_TEST_8"
				( objectStatus "@baseboard_fab2_lib.baseboard_fab2(sch_1):tp_cpu0_test_8" )
			)
			( signal "TP_CPU0_TEST_9"
				( objectStatus "@baseboard_fab2_lib.baseboard_fab2(sch_1):tp_cpu0_test_9" )
			)
			( signal "PVCCIN_CPU0"
				( attribute "VOLTAGE" "2.0V"
					( Units "uVoltage" "V" 1.000000)
					( Status sAliasFlattened )
					( Origin gFrontEnd )
				)
				( objectStatus "@baseboard_fab2_lib.baseboard_fab2(sch_1):pvccin_cpu0" )
			)
			( signal "VSENSE_PMAX_CPU0"
				( objectStatus "@baseboard_fab2_lib.baseboard_fab2(sch_1):vsense_pmax_cpu0" )
			)
			( signal "VSENSE_PVCCIN_CPU0_SKT_VRTN"
				( objectStatus "@baseboard_fab2_lib.baseboard_fab2(sch_1):vsense_pvccin_cpu0_skt_vrtn" )
			)
			( signal "VSENSE_PVCCIN_CPU0_SKT_VSEN"
				( objectStatus "@baseboard_fab2_lib.baseboard_fab2(sch_1):vsense_pvccin_cpu0_skt_vsen" )
			)
			( signal "VSENSE_VCCINR2PMAX_CPU0"
				( objectStatus "@baseboard_fab2_lib.baseboard_fab2(sch_1):vsense_vccinr2pmax_cpu0" )
			)
			( signal "PVCCIOMCP_CPU0"
				( attribute "VOLTAGE" "+0.95"
					( Units "uVoltage" "V" 1.000000)
					( Status sAliasFlattened )
					( Origin gFrontEnd )
				)
				( objectStatus "@baseboard_fab2_lib.baseboard_fab2(sch_1):pvcciomcp_cpu0" )
			)
			( signal "PVDDQ_ABC"
				( attribute "VOLTAGE" "1.2V"
					( Units "uVoltage" "V" 1.000000)
					( Status sAliasFlattened )
					( Origin gFrontEnd )
				)
				( objectStatus "@baseboard_fab2_lib.baseboard_fab2(sch_1):pvddq_abc" )
			)
			( signal "PVDDQ_DEF"
				( attribute "VOLTAGE" "1.2V"
					( Units "uVoltage" "V" 1.000000)
					( Status sAliasFlattened )
					( Origin gFrontEnd )
				)
				( objectStatus "@baseboard_fab2_lib.baseboard_fab2(sch_1):pvddq_def" )
			)
			( signal "PVPP_ABC"
				( attribute "VOLTAGE" "2.5V"
					( Units "uVoltage" "V" 1.000000)
					( Status sAliasFlattened )
					( Origin gFrontEnd )
				)
				( objectStatus "@baseboard_fab2_lib.baseboard_fab2(sch_1):pvpp_abc" )
			)
			( signal "PVSA_CPU0"
				( attribute "VOLTAGE" "1.1V"
					( Units "uVoltage" "V" 1.000000)
					( Status sAliasFlattened )
					( Origin gFrontEnd )
				)
				( objectStatus "@baseboard_fab2_lib.baseboard_fab2(sch_1):pvsa_cpu0" )
			)
			( signal "PD_CPU0_MCP01_DMON"
				( objectStatus "@baseboard_fab2_lib.baseboard_fab2(sch_1):pd_cpu0_mcp01_dmon" )
			)
			( signal "TP_CPU0_KTI2_AMONV"
				( objectStatus "@baseboard_fab2_lib.baseboard_fab2(sch_1):tp_cpu0_kti2_amonv" )
			)
			( signal "TP_CPU0_KTI2_DFX_DN"
				( objectStatus "@baseboard_fab2_lib.baseboard_fab2(sch_1):tp_cpu0_kti2_dfx_dn" )
			)
			( signal "TP_CPU0_RSVD_0"
				( objectStatus "@baseboard_fab2_lib.baseboard_fab2(sch_1):tp_cpu0_rsvd_0" )
			)
			( signal "TP_CPU0_RSVD_1"
				( objectStatus "@baseboard_fab2_lib.baseboard_fab2(sch_1):tp_cpu0_rsvd_1" )
			)
			( signal "TP_CPU0_RSVD_10"
				( objectStatus "@baseboard_fab2_lib.baseboard_fab2(sch_1):tp_cpu0_rsvd_10" )
			)
			( signal "TP_CPU0_RSVD_11"
				( objectStatus "@baseboard_fab2_lib.baseboard_fab2(sch_1):tp_cpu0_rsvd_11" )
			)
			( signal "TP_CPU0_RSVD_12"
				( objectStatus "@baseboard_fab2_lib.baseboard_fab2(sch_1):tp_cpu0_rsvd_12" )
			)
			( signal "TP_CPU0_RSVD_13"
				( objectStatus "@baseboard_fab2_lib.baseboard_fab2(sch_1):tp_cpu0_rsvd_13" )
			)
			( signal "TP_CPU0_RSVD_14"
				( objectStatus "@baseboard_fab2_lib.baseboard_fab2(sch_1):tp_cpu0_rsvd_14" )
			)
			( signal "TP_CPU0_RSVD_15"
				( objectStatus "@baseboard_fab2_lib.baseboard_fab2(sch_1):tp_cpu0_rsvd_15" )
			)
			( signal "TP_CPU0_RSVD_16"
				( objectStatus "@baseboard_fab2_lib.baseboard_fab2(sch_1):tp_cpu0_rsvd_16" )
			)
			( signal "TP_CPU0_RSVD_17"
				( objectStatus "@baseboard_fab2_lib.baseboard_fab2(sch_1):tp_cpu0_rsvd_17" )
			)
			( signal "TP_CPU0_RSVD_18"
				( objectStatus "@baseboard_fab2_lib.baseboard_fab2(sch_1):tp_cpu0_rsvd_18" )
			)
			( signal "TP_CPU0_RSVD_19"
				( objectStatus "@baseboard_fab2_lib.baseboard_fab2(sch_1):tp_cpu0_rsvd_19" )
			)
			( signal "TP_CPU0_RSVD_2"
				( objectStatus "@baseboard_fab2_lib.baseboard_fab2(sch_1):tp_cpu0_rsvd_2" )
			)
			( signal "TP_CPU0_RSVD_20"
				( objectStatus "@baseboard_fab2_lib.baseboard_fab2(sch_1):tp_cpu0_rsvd_20" )
			)
			( signal "TP_CPU0_RSVD_21"
				( objectStatus "@baseboard_fab2_lib.baseboard_fab2(sch_1):tp_cpu0_rsvd_21" )
			)
			( signal "TP_CPU0_RSVD_22"
				( objectStatus "@baseboard_fab2_lib.baseboard_fab2(sch_1):tp_cpu0_rsvd_22" )
			)
			( signal "TP_CPU0_RSVD_23"
				( objectStatus "@baseboard_fab2_lib.baseboard_fab2(sch_1):tp_cpu0_rsvd_23" )
			)
			( signal "TP_CPU0_RSVD_24"
				( objectStatus "@baseboard_fab2_lib.baseboard_fab2(sch_1):tp_cpu0_rsvd_24" )
			)
			( signal "TP_CPU0_RSVD_25"
				( objectStatus "@baseboard_fab2_lib.baseboard_fab2(sch_1):tp_cpu0_rsvd_25" )
			)
			( signal "TP_CPU0_RSVD_26"
				( objectStatus "@baseboard_fab2_lib.baseboard_fab2(sch_1):tp_cpu0_rsvd_26" )
			)
			( signal "TP_CPU0_RSVD_27"
				( objectStatus "@baseboard_fab2_lib.baseboard_fab2(sch_1):tp_cpu0_rsvd_27" )
			)
			( signal "TP_CPU0_RSVD_28"
				( objectStatus "@baseboard_fab2_lib.baseboard_fab2(sch_1):tp_cpu0_rsvd_28" )
			)
			( signal "TP_CPU0_RSVD_29"
				( objectStatus "@baseboard_fab2_lib.baseboard_fab2(sch_1):tp_cpu0_rsvd_29" )
			)
			( signal "TP_CPU0_RSVD_3"
				( objectStatus "@baseboard_fab2_lib.baseboard_fab2(sch_1):tp_cpu0_rsvd_3" )
			)
			( signal "TP_CPU0_RSVD_30"
				( objectStatus "@baseboard_fab2_lib.baseboard_fab2(sch_1):tp_cpu0_rsvd_30" )
			)
			( signal "TP_CPU0_RSVD_31"
				( objectStatus "@baseboard_fab2_lib.baseboard_fab2(sch_1):tp_cpu0_rsvd_31" )
			)
			( signal "TP_CPU0_RSVD_32"
				( objectStatus "@baseboard_fab2_lib.baseboard_fab2(sch_1):tp_cpu0_rsvd_32" )
			)
			( signal "TP_CPU0_RSVD_33"
				( objectStatus "@baseboard_fab2_lib.baseboard_fab2(sch_1):tp_cpu0_rsvd_33" )
			)
			( signal "TP_CPU0_RSVD_34"
				( objectStatus "@baseboard_fab2_lib.baseboard_fab2(sch_1):tp_cpu0_rsvd_34" )
			)
			( signal "TP_CPU0_RSVD_35"
				( objectStatus "@baseboard_fab2_lib.baseboard_fab2(sch_1):tp_cpu0_rsvd_35" )
			)
			( signal "TP_CPU0_RSVD_36"
				( objectStatus "@baseboard_fab2_lib.baseboard_fab2(sch_1):tp_cpu0_rsvd_36" )
			)
			( signal "TP_CPU0_RSVD_37"
				( objectStatus "@baseboard_fab2_lib.baseboard_fab2(sch_1):tp_cpu0_rsvd_37" )
			)
			( signal "TP_CPU0_RSVD_38"
				( objectStatus "@baseboard_fab2_lib.baseboard_fab2(sch_1):tp_cpu0_rsvd_38" )
			)
			( signal "TP_CPU0_RSVD_39"
				( objectStatus "@baseboard_fab2_lib.baseboard_fab2(sch_1):tp_cpu0_rsvd_39" )
			)
			( signal "TP_CPU0_RSVD_4"
				( objectStatus "@baseboard_fab2_lib.baseboard_fab2(sch_1):tp_cpu0_rsvd_4" )
			)
			( signal "TP_CPU0_RSVD_40"
				( objectStatus "@baseboard_fab2_lib.baseboard_fab2(sch_1):tp_cpu0_rsvd_40" )
			)
			( signal "TP_CPU0_RSVD_41"
				( objectStatus "@baseboard_fab2_lib.baseboard_fab2(sch_1):tp_cpu0_rsvd_41" )
			)
			( signal "TP_CPU0_RSVD_42"
				( objectStatus "@baseboard_fab2_lib.baseboard_fab2(sch_1):tp_cpu0_rsvd_42" )
			)
			( signal "TP_CPU0_RSVD_43"
				( objectStatus "@baseboard_fab2_lib.baseboard_fab2(sch_1):tp_cpu0_rsvd_43" )
			)
			( signal "TP_CPU0_RSVD_44"
				( objectStatus "@baseboard_fab2_lib.baseboard_fab2(sch_1):tp_cpu0_rsvd_44" )
			)
			( signal "TP_CPU0_RSVD_45"
				( objectStatus "@baseboard_fab2_lib.baseboard_fab2(sch_1):tp_cpu0_rsvd_45" )
			)
			( signal "TP_CPU0_RSVD_46"
				( objectStatus "@baseboard_fab2_lib.baseboard_fab2(sch_1):tp_cpu0_rsvd_46" )
			)
			( signal "TP_CPU0_RSVD_47"
				( objectStatus "@baseboard_fab2_lib.baseboard_fab2(sch_1):tp_cpu0_rsvd_47" )
			)
			( signal "TP_CPU0_RSVD_48"
				( objectStatus "@baseboard_fab2_lib.baseboard_fab2(sch_1):tp_cpu0_rsvd_48" )
			)
			( signal "TP_CPU0_RSVD_49"
				( objectStatus "@baseboard_fab2_lib.baseboard_fab2(sch_1):tp_cpu0_rsvd_49" )
			)
			( signal "TP_CPU0_RSVD_5"
				( objectStatus "@baseboard_fab2_lib.baseboard_fab2(sch_1):tp_cpu0_rsvd_5" )
			)
			( signal "TP_CPU0_RSVD_50"
				( objectStatus "@baseboard_fab2_lib.baseboard_fab2(sch_1):tp_cpu0_rsvd_50" )
			)
			( signal "TP_CPU0_RSVD_51"
				( objectStatus "@baseboard_fab2_lib.baseboard_fab2(sch_1):tp_cpu0_rsvd_51" )
			)
			( signal "TP_CPU0_RSVD_53"
				( objectStatus "@baseboard_fab2_lib.baseboard_fab2(sch_1):tp_cpu0_rsvd_53" )
			)
			( signal "TP_CPU0_RSVD_54"
				( objectStatus "@baseboard_fab2_lib.baseboard_fab2(sch_1):tp_cpu0_rsvd_54" )
			)
			( signal "TP_CPU0_RSVD_55"
				( objectStatus "@baseboard_fab2_lib.baseboard_fab2(sch_1):tp_cpu0_rsvd_55" )
			)
			( signal "TP_CPU0_RSVD_56"
				( objectStatus "@baseboard_fab2_lib.baseboard_fab2(sch_1):tp_cpu0_rsvd_56" )
			)
			( signal "TP_CPU0_RSVD_57"
				( objectStatus "@baseboard_fab2_lib.baseboard_fab2(sch_1):tp_cpu0_rsvd_57" )
			)
			( signal "TP_CPU0_RSVD_59"
				( objectStatus "@baseboard_fab2_lib.baseboard_fab2(sch_1):tp_cpu0_rsvd_59" )
			)
			( signal "TP_CPU0_RSVD_6"
				( objectStatus "@baseboard_fab2_lib.baseboard_fab2(sch_1):tp_cpu0_rsvd_6" )
			)
			( signal "TP_CPU0_RSVD_60"
				( objectStatus "@baseboard_fab2_lib.baseboard_fab2(sch_1):tp_cpu0_rsvd_60" )
			)
			( signal "TP_CPU0_RSVD_61"
				( objectStatus "@baseboard_fab2_lib.baseboard_fab2(sch_1):tp_cpu0_rsvd_61" )
			)
			( signal "TP_CPU0_RSVD_64"
				( objectStatus "@baseboard_fab2_lib.baseboard_fab2(sch_1):tp_cpu0_rsvd_64" )
			)
			( signal "TP_CPU0_RSVD_66"
				( objectStatus "@baseboard_fab2_lib.baseboard_fab2(sch_1):tp_cpu0_rsvd_66" )
			)
			( signal "TP_CPU0_RSVD_67"
				( objectStatus "@baseboard_fab2_lib.baseboard_fab2(sch_1):tp_cpu0_rsvd_67" )
			)
			( signal "TP_CPU0_RSVD_69"
				( objectStatus "@baseboard_fab2_lib.baseboard_fab2(sch_1):tp_cpu0_rsvd_69" )
			)
			( signal "TP_CPU0_RSVD_7"
				( objectStatus "@baseboard_fab2_lib.baseboard_fab2(sch_1):tp_cpu0_rsvd_7" )
			)
			( signal "TP_CPU0_RSVD_70"
				( objectStatus "@baseboard_fab2_lib.baseboard_fab2(sch_1):tp_cpu0_rsvd_70" )
			)
			( signal "TP_CPU0_RSVD_72"
				( objectStatus "@baseboard_fab2_lib.baseboard_fab2(sch_1):tp_cpu0_rsvd_72" )
			)
			( signal "TP_CPU0_RSVD_73"
				( objectStatus "@baseboard_fab2_lib.baseboard_fab2(sch_1):tp_cpu0_rsvd_73" )
			)
			( signal "TP_CPU0_RSVD_8"
				( objectStatus "@baseboard_fab2_lib.baseboard_fab2(sch_1):tp_cpu0_rsvd_8" )
			)
			( signal "TP_CPU0_RSVD_9"
				( objectStatus "@baseboard_fab2_lib.baseboard_fab2(sch_1):tp_cpu0_rsvd_9" )
			)
			( signal "VSENSE_PVCCIO_CPU0_SKT_VRTN"
				( objectStatus "@baseboard_fab2_lib.baseboard_fab2(sch_1):vsense_pvccio_cpu0_skt_vrtn" )
			)
			( signal "VSENSE_PVCCIO_CPU0_SKT_VSEN"
				( objectStatus "@baseboard_fab2_lib.baseboard_fab2(sch_1):vsense_pvccio_cpu0_skt_vsen" )
			)
			( signal "VSENSE_PVCCIOMCP_CPU0_SKT_VRTN"
				( objectStatus "@baseboard_fab2_lib.baseboard_fab2(sch_1):vsense_pvcciomcp_cpu0_skt_vrtn" )
			)
			( signal "VSENSE_PVCCIOMCP_CPU0_SKT_VSEN"
				( objectStatus "@baseboard_fab2_lib.baseboard_fab2(sch_1):vsense_pvcciomcp_cpu0_skt_vsen" )
			)
			( signal "VSENSE_PVCCMCP_CPU0_SKT_VRTN"
				( objectStatus "@baseboard_fab2_lib.baseboard_fab2(sch_1):vsense_pvccmcp_cpu0_skt_vrtn" )
			)
			( signal "VSENSE_PVCCMCP_CPU0_SKT_VSEN"
				( objectStatus "@baseboard_fab2_lib.baseboard_fab2(sch_1):vsense_pvccmcp_cpu0_skt_vsen" )
			)
			( signal "VSENSE_PVSA_CPU0_SKT_VRTN"
				( objectStatus "@baseboard_fab2_lib.baseboard_fab2(sch_1):vsense_pvsa_cpu0_skt_vrtn" )
			)
			( signal "VSENSE_PVSA_CPU0_SKT_VSEN"
				( objectStatus "@baseboard_fab2_lib.baseboard_fab2(sch_1):vsense_pvsa_cpu0_skt_vsen" )
			)
			( signal "FM_ADR_COMPLETE_ABC_N"
				( objectStatus "@baseboard_fab2_lib.baseboard_fab2(sch_1):fm_adr_complete_abc_n" )
			)
			( signal "FM_DIMM_EVENT_COD_N"
				( objectStatus "@baseboard_fab2_lib.baseboard_fab2(sch_1):fm_dimm_event_cod_n" )
			)
			( signal "M_A_VREF"
				( objectStatus "@baseboard_fab2_lib.baseboard_fab2(sch_1):m_a_vref" )
			)
			( signal "P12V_NVDIMM_ABC"
				( attribute "VOLTAGE" "12.0"
					( Units "uVoltage" "V" 1.000000)
					( Status sAliasFlattened )
					( Origin gFrontEnd )
				)
				( objectStatus "@baseboard_fab2_lib.baseboard_fab2(sch_1):p12v_nvdimm_abc" )
			)
			( signal "PVTT_ABC"
				( attribute "VOLTAGE" "0.6V"
					( Units "uVoltage" "V" 1.000000)
					( Status sAliasFlattened )
					( Origin gFrontEnd )
				)
				( objectStatus "@baseboard_fab2_lib.baseboard_fab2(sch_1):pvtt_abc" )
			)
			( signal "SMB_DDR_ABC_VPP_SCL"
				( objectStatus "@baseboard_fab2_lib.baseboard_fab2(sch_1):smb_ddr_abc_vpp_scl" )
			)
			( signal "SMB_DDR_ABC_VPP_SDA"
				( objectStatus "@baseboard_fab2_lib.baseboard_fab2(sch_1):smb_ddr_abc_vpp_sda" )
			)
			( signal "TP_CH_A_DIMM_A0_RFU_0"
				( objectStatus "@baseboard_fab2_lib.baseboard_fab2(sch_1):tp_ch_a_dimm_a0_rfu_0" )
			)
			( signal "TP_CH_A_DIMM_A0_RFU_1"
				( objectStatus "@baseboard_fab2_lib.baseboard_fab2(sch_1):tp_ch_a_dimm_a0_rfu_1" )
			)
			( signal "TP_CH_A_DIMM_A0_RFU_2"
				( objectStatus "@baseboard_fab2_lib.baseboard_fab2(sch_1):tp_ch_a_dimm_a0_rfu_2" )
			)
			( signal "TP_CH_A_DIMM_A1_RFU_0"
				( objectStatus "@baseboard_fab2_lib.baseboard_fab2(sch_1):tp_ch_a_dimm_a1_rfu_0" )
			)
			( signal "TP_CH_A_DIMM_A1_RFU_1"
				( objectStatus "@baseboard_fab2_lib.baseboard_fab2(sch_1):tp_ch_a_dimm_a1_rfu_1" )
			)
			( signal "TP_CH_A_DIMM_A1_RFU_2"
				( objectStatus "@baseboard_fab2_lib.baseboard_fab2(sch_1):tp_ch_a_dimm_a1_rfu_2" )
			)
			( signal "M_B_VREF"
				( objectStatus "@baseboard_fab2_lib.baseboard_fab2(sch_1):m_b_vref" )
			)
			( signal "TP_CH_B_DIMM_B0_RFU_0"
				( objectStatus "@baseboard_fab2_lib.baseboard_fab2(sch_1):tp_ch_b_dimm_b0_rfu_0" )
			)
			( signal "TP_CH_B_DIMM_B0_RFU_1"
				( objectStatus "@baseboard_fab2_lib.baseboard_fab2(sch_1):tp_ch_b_dimm_b0_rfu_1" )
			)
			( signal "TP_CH_B_DIMM_B0_RFU_2"
				( objectStatus "@baseboard_fab2_lib.baseboard_fab2(sch_1):tp_ch_b_dimm_b0_rfu_2" )
			)
			( signal "TP_CH_B_DIMM_B1_RFU_0"
				( objectStatus "@baseboard_fab2_lib.baseboard_fab2(sch_1):tp_ch_b_dimm_b1_rfu_0" )
			)
			( signal "TP_CH_B_DIMM_B1_RFU_1"
				( objectStatus "@baseboard_fab2_lib.baseboard_fab2(sch_1):tp_ch_b_dimm_b1_rfu_1" )
			)
			( signal "TP_CH_B_DIMM_B1_RFU_2"
				( objectStatus "@baseboard_fab2_lib.baseboard_fab2(sch_1):tp_ch_b_dimm_b1_rfu_2" )
			)
			( signal "M_C_VREF"
				( objectStatus "@baseboard_fab2_lib.baseboard_fab2(sch_1):m_c_vref" )
			)
			( signal "TP_CH_C_DIMM_C0_RFU_0"
				( objectStatus "@baseboard_fab2_lib.baseboard_fab2(sch_1):tp_ch_c_dimm_c0_rfu_0" )
			)
			( signal "TP_CH_C_DIMM_C0_RFU_1"
				( objectStatus "@baseboard_fab2_lib.baseboard_fab2(sch_1):tp_ch_c_dimm_c0_rfu_1" )
			)
			( signal "TP_CH_C_DIMM_C0_RFU_2"
				( objectStatus "@baseboard_fab2_lib.baseboard_fab2(sch_1):tp_ch_c_dimm_c0_rfu_2" )
			)
			( signal "TP_CH_C_DIMM_C1_RFU_0"
				( objectStatus "@baseboard_fab2_lib.baseboard_fab2(sch_1):tp_ch_c_dimm_c1_rfu_0" )
			)
			( signal "TP_CH_C_DIMM_C1_RFU_1"
				( objectStatus "@baseboard_fab2_lib.baseboard_fab2(sch_1):tp_ch_c_dimm_c1_rfu_1" )
			)
			( signal "TP_CH_C_DIMM_C1_RFU_2"
				( objectStatus "@baseboard_fab2_lib.baseboard_fab2(sch_1):tp_ch_c_dimm_c1_rfu_2" )
			)
			( signal "FM_ADR_COMPLETE_DEF_N"
				( objectStatus "@baseboard_fab2_lib.baseboard_fab2(sch_1):fm_adr_complete_def_n" )
			)
			( signal "M_D_VREF"
				( objectStatus "@baseboard_fab2_lib.baseboard_fab2(sch_1):m_d_vref" )
			)
			( signal "P12V_NVDIMM_DEF"
				( attribute "VOLTAGE" "12.0"
					( Units "uVoltage" "V" 1.000000)
					( Status sAliasFlattened )
					( Origin gFrontEnd )
				)
				( objectStatus "@baseboard_fab2_lib.baseboard_fab2(sch_1):p12v_nvdimm_def" )
			)
			( signal "PVPP_DEF"
				( attribute "VOLTAGE" "2.5V"
					( Units "uVoltage" "V" 1.000000)
					( Status sAliasFlattened )
					( Origin gFrontEnd )
				)
				( objectStatus "@baseboard_fab2_lib.baseboard_fab2(sch_1):pvpp_def" )
			)
			( signal "PVTT_DEF"
				( attribute "VOLTAGE" "0.6V"
					( Units "uVoltage" "V" 1.000000)
					( Status sAliasFlattened )
					( Origin gFrontEnd )
				)
				( objectStatus "@baseboard_fab2_lib.baseboard_fab2(sch_1):pvtt_def" )
			)
			( signal "SMB_DDR_DEF_VPP_SCL"
				( objectStatus "@baseboard_fab2_lib.baseboard_fab2(sch_1):smb_ddr_def_vpp_scl" )
			)
			( signal "SMB_DDR_DEF_VPP_SDA"
				( objectStatus "@baseboard_fab2_lib.baseboard_fab2(sch_1):smb_ddr_def_vpp_sda" )
			)
			( signal "TP_CH_D_DIMM_D0_RFU_0"
				( objectStatus "@baseboard_fab2_lib.baseboard_fab2(sch_1):tp_ch_d_dimm_d0_rfu_0" )
			)
			( signal "TP_CH_D_DIMM_D0_RFU_1"
				( objectStatus "@baseboard_fab2_lib.baseboard_fab2(sch_1):tp_ch_d_dimm_d0_rfu_1" )
			)
			( signal "TP_CH_D_DIMM_D0_RFU_2"
				( objectStatus "@baseboard_fab2_lib.baseboard_fab2(sch_1):tp_ch_d_dimm_d0_rfu_2" )
			)
			( signal "TP_CH_D_DIMM_D1_RFU_0"
				( objectStatus "@baseboard_fab2_lib.baseboard_fab2(sch_1):tp_ch_d_dimm_d1_rfu_0" )
			)
			( signal "TP_CH_D_DIMM_D1_RFU_1"
				( objectStatus "@baseboard_fab2_lib.baseboard_fab2(sch_1):tp_ch_d_dimm_d1_rfu_1" )
			)
			( signal "TP_CH_D_DIMM_D1_RFU_2"
				( objectStatus "@baseboard_fab2_lib.baseboard_fab2(sch_1):tp_ch_d_dimm_d1_rfu_2" )
			)
			( signal "M_E_VREF"
				( objectStatus "@baseboard_fab2_lib.baseboard_fab2(sch_1):m_e_vref" )
			)
			( signal "TP_CH_E_DIMM_E0_RFU_0"
				( objectStatus "@baseboard_fab2_lib.baseboard_fab2(sch_1):tp_ch_e_dimm_e0_rfu_0" )
			)
			( signal "TP_CH_E_DIMM_E0_RFU_1"
				( objectStatus "@baseboard_fab2_lib.baseboard_fab2(sch_1):tp_ch_e_dimm_e0_rfu_1" )
			)
			( signal "TP_CH_E_DIMM_E0_RFU_2"
				( objectStatus "@baseboard_fab2_lib.baseboard_fab2(sch_1):tp_ch_e_dimm_e0_rfu_2" )
			)
			( signal "TP_CH_E_DIMM_E1_RFU_0"
				( objectStatus "@baseboard_fab2_lib.baseboard_fab2(sch_1):tp_ch_e_dimm_e1_rfu_0" )
			)
			( signal "TP_CH_E_DIMM_E1_RFU_1"
				( objectStatus "@baseboard_fab2_lib.baseboard_fab2(sch_1):tp_ch_e_dimm_e1_rfu_1" )
			)
			( signal "TP_CH_E_DIMM_E1_RFU_2"
				( objectStatus "@baseboard_fab2_lib.baseboard_fab2(sch_1):tp_ch_e_dimm_e1_rfu_2" )
			)
			( signal "M_F_VREF"
				( objectStatus "@baseboard_fab2_lib.baseboard_fab2(sch_1):m_f_vref" )
			)
			( signal "TP_CH_F_DIMM_F0_RFU_0"
				( objectStatus "@baseboard_fab2_lib.baseboard_fab2(sch_1):tp_ch_f_dimm_f0_rfu_0" )
			)
			( signal "TP_CH_F_DIMM_F0_RFU_1"
				( objectStatus "@baseboard_fab2_lib.baseboard_fab2(sch_1):tp_ch_f_dimm_f0_rfu_1" )
			)
			( signal "TP_CH_F_DIMM_F0_RFU_2"
				( objectStatus "@baseboard_fab2_lib.baseboard_fab2(sch_1):tp_ch_f_dimm_f0_rfu_2" )
			)
			( signal "TP_CH_F_DIMM_F1_RFU_0"
				( objectStatus "@baseboard_fab2_lib.baseboard_fab2(sch_1):tp_ch_f_dimm_f1_rfu_0" )
			)
			( signal "TP_CH_F_DIMM_F1_RFU_1"
				( objectStatus "@baseboard_fab2_lib.baseboard_fab2(sch_1):tp_ch_f_dimm_f1_rfu_1" )
			)
			( signal "TP_CH_F_DIMM_F1_RFU_2"
				( objectStatus "@baseboard_fab2_lib.baseboard_fab2(sch_1):tp_ch_f_dimm_f1_rfu_2" )
			)
			( signal "A_CPU1_GHJ_RCOMP0"
				( objectStatus "@baseboard_fab2_lib.baseboard_fab2(sch_1):a_cpu1_ghj_rcomp0" )
			)
			( signal "A_CPU1_GHJ_RCOMP1"
				( objectStatus "@baseboard_fab2_lib.baseboard_fab2(sch_1):a_cpu1_ghj_rcomp1" )
			)
			( signal "A_CPU1_GHJ_RCOMP2"
				( objectStatus "@baseboard_fab2_lib.baseboard_fab2(sch_1):a_cpu1_ghj_rcomp2" )
			)
			( signal "A_CPU1_KLM_RCOMP0"
				( objectStatus "@baseboard_fab2_lib.baseboard_fab2(sch_1):a_cpu1_klm_rcomp0" )
			)
			( signal "A_CPU1_KLM_RCOMP1"
				( objectStatus "@baseboard_fab2_lib.baseboard_fab2(sch_1):a_cpu1_klm_rcomp1" )
			)
			( signal "A_CPU1_KLM_RCOMP2"
				( objectStatus "@baseboard_fab2_lib.baseboard_fab2(sch_1):a_cpu1_klm_rcomp2" )
			)
			( signal "A_CPU1_MCP01_RBIAS"
				( objectStatus "@baseboard_fab2_lib.baseboard_fab2(sch_1):a_cpu1_mcp01_rbias" )
			)
			( signal "A_CPU1_PE012_RBIAS"
				( objectStatus "@baseboard_fab2_lib.baseboard_fab2(sch_1):a_cpu1_pe012_rbias" )
			)
			( signal "A_CPU1_PE3_RBIAS"
				( objectStatus "@baseboard_fab2_lib.baseboard_fab2(sch_1):a_cpu1_pe3_rbias" )
			)
			( signal "A_CPU1_UPI01_RBIAS"
				( objectStatus "@baseboard_fab2_lib.baseboard_fab2(sch_1):a_cpu1_upi01_rbias" )
			)
			( signal "A_CPU1_UPI2_RBIAS"
				( objectStatus "@baseboard_fab2_lib.baseboard_fab2(sch_1):a_cpu1_upi2_rbias" )
			)
			( signal "CLK_100M_CPU1_BCLK0_DN"
				( objectStatus "@baseboard_fab2_lib.baseboard_fab2(sch_1):clk_100m_cpu1_bclk0_dn" )
			)
			( signal "CLK_100M_CPU1_BCLK0_DP"
				( objectStatus "@baseboard_fab2_lib.baseboard_fab2(sch_1):clk_100m_cpu1_bclk0_dp" )
			)
			( signal "CLK_100M_CPU1_BCLK1_DN"
				( objectStatus "@baseboard_fab2_lib.baseboard_fab2(sch_1):clk_100m_cpu1_bclk1_dn" )
			)
			( signal "CLK_100M_CPU1_BCLK1_DP"
				( objectStatus "@baseboard_fab2_lib.baseboard_fab2(sch_1):clk_100m_cpu1_bclk1_dp" )
			)
			( signal "CLK_100M_CPU1_BCLK2_DN"
				( objectStatus "@baseboard_fab2_lib.baseboard_fab2(sch_1):clk_100m_cpu1_bclk2_dn" )
			)
			( signal "CLK_100M_CPU1_BCLK2_DP"
				( objectStatus "@baseboard_fab2_lib.baseboard_fab2(sch_1):clk_100m_cpu1_bclk2_dp" )
			)
			( signal "FM_CPU1_PKGID0"
				( objectStatus "@baseboard_fab2_lib.baseboard_fab2(sch_1):fm_cpu1_pkgid0" )
			)
			( signal "FM_CPU1_PKGID1"
				( objectStatus "@baseboard_fab2_lib.baseboard_fab2(sch_1):fm_cpu1_pkgid1" )
			)
			( signal "FM_CPU1_PKGID2"
				( objectStatus "@baseboard_fab2_lib.baseboard_fab2(sch_1):fm_cpu1_pkgid2" )
			)
			( signal "FM_CPU1_PROC_ID0"
				( objectStatus "@baseboard_fab2_lib.baseboard_fab2(sch_1):fm_cpu1_proc_id0" )
			)
			( signal "FM_CPU1_PROC_ID1"
				( objectStatus "@baseboard_fab2_lib.baseboard_fab2(sch_1):fm_cpu1_proc_id1" )
			)
			( signal "FM_CPU1_SKTOCC_LVT3_N"
				( objectStatus "@baseboard_fab2_lib.baseboard_fab2(sch_1):fm_cpu1_sktocc_lvt3_n" )
			)
			( signal "FM_CPU1_SM_WP"
				( objectStatus "@baseboard_fab2_lib.baseboard_fab2(sch_1):fm_cpu1_sm_wp" )
			)
			( signal "H_CPU1_BMCINIT"
				( objectStatus "@baseboard_fab2_lib.baseboard_fab2(sch_1):h_cpu1_bmcinit" )
			)
			( signal "H_CPU1_CATERR_G_N"
				( objectStatus "@baseboard_fab2_lib.baseboard_fab2(sch_1):h_cpu1_caterr_g_n" )
			)
			( signal "H_CPU1_ERR0_G_N"
				( objectStatus "@baseboard_fab2_lib.baseboard_fab2(sch_1):h_cpu1_err0_g_n" )
			)
			( signal "H_CPU1_ERR1_G_N"
				( objectStatus "@baseboard_fab2_lib.baseboard_fab2(sch_1):h_cpu1_err1_g_n" )
			)
			( signal "H_CPU1_ERR2_G_N"
				( objectStatus "@baseboard_fab2_lib.baseboard_fab2(sch_1):h_cpu1_err2_g_n" )
			)
			( signal "H_CPU1_FAST_WAKE_N"
				( objectStatus "@baseboard_fab2_lib.baseboard_fab2(sch_1):h_cpu1_fast_wake_n" )
			)
			( signal "H_CPU1_MEMGHJ_MEMHOT_G_N"
				( objectStatus "@baseboard_fab2_lib.baseboard_fab2(sch_1):h_cpu1_memghj_memhot_g_n" )
			)
			( signal "H_CPU1_MEMKLM_MEMHOT_G_N"
				( objectStatus "@baseboard_fab2_lib.baseboard_fab2(sch_1):h_cpu1_memklm_memhot_g_n" )
			)
			( signal "H_CPU1_MSMI_G_N"
				( objectStatus "@baseboard_fab2_lib.baseboard_fab2(sch_1):h_cpu1_msmi_g_n" )
			)
			( signal "H_CPU1_PROCHOT_G_N"
				( objectStatus "@baseboard_fab2_lib.baseboard_fab2(sch_1):h_cpu1_prochot_g_n" )
			)
			( signal "H_CPU1_THERMTRIP_G_N"
				( objectStatus "@baseboard_fab2_lib.baseboard_fab2(sch_1):h_cpu1_thermtrip_g_n" )
			)
			( signal "H_PM_SYNC_GTL_R2"
				( objectStatus "@baseboard_fab2_lib.baseboard_fab2(sch_1):h_pm_sync_gtl_r2" )
			)
			( signal "H_PMSYNC_CLK_24M_CPU1"
				( objectStatus "@baseboard_fab2_lib.baseboard_fab2(sch_1):h_pmsync_clk_24m_cpu1" )
			)
			( signal "M_G_CPU_VREF"
				( objectStatus "@baseboard_fab2_lib.baseboard_fab2(sch_1):m_g_cpu_vref" )
			)
			( signal "M_GHJ_RST_N"
				( objectStatus "@baseboard_fab2_lib.baseboard_fab2(sch_1):m_ghj_rst_n" )
			)
			( signal "M_H_CPU_VREF"
				( objectStatus "@baseboard_fab2_lib.baseboard_fab2(sch_1):m_h_cpu_vref" )
			)
			( signal "M_J_CPU_VREF"
				( objectStatus "@baseboard_fab2_lib.baseboard_fab2(sch_1):m_j_cpu_vref" )
			)
			( signal "M_K_CPU_VREF"
				( objectStatus "@baseboard_fab2_lib.baseboard_fab2(sch_1):m_k_cpu_vref" )
			)
			( signal "M_KLM_RST_N"
				( objectStatus "@baseboard_fab2_lib.baseboard_fab2(sch_1):m_klm_rst_n" )
			)
			( signal "M_L_CPU_VREF"
				( objectStatus "@baseboard_fab2_lib.baseboard_fab2(sch_1):m_l_cpu_vref" )
			)
			( signal "M_M_CPU_VREF"
				( objectStatus "@baseboard_fab2_lib.baseboard_fab2(sch_1):m_m_cpu_vref" )
			)
			( signal "PD_CPU1_BIST_ENABLE"
				( objectStatus "@baseboard_fab2_lib.baseboard_fab2(sch_1):pd_cpu1_bist_enable" )
			)
			( signal "PD_CPU1_KSFC_DIS"
				( objectStatus "@baseboard_fab2_lib.baseboard_fab2(sch_1):pd_cpu1_ksfc_dis" )
			)
			( signal "PD_CPU1_TEST12"
				( objectStatus "@baseboard_fab2_lib.baseboard_fab2(sch_1):pd_cpu1_test12" )
			)
			( signal "PD_CPU1_TEST13"
				( objectStatus "@baseboard_fab2_lib.baseboard_fab2(sch_1):pd_cpu1_test13" )
			)
			( signal "PD_CPU1_TEST14"
				( objectStatus "@baseboard_fab2_lib.baseboard_fab2(sch_1):pd_cpu1_test14" )
			)
			( signal "PD_CPU1_TXT_PLTEN"
				( objectStatus "@baseboard_fab2_lib.baseboard_fab2(sch_1):pd_cpu1_txt_plten" )
			)
			( signal "PD_PIROM_CPU1_ADDR1"
				( objectStatus "@baseboard_fab2_lib.baseboard_fab2(sch_1):pd_pirom_cpu1_addr1" )
			)
			( signal "PD_PIROM_CPU1_ADDR2"
				( objectStatus "@baseboard_fab2_lib.baseboard_fab2(sch_1):pd_pirom_cpu1_addr2" )
			)
			( signal "PU_CPU1_EAR_N"
				( objectStatus "@baseboard_fab2_lib.baseboard_fab2(sch_1):pu_cpu1_ear_n" )
			)
			( signal "PU_CPU1_FRMAGENT"
				( objectStatus "@baseboard_fab2_lib.baseboard_fab2(sch_1):pu_cpu1_frmagent" )
			)
			( signal "PU_CPU1_LEGACY_SKT"
				( objectStatus "@baseboard_fab2_lib.baseboard_fab2(sch_1):pu_cpu1_legacy_skt" )
			)
			( signal "PU_CPU1_SAFE_MODE_BOOT"
				( objectStatus "@baseboard_fab2_lib.baseboard_fab2(sch_1):pu_cpu1_safe_mode_boot" )
			)
			( signal "PU_CPU1_SOCKET_ID_0"
				( objectStatus "@baseboard_fab2_lib.baseboard_fab2(sch_1):pu_cpu1_socket_id_0" )
			)
			( signal "PU_CPU1_SOCKET_ID_1"
				( objectStatus "@baseboard_fab2_lib.baseboard_fab2(sch_1):pu_cpu1_socket_id_1" )
			)
			( signal "PU_CPU1_TSC_SYNC"
				( objectStatus "@baseboard_fab2_lib.baseboard_fab2(sch_1):pu_cpu1_tsc_sync" )
			)
			( signal "PU_CPU1_TXT_AGENT"
				( objectStatus "@baseboard_fab2_lib.baseboard_fab2(sch_1):pu_cpu1_txt_agent" )
			)
			( signal "PU_PIROM_CPU1_ADDR0"
				( objectStatus "@baseboard_fab2_lib.baseboard_fab2(sch_1):pu_pirom_cpu1_addr0" )
			)
			( signal "PVCCIO_CPU1"
				( attribute "VOLTAGE" "1.1V"
					( Units "uVoltage" "V" 1.000000)
					( Status sAliasFlattened )
					( Origin gFrontEnd )
				)
				( objectStatus "@baseboard_fab2_lib.baseboard_fab2(sch_1):pvccio_cpu1" )
			)
			( signal "PWRGD_CPU1_DRAMPWROK_GHJ_G"
				( objectStatus "@baseboard_fab2_lib.baseboard_fab2(sch_1):pwrgd_cpu1_drampwrok_ghj_g" )
			)
			( signal "PWRGD_CPU1_DRAMPWROK_KLM_G"
				( objectStatus "@baseboard_fab2_lib.baseboard_fab2(sch_1):pwrgd_cpu1_drampwrok_klm_g" )
			)
			( signal "PWRGD_CPU1_G"
				( objectStatus "@baseboard_fab2_lib.baseboard_fab2(sch_1):pwrgd_cpu1_g" )
			)
			( signal "RST_CPU1_G_N"
				( objectStatus "@baseboard_fab2_lib.baseboard_fab2(sch_1):rst_cpu1_g_n" )
			)
			( signal "SMB_CPU1_PE_HP_GTL_SCL"
				( objectStatus "@baseboard_fab2_lib.baseboard_fab2(sch_1):smb_cpu1_pe_hp_gtl_scl" )
			)
			( signal "SMB_CPU1_PE_HP_GTL_SDA"
				( objectStatus "@baseboard_fab2_lib.baseboard_fab2(sch_1):smb_cpu1_pe_hp_gtl_sda" )
			)
			( signal "SMB_DDR_GHJ_SCL_G_R"
				( objectStatus "@baseboard_fab2_lib.baseboard_fab2(sch_1):smb_ddr_ghj_scl_g_r" )
			)
			( signal "SMB_DDR_GHJ_SDA_G_R"
				( objectStatus "@baseboard_fab2_lib.baseboard_fab2(sch_1):smb_ddr_ghj_sda_g_r" )
			)
			( signal "SMB_DDR_KLM_SCL_G_R"
				( objectStatus "@baseboard_fab2_lib.baseboard_fab2(sch_1):smb_ddr_klm_scl_g_r" )
			)
			( signal "SMB_DDR_KLM_SDA_G_R"
				( objectStatus "@baseboard_fab2_lib.baseboard_fab2(sch_1):smb_ddr_klm_sda_g_r" )
			)
			( signal "SMB_PIROM_CPU1_SCL"
				( objectStatus "@baseboard_fab2_lib.baseboard_fab2(sch_1):smb_pirom_cpu1_scl" )
			)
			( signal "SMB_PIROM_CPU1_SDA"
				( objectStatus "@baseboard_fab2_lib.baseboard_fab2(sch_1):smb_pirom_cpu1_sda" )
			)
			( signal "SVID_ALERT0_CPU1_N"
				( objectStatus "@baseboard_fab2_lib.baseboard_fab2(sch_1):svid_alert0_cpu1_n" )
			)
			( signal "SVID_ALERT0_CPU1_R_N"
				( objectStatus "@baseboard_fab2_lib.baseboard_fab2(sch_1):svid_alert0_cpu1_r_n" )
			)
			( signal "SVID_ALERT1_CPU1_N"
				( objectStatus "@baseboard_fab2_lib.baseboard_fab2(sch_1):svid_alert1_cpu1_n" )
			)
			( signal "SVID_ALERT1_CPU1_R_N"
				( objectStatus "@baseboard_fab2_lib.baseboard_fab2(sch_1):svid_alert1_cpu1_r_n" )
			)
			( signal "SVID_CLK0_CPU1"
				( objectStatus "@baseboard_fab2_lib.baseboard_fab2(sch_1):svid_clk0_cpu1" )
			)
			( signal "SVID_CLK0_CPU1_R"
				( objectStatus "@baseboard_fab2_lib.baseboard_fab2(sch_1):svid_clk0_cpu1_r" )
			)
			( signal "SVID_CLK1_CPU1"
				( objectStatus "@baseboard_fab2_lib.baseboard_fab2(sch_1):svid_clk1_cpu1" )
			)
			( signal "SVID_CLK1_CPU1_R"
				( objectStatus "@baseboard_fab2_lib.baseboard_fab2(sch_1):svid_clk1_cpu1_r" )
			)
			( signal "SVID_DIO0_CPU1"
				( objectStatus "@baseboard_fab2_lib.baseboard_fab2(sch_1):svid_dio0_cpu1" )
			)
			( signal "SVID_DIO0_CPU1_R"
				( objectStatus "@baseboard_fab2_lib.baseboard_fab2(sch_1):svid_dio0_cpu1_r" )
			)
			( signal "SVID_DIO1_CPU1"
				( objectStatus "@baseboard_fab2_lib.baseboard_fab2(sch_1):svid_dio1_cpu1" )
			)
			( signal "SVID_DIO1_CPU1_R"
				( objectStatus "@baseboard_fab2_lib.baseboard_fab2(sch_1):svid_dio1_cpu1_r" )
			)
			( signal "TP_CPU1_NMI"
				( objectStatus "@baseboard_fab2_lib.baseboard_fab2(sch_1):tp_cpu1_nmi" )
			)
			( signal "TP_CPU1_PROC_DIS_G_N"
				( objectStatus "@baseboard_fab2_lib.baseboard_fab2(sch_1):tp_cpu1_proc_dis_g_n" )
			)
			( signal "TP_CPU1_SOCKET_ID_2"
				( objectStatus "@baseboard_fab2_lib.baseboard_fab2(sch_1):tp_cpu1_socket_id_2" )
			)
			( signal "TP_XDP_CPU1_OBSDATA_B0_MBP2_N"
				( objectStatus "@baseboard_fab2_lib.baseboard_fab2(sch_1):tp_xdp_cpu1_obsdata_b0_mbp2_n" )
			)
			( signal "TP_XDP_CPU1_OBSDATA_B1_MBP3_N"
				( objectStatus "@baseboard_fab2_lib.baseboard_fab2(sch_1):tp_xdp_cpu1_obsdata_b1_mbp3_n" )
			)
			( signal "TP_XDP_CPU1_OBSDATA_B2_MBP4_N"
				( objectStatus "@baseboard_fab2_lib.baseboard_fab2(sch_1):tp_xdp_cpu1_obsdata_b2_mbp4_n" )
			)
			( signal "TP_XDP_CPU1_OBSDATA_B3_MBP5_N"
				( objectStatus "@baseboard_fab2_lib.baseboard_fab2(sch_1):tp_xdp_cpu1_obsdata_b3_mbp5_n" )
			)
			( signal "XDP_CPU1_TDI"
				( objectStatus "@baseboard_fab2_lib.baseboard_fab2(sch_1):xdp_cpu1_tdi" )
			)
			( signal "XDP_CPU1_TDO"
				( objectStatus "@baseboard_fab2_lib.baseboard_fab2(sch_1):xdp_cpu1_tdo" )
			)
			( signal "CLK_100M_CPU1_RC_REFCLK0_DN"
				( objectStatus "@baseboard_fab2_lib.baseboard_fab2(sch_1):clk_100m_cpu1_rc_refclk0_dn" )
			)
			( signal "CLK_100M_CPU1_RC_REFCLK0_DP"
				( objectStatus "@baseboard_fab2_lib.baseboard_fab2(sch_1):clk_100m_cpu1_rc_refclk0_dp" )
			)
			( signal "CLK_322M_OSC_CPU1_RC_DN"
				( objectStatus "@baseboard_fab2_lib.baseboard_fab2(sch_1):clk_322m_osc_cpu1_rc_dn" )
			)
			( signal "CLK_322M_OSC_CPU1_RC_DP"
				( objectStatus "@baseboard_fab2_lib.baseboard_fab2(sch_1):clk_322m_osc_cpu1_rc_dp" )
			)
			( signal "FM_CPU1_RC_ERROR_N"
				( objectStatus "@baseboard_fab2_lib.baseboard_fab2(sch_1):fm_cpu1_rc_error_n" )
			)
			( signal "H_CPU1_FIVR_FAULT_G"
				( objectStatus "@baseboard_fab2_lib.baseboard_fab2(sch_1):h_cpu1_fivr_fault_g" )
			)
			( signal "P1V8_MCP_CPU1"
				( attribute "VOLTAGE" "1.8"
					( Units "uVoltage" "V" 1.000000)
					( Status sAliasFlattened )
					( Origin gFrontEnd )
				)
				( objectStatus "@baseboard_fab2_lib.baseboard_fab2(sch_1):p1v8_mcp_cpu1" )
			)
			( signal "PD_CPU1_DMIMODE_OVERRIDE"
				( objectStatus "@baseboard_fab2_lib.baseboard_fab2(sch_1):pd_cpu1_dmimode_override" )
			)
			( signal "PD_CPU1_RSVD_TEST_1"
				( objectStatus "@baseboard_fab2_lib.baseboard_fab2(sch_1):pd_cpu1_rsvd_test_1" )
			)
			( signal "PD_CPU1_RSVD_TEST_2"
				( objectStatus "@baseboard_fab2_lib.baseboard_fab2(sch_1):pd_cpu1_rsvd_test_2" )
			)
			( signal "PVCCMCP_CPU1"
				( attribute "VOLTAGE" "+0.95"
					( Units "uVoltage" "V" 1.000000)
					( Status sAliasFlattened )
					( Origin gFrontEnd )
				)
				( objectStatus "@baseboard_fab2_lib.baseboard_fab2(sch_1):pvccmcp_cpu1" )
			)
			( signal "TP_CPU1_RSVD_194"
				( objectStatus "@baseboard_fab2_lib.baseboard_fab2(sch_1):tp_cpu1_rsvd_194" )
			)
			( signal "TP_CPU1_RSVD_198"
				( objectStatus "@baseboard_fab2_lib.baseboard_fab2(sch_1):tp_cpu1_rsvd_198" )
			)
			( signal "TP_CPU1_RSVD_199"
				( objectStatus "@baseboard_fab2_lib.baseboard_fab2(sch_1):tp_cpu1_rsvd_199" )
			)
			( signal "TP_CPU1_RSVD_204"
				( objectStatus "@baseboard_fab2_lib.baseboard_fab2(sch_1):tp_cpu1_rsvd_204" )
			)
			( signal "TP_CPU1_RSVD_205"
				( objectStatus "@baseboard_fab2_lib.baseboard_fab2(sch_1):tp_cpu1_rsvd_205" )
			)
			( signal "TP_CPU1_RSVD_208"
				( objectStatus "@baseboard_fab2_lib.baseboard_fab2(sch_1):tp_cpu1_rsvd_208" )
			)
			( signal "TP_CPU1_RSVD_210"
				( objectStatus "@baseboard_fab2_lib.baseboard_fab2(sch_1):tp_cpu1_rsvd_210" )
			)
			( signal "TP_CPU1_RSVD_211"
				( objectStatus "@baseboard_fab2_lib.baseboard_fab2(sch_1):tp_cpu1_rsvd_211" )
			)
			( signal "TP_CPU1_RSVD_212"
				( objectStatus "@baseboard_fab2_lib.baseboard_fab2(sch_1):tp_cpu1_rsvd_212" )
			)
			( signal "TP_CPU1_RSVD_214"
				( objectStatus "@baseboard_fab2_lib.baseboard_fab2(sch_1):tp_cpu1_rsvd_214" )
			)
			( signal "TP_CPU1_RSVD_216"
				( objectStatus "@baseboard_fab2_lib.baseboard_fab2(sch_1):tp_cpu1_rsvd_216" )
			)
			( signal "TP_CPU1_RSVD_217"
				( objectStatus "@baseboard_fab2_lib.baseboard_fab2(sch_1):tp_cpu1_rsvd_217" )
			)
			( signal "TP_CPU1_RSVD_218"
				( objectStatus "@baseboard_fab2_lib.baseboard_fab2(sch_1):tp_cpu1_rsvd_218" )
			)
			( signal "TP_CPU1_RSVD_219"
				( objectStatus "@baseboard_fab2_lib.baseboard_fab2(sch_1):tp_cpu1_rsvd_219" )
			)
			( signal "TP_CPU1_RSVD_222"
				( objectStatus "@baseboard_fab2_lib.baseboard_fab2(sch_1):tp_cpu1_rsvd_222" )
			)
			( signal "TP_CPU1_RSVD_223"
				( objectStatus "@baseboard_fab2_lib.baseboard_fab2(sch_1):tp_cpu1_rsvd_223" )
			)
			( signal "TP_CPU1_RSVD_224"
				( objectStatus "@baseboard_fab2_lib.baseboard_fab2(sch_1):tp_cpu1_rsvd_224" )
			)
			( signal "TP_CPU1_RSVD_225"
				( objectStatus "@baseboard_fab2_lib.baseboard_fab2(sch_1):tp_cpu1_rsvd_225" )
			)
			( signal "TP_CPU1_RSVD_226"
				( objectStatus "@baseboard_fab2_lib.baseboard_fab2(sch_1):tp_cpu1_rsvd_226" )
			)
			( signal "TP_CPU1_RSVD_227"
				( objectStatus "@baseboard_fab2_lib.baseboard_fab2(sch_1):tp_cpu1_rsvd_227" )
			)
			( signal "TP_CPU1_RSVD_228"
				( objectStatus "@baseboard_fab2_lib.baseboard_fab2(sch_1):tp_cpu1_rsvd_228" )
			)
			( signal "TP_CPU1_RSVD_229"
				( objectStatus "@baseboard_fab2_lib.baseboard_fab2(sch_1):tp_cpu1_rsvd_229" )
			)
			( signal "TP_CPU1_RSVD_230"
				( objectStatus "@baseboard_fab2_lib.baseboard_fab2(sch_1):tp_cpu1_rsvd_230" )
			)
			( signal "TP_CPU1_RSVD_231"
				( objectStatus "@baseboard_fab2_lib.baseboard_fab2(sch_1):tp_cpu1_rsvd_231" )
			)
			( signal "TP_CPU1_RSVD_232"
				( objectStatus "@baseboard_fab2_lib.baseboard_fab2(sch_1):tp_cpu1_rsvd_232" )
			)
			( signal "TP_CPU1_RSVD_233"
				( objectStatus "@baseboard_fab2_lib.baseboard_fab2(sch_1):tp_cpu1_rsvd_233" )
			)
			( signal "TP_CPU1_RSVD_234"
				( objectStatus "@baseboard_fab2_lib.baseboard_fab2(sch_1):tp_cpu1_rsvd_234" )
			)
			( signal "TP_CPU1_RSVD_235"
				( objectStatus "@baseboard_fab2_lib.baseboard_fab2(sch_1):tp_cpu1_rsvd_235" )
			)
			( signal "TP_CPU1_RSVD_236"
				( objectStatus "@baseboard_fab2_lib.baseboard_fab2(sch_1):tp_cpu1_rsvd_236" )
			)
			( signal "TP_CPU1_RSVD_237"
				( objectStatus "@baseboard_fab2_lib.baseboard_fab2(sch_1):tp_cpu1_rsvd_237" )
			)
			( signal "TP_CPU1_RSVD_238"
				( objectStatus "@baseboard_fab2_lib.baseboard_fab2(sch_1):tp_cpu1_rsvd_238" )
			)
			( signal "TP_CPU1_RSVD_239"
				( objectStatus "@baseboard_fab2_lib.baseboard_fab2(sch_1):tp_cpu1_rsvd_239" )
			)
			( signal "TP_CPU1_RSVD_240"
				( objectStatus "@baseboard_fab2_lib.baseboard_fab2(sch_1):tp_cpu1_rsvd_240" )
			)
			( signal "TP_CPU1_RSVD_241"
				( objectStatus "@baseboard_fab2_lib.baseboard_fab2(sch_1):tp_cpu1_rsvd_241" )
			)
			( signal "TP_CPU1_RSVD_242"
				( objectStatus "@baseboard_fab2_lib.baseboard_fab2(sch_1):tp_cpu1_rsvd_242" )
			)
			( signal "TP_CPU1_RSVD_243"
				( objectStatus "@baseboard_fab2_lib.baseboard_fab2(sch_1):tp_cpu1_rsvd_243" )
			)
			( signal "TP_CPU1_RSVD_244"
				( objectStatus "@baseboard_fab2_lib.baseboard_fab2(sch_1):tp_cpu1_rsvd_244" )
			)
			( signal "TP_CPU1_RSVD_245"
				( objectStatus "@baseboard_fab2_lib.baseboard_fab2(sch_1):tp_cpu1_rsvd_245" )
			)
			( signal "TP_CPU1_RSVD_246"
				( objectStatus "@baseboard_fab2_lib.baseboard_fab2(sch_1):tp_cpu1_rsvd_246" )
			)
			( signal "TP_CPU1_RSVD_247"
				( objectStatus "@baseboard_fab2_lib.baseboard_fab2(sch_1):tp_cpu1_rsvd_247" )
			)
			( signal "TP_CPU1_RSVD_248"
				( objectStatus "@baseboard_fab2_lib.baseboard_fab2(sch_1):tp_cpu1_rsvd_248" )
			)
			( signal "TP_CPU1_RSVD_249"
				( objectStatus "@baseboard_fab2_lib.baseboard_fab2(sch_1):tp_cpu1_rsvd_249" )
			)
			( signal "TP_CPU1_RSVD_250"
				( objectStatus "@baseboard_fab2_lib.baseboard_fab2(sch_1):tp_cpu1_rsvd_250" )
			)
			( signal "TP_CPU1_RSVD_251"
				( objectStatus "@baseboard_fab2_lib.baseboard_fab2(sch_1):tp_cpu1_rsvd_251" )
			)
			( signal "TP_CPU1_RSVD_252"
				( objectStatus "@baseboard_fab2_lib.baseboard_fab2(sch_1):tp_cpu1_rsvd_252" )
			)
			( signal "TP_CPU1_RSVD_253"
				( objectStatus "@baseboard_fab2_lib.baseboard_fab2(sch_1):tp_cpu1_rsvd_253" )
			)
			( signal "TP_CPU1_RSVD_254"
				( objectStatus "@baseboard_fab2_lib.baseboard_fab2(sch_1):tp_cpu1_rsvd_254" )
			)
			( signal "TP_CPU1_RSVD_256"
				( objectStatus "@baseboard_fab2_lib.baseboard_fab2(sch_1):tp_cpu1_rsvd_256" )
			)
			( signal "TP_CPU1_RSVD_258"
				( objectStatus "@baseboard_fab2_lib.baseboard_fab2(sch_1):tp_cpu1_rsvd_258" )
			)
			( signal "TP_CPU1_RSVD_259"
				( objectStatus "@baseboard_fab2_lib.baseboard_fab2(sch_1):tp_cpu1_rsvd_259" )
			)
			( signal "TP_CPU1_RSVD_260"
				( objectStatus "@baseboard_fab2_lib.baseboard_fab2(sch_1):tp_cpu1_rsvd_260" )
			)
			( signal "TP_CPU1_RSVD_261"
				( objectStatus "@baseboard_fab2_lib.baseboard_fab2(sch_1):tp_cpu1_rsvd_261" )
			)
			( signal "TP_CPU1_RSVD_262"
				( objectStatus "@baseboard_fab2_lib.baseboard_fab2(sch_1):tp_cpu1_rsvd_262" )
			)
			( signal "TP_CPU1_RSVD_263"
				( objectStatus "@baseboard_fab2_lib.baseboard_fab2(sch_1):tp_cpu1_rsvd_263" )
			)
			( signal "TP_CPU1_RSVD_264"
				( objectStatus "@baseboard_fab2_lib.baseboard_fab2(sch_1):tp_cpu1_rsvd_264" )
			)
			( signal "TP_CPU1_RSVD_265"
				( objectStatus "@baseboard_fab2_lib.baseboard_fab2(sch_1):tp_cpu1_rsvd_265" )
			)
			( signal "TP_CPU1_RSVD_266"
				( objectStatus "@baseboard_fab2_lib.baseboard_fab2(sch_1):tp_cpu1_rsvd_266" )
			)
			( signal "TP_CPU1_RSVD_267"
				( objectStatus "@baseboard_fab2_lib.baseboard_fab2(sch_1):tp_cpu1_rsvd_267" )
			)
			( signal "TP_CPU1_RSVD_268"
				( objectStatus "@baseboard_fab2_lib.baseboard_fab2(sch_1):tp_cpu1_rsvd_268" )
			)
			( signal "TP_CPU1_RSVD_269"
				( objectStatus "@baseboard_fab2_lib.baseboard_fab2(sch_1):tp_cpu1_rsvd_269" )
			)
			( signal "TP_CPU1_RSVD_270"
				( objectStatus "@baseboard_fab2_lib.baseboard_fab2(sch_1):tp_cpu1_rsvd_270" )
			)
			( signal "TP_CPU1_RSVD_271"
				( objectStatus "@baseboard_fab2_lib.baseboard_fab2(sch_1):tp_cpu1_rsvd_271" )
			)
			( signal "TP_CPU1_RSVD_272"
				( objectStatus "@baseboard_fab2_lib.baseboard_fab2(sch_1):tp_cpu1_rsvd_272" )
			)
			( signal "TP_CPU1_RSVD_273"
				( objectStatus "@baseboard_fab2_lib.baseboard_fab2(sch_1):tp_cpu1_rsvd_273" )
			)
			( signal "TP_CPU1_RSVD_274"
				( objectStatus "@baseboard_fab2_lib.baseboard_fab2(sch_1):tp_cpu1_rsvd_274" )
			)
			( signal "TP_CPU1_RSVD_275"
				( objectStatus "@baseboard_fab2_lib.baseboard_fab2(sch_1):tp_cpu1_rsvd_275" )
			)
			( signal "TP_CPU1_RSVD_276"
				( objectStatus "@baseboard_fab2_lib.baseboard_fab2(sch_1):tp_cpu1_rsvd_276" )
			)
			( signal "TP_CPU1_RSVD_277"
				( objectStatus "@baseboard_fab2_lib.baseboard_fab2(sch_1):tp_cpu1_rsvd_277" )
			)
			( signal "TP_CPU1_RSVD_278"
				( objectStatus "@baseboard_fab2_lib.baseboard_fab2(sch_1):tp_cpu1_rsvd_278" )
			)
			( signal "TP_CPU1_RSVD_279"
				( objectStatus "@baseboard_fab2_lib.baseboard_fab2(sch_1):tp_cpu1_rsvd_279" )
			)
			( signal "TP_CPU1_RSVD_280"
				( objectStatus "@baseboard_fab2_lib.baseboard_fab2(sch_1):tp_cpu1_rsvd_280" )
			)
			( signal "TP_CPU1_RSVD_281"
				( objectStatus "@baseboard_fab2_lib.baseboard_fab2(sch_1):tp_cpu1_rsvd_281" )
			)
			( signal "TP_CPU1_RSVD_282"
				( objectStatus "@baseboard_fab2_lib.baseboard_fab2(sch_1):tp_cpu1_rsvd_282" )
			)
			( signal "TP_CPU1_RSVD_283"
				( objectStatus "@baseboard_fab2_lib.baseboard_fab2(sch_1):tp_cpu1_rsvd_283" )
			)
			( signal "TP_CPU1_RSVD_284"
				( objectStatus "@baseboard_fab2_lib.baseboard_fab2(sch_1):tp_cpu1_rsvd_284" )
			)
			( signal "TP_CPU1_RSVD_285"
				( objectStatus "@baseboard_fab2_lib.baseboard_fab2(sch_1):tp_cpu1_rsvd_285" )
			)
			( signal "TP_CPU1_RSVD_286"
				( objectStatus "@baseboard_fab2_lib.baseboard_fab2(sch_1):tp_cpu1_rsvd_286" )
			)
			( signal "TP_CPU1_RSVD_287"
				( objectStatus "@baseboard_fab2_lib.baseboard_fab2(sch_1):tp_cpu1_rsvd_287" )
			)
			( signal "TP_CPU1_RSVD_288"
				( objectStatus "@baseboard_fab2_lib.baseboard_fab2(sch_1):tp_cpu1_rsvd_288" )
			)
			( signal "TP_CPU1_RSVD_289"
				( objectStatus "@baseboard_fab2_lib.baseboard_fab2(sch_1):tp_cpu1_rsvd_289" )
			)
			( signal "TP_CPU1_RSVD_290"
				( objectStatus "@baseboard_fab2_lib.baseboard_fab2(sch_1):tp_cpu1_rsvd_290" )
			)
			( signal "TP_CPU1_RSVD_291"
				( objectStatus "@baseboard_fab2_lib.baseboard_fab2(sch_1):tp_cpu1_rsvd_291" )
			)
			( signal "TP_CPU1_RSVD_292"
				( objectStatus "@baseboard_fab2_lib.baseboard_fab2(sch_1):tp_cpu1_rsvd_292" )
			)
			( signal "TP_CPU1_RSVD_293"
				( objectStatus "@baseboard_fab2_lib.baseboard_fab2(sch_1):tp_cpu1_rsvd_293" )
			)
			( signal "TP_CPU1_RSVD_298"
				( objectStatus "@baseboard_fab2_lib.baseboard_fab2(sch_1):tp_cpu1_rsvd_298" )
			)
			( signal "TP_CPU1_RSVD_299"
				( objectStatus "@baseboard_fab2_lib.baseboard_fab2(sch_1):tp_cpu1_rsvd_299" )
			)
			( signal "TP_CPU1_RSVD_300"
				( objectStatus "@baseboard_fab2_lib.baseboard_fab2(sch_1):tp_cpu1_rsvd_300" )
			)
			( signal "TP_CPU1_RSVD_303"
				( objectStatus "@baseboard_fab2_lib.baseboard_fab2(sch_1):tp_cpu1_rsvd_303" )
			)
			( signal "TP_CPU1_RSVD_304"
				( objectStatus "@baseboard_fab2_lib.baseboard_fab2(sch_1):tp_cpu1_rsvd_304" )
			)
			( signal "TP_CPU1_RSVD_TEST_11"
				( objectStatus "@baseboard_fab2_lib.baseboard_fab2(sch_1):tp_cpu1_rsvd_test_11" )
			)
			( signal "TP_CPU1_RSVD_TEST_3"
				( objectStatus "@baseboard_fab2_lib.baseboard_fab2(sch_1):tp_cpu1_rsvd_test_3" )
			)
			( signal "TP_CPU1_RSVD_TEST_4"
				( objectStatus "@baseboard_fab2_lib.baseboard_fab2(sch_1):tp_cpu1_rsvd_test_4" )
			)
			( signal "TP_CPU1_RSVD_TEST_5"
				( objectStatus "@baseboard_fab2_lib.baseboard_fab2(sch_1):tp_cpu1_rsvd_test_5" )
			)
			( signal "VSENSE_P1V8MCP_CPU1_SKT_VRTN"
				( objectStatus "@baseboard_fab2_lib.baseboard_fab2(sch_1):vsense_p1v8mcp_cpu1_skt_vrtn" )
			)
			( signal "VSENSE_P1V8MCP_CPU1_SKT_VSEN"
				( objectStatus "@baseboard_fab2_lib.baseboard_fab2(sch_1):vsense_p1v8mcp_cpu1_skt_vsen" )
			)
			( signal "M_G_ACT_N"
				( objectStatus "@baseboard_fab2_lib.baseboard_fab2(sch_1):m_g_act_n" )
			)
			( signal "M_G_ALERT_N"
				( objectStatus "@baseboard_fab2_lib.baseboard_fab2(sch_1):m_g_alert_n" )
			)
			( signal "M_G_BA<0>"
				( objectStatus "@baseboard_fab2_lib.baseboard_fab2(sch_1):m_g_ba(0)" )
			)
			( signal "M_G_BA<1>"
				( objectStatus "@baseboard_fab2_lib.baseboard_fab2(sch_1):m_g_ba(1)" )
			)
			( signal "M_G_BG<0>"
				( objectStatus "@baseboard_fab2_lib.baseboard_fab2(sch_1):m_g_bg(0)" )
			)
			( signal "M_G_BG<1>"
				( objectStatus "@baseboard_fab2_lib.baseboard_fab2(sch_1):m_g_bg(1)" )
			)
			( signal "M_G_C<2>"
				( objectStatus "@baseboard_fab2_lib.baseboard_fab2(sch_1):m_g_c(2)" )
			)
			( signal "M_G_CKE<0>"
				( objectStatus "@baseboard_fab2_lib.baseboard_fab2(sch_1):m_g_cke(0)" )
			)
			( signal "M_G_CKE<1>"
				( objectStatus "@baseboard_fab2_lib.baseboard_fab2(sch_1):m_g_cke(1)" )
			)
			( signal "M_G_CKE<2>"
				( objectStatus "@baseboard_fab2_lib.baseboard_fab2(sch_1):m_g_cke(2)" )
			)
			( signal "M_G_CKE<3>"
				( objectStatus "@baseboard_fab2_lib.baseboard_fab2(sch_1):m_g_cke(3)" )
			)
			( signal "M_G_CLK_DN<0>"
				( objectStatus "@baseboard_fab2_lib.baseboard_fab2(sch_1):m_g_clk_dn(0)" )
			)
			( signal "M_G_CLK_DN<1>"
				( objectStatus "@baseboard_fab2_lib.baseboard_fab2(sch_1):m_g_clk_dn(1)" )
			)
			( signal "M_G_CLK_DN<2>"
				( objectStatus "@baseboard_fab2_lib.baseboard_fab2(sch_1):m_g_clk_dn(2)" )
			)
			( signal "M_G_CLK_DN<3>"
				( objectStatus "@baseboard_fab2_lib.baseboard_fab2(sch_1):m_g_clk_dn(3)" )
			)
			( signal "M_G_CLK_DP<0>"
				( objectStatus "@baseboard_fab2_lib.baseboard_fab2(sch_1):m_g_clk_dp(0)" )
			)
			( signal "M_G_CLK_DP<1>"
				( objectStatus "@baseboard_fab2_lib.baseboard_fab2(sch_1):m_g_clk_dp(1)" )
			)
			( signal "M_G_CLK_DP<2>"
				( objectStatus "@baseboard_fab2_lib.baseboard_fab2(sch_1):m_g_clk_dp(2)" )
			)
			( signal "M_G_CLK_DP<3>"
				( objectStatus "@baseboard_fab2_lib.baseboard_fab2(sch_1):m_g_clk_dp(3)" )
			)
			( signal "M_G_CS_N<0>"
				( objectStatus "@baseboard_fab2_lib.baseboard_fab2(sch_1):m_g_cs_n(0)" )
			)
			( signal "M_G_CS_N<1>"
				( objectStatus "@baseboard_fab2_lib.baseboard_fab2(sch_1):m_g_cs_n(1)" )
			)
			( signal "M_G_CS_N<2>"
				( objectStatus "@baseboard_fab2_lib.baseboard_fab2(sch_1):m_g_cs_n(2)" )
			)
			( signal "M_G_CS_N<3>"
				( objectStatus "@baseboard_fab2_lib.baseboard_fab2(sch_1):m_g_cs_n(3)" )
			)
			( signal "M_G_CS_N<4>"
				( objectStatus "@baseboard_fab2_lib.baseboard_fab2(sch_1):m_g_cs_n(4)" )
			)
			( signal "M_G_CS_N<5>"
				( objectStatus "@baseboard_fab2_lib.baseboard_fab2(sch_1):m_g_cs_n(5)" )
			)
			( signal "M_G_CS_N<6>"
				( objectStatus "@baseboard_fab2_lib.baseboard_fab2(sch_1):m_g_cs_n(6)" )
			)
			( signal "M_G_CS_N<7>"
				( objectStatus "@baseboard_fab2_lib.baseboard_fab2(sch_1):m_g_cs_n(7)" )
			)
			( signal "M_G_DQ<0>"
				( objectStatus "@baseboard_fab2_lib.baseboard_fab2(sch_1):m_g_dq(0)" )
			)
			( signal "M_G_DQ<1>"
				( objectStatus "@baseboard_fab2_lib.baseboard_fab2(sch_1):m_g_dq(1)" )
			)
			( signal "M_G_DQ<2>"
				( objectStatus "@baseboard_fab2_lib.baseboard_fab2(sch_1):m_g_dq(2)" )
			)
			( signal "M_G_DQ<3>"
				( objectStatus "@baseboard_fab2_lib.baseboard_fab2(sch_1):m_g_dq(3)" )
			)
			( signal "M_G_DQ<4>"
				( objectStatus "@baseboard_fab2_lib.baseboard_fab2(sch_1):m_g_dq(4)" )
			)
			( signal "M_G_DQ<5>"
				( objectStatus "@baseboard_fab2_lib.baseboard_fab2(sch_1):m_g_dq(5)" )
			)
			( signal "M_G_DQ<6>"
				( objectStatus "@baseboard_fab2_lib.baseboard_fab2(sch_1):m_g_dq(6)" )
			)
			( signal "M_G_DQ<7>"
				( objectStatus "@baseboard_fab2_lib.baseboard_fab2(sch_1):m_g_dq(7)" )
			)
			( signal "M_G_DQ<8>"
				( objectStatus "@baseboard_fab2_lib.baseboard_fab2(sch_1):m_g_dq(8)" )
			)
			( signal "M_G_DQ<9>"
				( objectStatus "@baseboard_fab2_lib.baseboard_fab2(sch_1):m_g_dq(9)" )
			)
			( signal "M_G_DQ<10>"
				( objectStatus "@baseboard_fab2_lib.baseboard_fab2(sch_1):m_g_dq(10)" )
			)
			( signal "M_G_DQ<11>"
				( objectStatus "@baseboard_fab2_lib.baseboard_fab2(sch_1):m_g_dq(11)" )
			)
			( signal "M_G_DQ<12>"
				( objectStatus "@baseboard_fab2_lib.baseboard_fab2(sch_1):m_g_dq(12)" )
			)
			( signal "M_G_DQ<13>"
				( objectStatus "@baseboard_fab2_lib.baseboard_fab2(sch_1):m_g_dq(13)" )
			)
			( signal "M_G_DQ<14>"
				( objectStatus "@baseboard_fab2_lib.baseboard_fab2(sch_1):m_g_dq(14)" )
			)
			( signal "M_G_DQ<15>"
				( objectStatus "@baseboard_fab2_lib.baseboard_fab2(sch_1):m_g_dq(15)" )
			)
			( signal "M_G_DQ<16>"
				( objectStatus "@baseboard_fab2_lib.baseboard_fab2(sch_1):m_g_dq(16)" )
			)
			( signal "M_G_DQ<17>"
				( objectStatus "@baseboard_fab2_lib.baseboard_fab2(sch_1):m_g_dq(17)" )
			)
			( signal "M_G_DQ<18>"
				( objectStatus "@baseboard_fab2_lib.baseboard_fab2(sch_1):m_g_dq(18)" )
			)
			( signal "M_G_DQ<19>"
				( objectStatus "@baseboard_fab2_lib.baseboard_fab2(sch_1):m_g_dq(19)" )
			)
			( signal "M_G_DQ<20>"
				( objectStatus "@baseboard_fab2_lib.baseboard_fab2(sch_1):m_g_dq(20)" )
			)
			( signal "M_G_DQ<21>"
				( objectStatus "@baseboard_fab2_lib.baseboard_fab2(sch_1):m_g_dq(21)" )
			)
			( signal "M_G_DQ<22>"
				( objectStatus "@baseboard_fab2_lib.baseboard_fab2(sch_1):m_g_dq(22)" )
			)
			( signal "M_G_DQ<23>"
				( objectStatus "@baseboard_fab2_lib.baseboard_fab2(sch_1):m_g_dq(23)" )
			)
			( signal "M_G_DQ<24>"
				( objectStatus "@baseboard_fab2_lib.baseboard_fab2(sch_1):m_g_dq(24)" )
			)
			( signal "M_G_DQ<25>"
				( objectStatus "@baseboard_fab2_lib.baseboard_fab2(sch_1):m_g_dq(25)" )
			)
			( signal "M_G_DQ<26>"
				( objectStatus "@baseboard_fab2_lib.baseboard_fab2(sch_1):m_g_dq(26)" )
			)
			( signal "M_G_DQ<27>"
				( objectStatus "@baseboard_fab2_lib.baseboard_fab2(sch_1):m_g_dq(27)" )
			)
			( signal "M_G_DQ<28>"
				( objectStatus "@baseboard_fab2_lib.baseboard_fab2(sch_1):m_g_dq(28)" )
			)
			( signal "M_G_DQ<29>"
				( objectStatus "@baseboard_fab2_lib.baseboard_fab2(sch_1):m_g_dq(29)" )
			)
			( signal "M_G_DQ<30>"
				( objectStatus "@baseboard_fab2_lib.baseboard_fab2(sch_1):m_g_dq(30)" )
			)
			( signal "M_G_DQ<31>"
				( objectStatus "@baseboard_fab2_lib.baseboard_fab2(sch_1):m_g_dq(31)" )
			)
			( signal "M_G_DQ<32>"
				( objectStatus "@baseboard_fab2_lib.baseboard_fab2(sch_1):m_g_dq(32)" )
			)
			( signal "M_G_DQ<33>"
				( objectStatus "@baseboard_fab2_lib.baseboard_fab2(sch_1):m_g_dq(33)" )
			)
			( signal "M_G_DQ<34>"
				( objectStatus "@baseboard_fab2_lib.baseboard_fab2(sch_1):m_g_dq(34)" )
			)
			( signal "M_G_DQ<35>"
				( objectStatus "@baseboard_fab2_lib.baseboard_fab2(sch_1):m_g_dq(35)" )
			)
			( signal "M_G_DQ<36>"
				( objectStatus "@baseboard_fab2_lib.baseboard_fab2(sch_1):m_g_dq(36)" )
			)
			( signal "M_G_DQ<37>"
				( objectStatus "@baseboard_fab2_lib.baseboard_fab2(sch_1):m_g_dq(37)" )
			)
			( signal "M_G_DQ<38>"
				( objectStatus "@baseboard_fab2_lib.baseboard_fab2(sch_1):m_g_dq(38)" )
			)
			( signal "M_G_DQ<39>"
				( objectStatus "@baseboard_fab2_lib.baseboard_fab2(sch_1):m_g_dq(39)" )
			)
			( signal "M_G_DQ<40>"
				( objectStatus "@baseboard_fab2_lib.baseboard_fab2(sch_1):m_g_dq(40)" )
			)
			( signal "M_G_DQ<41>"
				( objectStatus "@baseboard_fab2_lib.baseboard_fab2(sch_1):m_g_dq(41)" )
			)
			( signal "M_G_DQ<42>"
				( objectStatus "@baseboard_fab2_lib.baseboard_fab2(sch_1):m_g_dq(42)" )
			)
			( signal "M_G_DQ<43>"
				( objectStatus "@baseboard_fab2_lib.baseboard_fab2(sch_1):m_g_dq(43)" )
			)
			( signal "M_G_DQ<44>"
				( objectStatus "@baseboard_fab2_lib.baseboard_fab2(sch_1):m_g_dq(44)" )
			)
			( signal "M_G_DQ<45>"
				( objectStatus "@baseboard_fab2_lib.baseboard_fab2(sch_1):m_g_dq(45)" )
			)
			( signal "M_G_DQ<46>"
				( objectStatus "@baseboard_fab2_lib.baseboard_fab2(sch_1):m_g_dq(46)" )
			)
			( signal "M_G_DQ<47>"
				( objectStatus "@baseboard_fab2_lib.baseboard_fab2(sch_1):m_g_dq(47)" )
			)
			( signal "M_G_DQ<48>"
				( objectStatus "@baseboard_fab2_lib.baseboard_fab2(sch_1):m_g_dq(48)" )
			)
			( signal "M_G_DQ<49>"
				( objectStatus "@baseboard_fab2_lib.baseboard_fab2(sch_1):m_g_dq(49)" )
			)
			( signal "M_G_DQ<50>"
				( objectStatus "@baseboard_fab2_lib.baseboard_fab2(sch_1):m_g_dq(50)" )
			)
			( signal "M_G_DQ<51>"
				( objectStatus "@baseboard_fab2_lib.baseboard_fab2(sch_1):m_g_dq(51)" )
			)
			( signal "M_G_DQ<52>"
				( objectStatus "@baseboard_fab2_lib.baseboard_fab2(sch_1):m_g_dq(52)" )
			)
			( signal "M_G_DQ<53>"
				( objectStatus "@baseboard_fab2_lib.baseboard_fab2(sch_1):m_g_dq(53)" )
			)
			( signal "M_G_DQ<54>"
				( objectStatus "@baseboard_fab2_lib.baseboard_fab2(sch_1):m_g_dq(54)" )
			)
			( signal "M_G_DQ<55>"
				( objectStatus "@baseboard_fab2_lib.baseboard_fab2(sch_1):m_g_dq(55)" )
			)
			( signal "M_G_DQ<56>"
				( objectStatus "@baseboard_fab2_lib.baseboard_fab2(sch_1):m_g_dq(56)" )
			)
			( signal "M_G_DQ<57>"
				( objectStatus "@baseboard_fab2_lib.baseboard_fab2(sch_1):m_g_dq(57)" )
			)
			( signal "M_G_DQ<58>"
				( objectStatus "@baseboard_fab2_lib.baseboard_fab2(sch_1):m_g_dq(58)" )
			)
			( signal "M_G_DQ<59>"
				( objectStatus "@baseboard_fab2_lib.baseboard_fab2(sch_1):m_g_dq(59)" )
			)
			( signal "M_G_DQ<60>"
				( objectStatus "@baseboard_fab2_lib.baseboard_fab2(sch_1):m_g_dq(60)" )
			)
			( signal "M_G_DQ<61>"
				( objectStatus "@baseboard_fab2_lib.baseboard_fab2(sch_1):m_g_dq(61)" )
			)
			( signal "M_G_DQ<62>"
				( objectStatus "@baseboard_fab2_lib.baseboard_fab2(sch_1):m_g_dq(62)" )
			)
			( signal "M_G_DQ<63>"
				( objectStatus "@baseboard_fab2_lib.baseboard_fab2(sch_1):m_g_dq(63)" )
			)
			( signal "M_G_DQS_DN<0>"
				( objectStatus "@baseboard_fab2_lib.baseboard_fab2(sch_1):m_g_dqs_dn(0)" )
			)
			( signal "M_G_DQS_DN<1>"
				( objectStatus "@baseboard_fab2_lib.baseboard_fab2(sch_1):m_g_dqs_dn(1)" )
			)
			( signal "M_G_DQS_DN<2>"
				( objectStatus "@baseboard_fab2_lib.baseboard_fab2(sch_1):m_g_dqs_dn(2)" )
			)
			( signal "M_G_DQS_DN<3>"
				( objectStatus "@baseboard_fab2_lib.baseboard_fab2(sch_1):m_g_dqs_dn(3)" )
			)
			( signal "M_G_DQS_DN<4>"
				( objectStatus "@baseboard_fab2_lib.baseboard_fab2(sch_1):m_g_dqs_dn(4)" )
			)
			( signal "M_G_DQS_DN<5>"
				( objectStatus "@baseboard_fab2_lib.baseboard_fab2(sch_1):m_g_dqs_dn(5)" )
			)
			( signal "M_G_DQS_DN<6>"
				( objectStatus "@baseboard_fab2_lib.baseboard_fab2(sch_1):m_g_dqs_dn(6)" )
			)
			( signal "M_G_DQS_DN<7>"
				( objectStatus "@baseboard_fab2_lib.baseboard_fab2(sch_1):m_g_dqs_dn(7)" )
			)
			( signal "M_G_DQS_DN<8>"
				( objectStatus "@baseboard_fab2_lib.baseboard_fab2(sch_1):m_g_dqs_dn(8)" )
			)
			( signal "M_G_DQS_DN<9>"
				( objectStatus "@baseboard_fab2_lib.baseboard_fab2(sch_1):m_g_dqs_dn(9)" )
			)
			( signal "M_G_DQS_DN<10>"
				( objectStatus "@baseboard_fab2_lib.baseboard_fab2(sch_1):m_g_dqs_dn(10)" )
			)
			( signal "M_G_DQS_DN<11>"
				( objectStatus "@baseboard_fab2_lib.baseboard_fab2(sch_1):m_g_dqs_dn(11)" )
			)
			( signal "M_G_DQS_DN<12>"
				( objectStatus "@baseboard_fab2_lib.baseboard_fab2(sch_1):m_g_dqs_dn(12)" )
			)
			( signal "M_G_DQS_DN<13>"
				( objectStatus "@baseboard_fab2_lib.baseboard_fab2(sch_1):m_g_dqs_dn(13)" )
			)
			( signal "M_G_DQS_DN<14>"
				( objectStatus "@baseboard_fab2_lib.baseboard_fab2(sch_1):m_g_dqs_dn(14)" )
			)
			( signal "M_G_DQS_DN<15>"
				( objectStatus "@baseboard_fab2_lib.baseboard_fab2(sch_1):m_g_dqs_dn(15)" )
			)
			( signal "M_G_DQS_DN<16>"
				( objectStatus "@baseboard_fab2_lib.baseboard_fab2(sch_1):m_g_dqs_dn(16)" )
			)
			( signal "M_G_DQS_DN<17>"
				( objectStatus "@baseboard_fab2_lib.baseboard_fab2(sch_1):m_g_dqs_dn(17)" )
			)
			( signal "M_G_DQS_DP<0>"
				( objectStatus "@baseboard_fab2_lib.baseboard_fab2(sch_1):m_g_dqs_dp(0)" )
			)
			( signal "M_G_DQS_DP<1>"
				( objectStatus "@baseboard_fab2_lib.baseboard_fab2(sch_1):m_g_dqs_dp(1)" )
			)
			( signal "M_G_DQS_DP<2>"
				( objectStatus "@baseboard_fab2_lib.baseboard_fab2(sch_1):m_g_dqs_dp(2)" )
			)
			( signal "M_G_DQS_DP<3>"
				( objectStatus "@baseboard_fab2_lib.baseboard_fab2(sch_1):m_g_dqs_dp(3)" )
			)
			( signal "M_G_DQS_DP<4>"
				( objectStatus "@baseboard_fab2_lib.baseboard_fab2(sch_1):m_g_dqs_dp(4)" )
			)
			( signal "M_G_DQS_DP<5>"
				( objectStatus "@baseboard_fab2_lib.baseboard_fab2(sch_1):m_g_dqs_dp(5)" )
			)
			( signal "M_G_DQS_DP<6>"
				( objectStatus "@baseboard_fab2_lib.baseboard_fab2(sch_1):m_g_dqs_dp(6)" )
			)
			( signal "M_G_DQS_DP<7>"
				( objectStatus "@baseboard_fab2_lib.baseboard_fab2(sch_1):m_g_dqs_dp(7)" )
			)
			( signal "M_G_DQS_DP<8>"
				( objectStatus "@baseboard_fab2_lib.baseboard_fab2(sch_1):m_g_dqs_dp(8)" )
			)
			( signal "M_G_DQS_DP<9>"
				( objectStatus "@baseboard_fab2_lib.baseboard_fab2(sch_1):m_g_dqs_dp(9)" )
			)
			( signal "M_G_DQS_DP<10>"
				( objectStatus "@baseboard_fab2_lib.baseboard_fab2(sch_1):m_g_dqs_dp(10)" )
			)
			( signal "M_G_DQS_DP<11>"
				( objectStatus "@baseboard_fab2_lib.baseboard_fab2(sch_1):m_g_dqs_dp(11)" )
			)
			( signal "M_G_DQS_DP<12>"
				( objectStatus "@baseboard_fab2_lib.baseboard_fab2(sch_1):m_g_dqs_dp(12)" )
			)
			( signal "M_G_DQS_DP<13>"
				( objectStatus "@baseboard_fab2_lib.baseboard_fab2(sch_1):m_g_dqs_dp(13)" )
			)
			( signal "M_G_DQS_DP<14>"
				( objectStatus "@baseboard_fab2_lib.baseboard_fab2(sch_1):m_g_dqs_dp(14)" )
			)
			( signal "M_G_DQS_DP<15>"
				( objectStatus "@baseboard_fab2_lib.baseboard_fab2(sch_1):m_g_dqs_dp(15)" )
			)
			( signal "M_G_DQS_DP<16>"
				( objectStatus "@baseboard_fab2_lib.baseboard_fab2(sch_1):m_g_dqs_dp(16)" )
			)
			( signal "M_G_DQS_DP<17>"
				( objectStatus "@baseboard_fab2_lib.baseboard_fab2(sch_1):m_g_dqs_dp(17)" )
			)
			( signal "M_G_ECC<0>"
				( objectStatus "@baseboard_fab2_lib.baseboard_fab2(sch_1):m_g_ecc(0)" )
			)
			( signal "M_G_ECC<1>"
				( objectStatus "@baseboard_fab2_lib.baseboard_fab2(sch_1):m_g_ecc(1)" )
			)
			( signal "M_G_ECC<2>"
				( objectStatus "@baseboard_fab2_lib.baseboard_fab2(sch_1):m_g_ecc(2)" )
			)
			( signal "M_G_ECC<3>"
				( objectStatus "@baseboard_fab2_lib.baseboard_fab2(sch_1):m_g_ecc(3)" )
			)
			( signal "M_G_ECC<4>"
				( objectStatus "@baseboard_fab2_lib.baseboard_fab2(sch_1):m_g_ecc(4)" )
			)
			( signal "M_G_ECC<5>"
				( objectStatus "@baseboard_fab2_lib.baseboard_fab2(sch_1):m_g_ecc(5)" )
			)
			( signal "M_G_ECC<6>"
				( objectStatus "@baseboard_fab2_lib.baseboard_fab2(sch_1):m_g_ecc(6)" )
			)
			( signal "M_G_ECC<7>"
				( objectStatus "@baseboard_fab2_lib.baseboard_fab2(sch_1):m_g_ecc(7)" )
			)
			( signal "M_G_MA<0>"
				( objectStatus "@baseboard_fab2_lib.baseboard_fab2(sch_1):m_g_ma(0)" )
			)
			( signal "M_G_MA<1>"
				( objectStatus "@baseboard_fab2_lib.baseboard_fab2(sch_1):m_g_ma(1)" )
			)
			( signal "M_G_MA<2>"
				( objectStatus "@baseboard_fab2_lib.baseboard_fab2(sch_1):m_g_ma(2)" )
			)
			( signal "M_G_MA<3>"
				( objectStatus "@baseboard_fab2_lib.baseboard_fab2(sch_1):m_g_ma(3)" )
			)
			( signal "M_G_MA<4>"
				( objectStatus "@baseboard_fab2_lib.baseboard_fab2(sch_1):m_g_ma(4)" )
			)
			( signal "M_G_MA<5>"
				( objectStatus "@baseboard_fab2_lib.baseboard_fab2(sch_1):m_g_ma(5)" )
			)
			( signal "M_G_MA<6>"
				( objectStatus "@baseboard_fab2_lib.baseboard_fab2(sch_1):m_g_ma(6)" )
			)
			( signal "M_G_MA<7>"
				( objectStatus "@baseboard_fab2_lib.baseboard_fab2(sch_1):m_g_ma(7)" )
			)
			( signal "M_G_MA<8>"
				( objectStatus "@baseboard_fab2_lib.baseboard_fab2(sch_1):m_g_ma(8)" )
			)
			( signal "M_G_MA<9>"
				( objectStatus "@baseboard_fab2_lib.baseboard_fab2(sch_1):m_g_ma(9)" )
			)
			( signal "M_G_MA<10>"
				( objectStatus "@baseboard_fab2_lib.baseboard_fab2(sch_1):m_g_ma(10)" )
			)
			( signal "M_G_MA<11>"
				( objectStatus "@baseboard_fab2_lib.baseboard_fab2(sch_1):m_g_ma(11)" )
			)
			( signal "M_G_MA<12>"
				( objectStatus "@baseboard_fab2_lib.baseboard_fab2(sch_1):m_g_ma(12)" )
			)
			( signal "M_G_MA<13>"
				( objectStatus "@baseboard_fab2_lib.baseboard_fab2(sch_1):m_g_ma(13)" )
			)
			( signal "M_G_MA<14>"
				( objectStatus "@baseboard_fab2_lib.baseboard_fab2(sch_1):m_g_ma(14)" )
			)
			( signal "M_G_MA<15>"
				( objectStatus "@baseboard_fab2_lib.baseboard_fab2(sch_1):m_g_ma(15)" )
			)
			( signal "M_G_MA<16>"
				( objectStatus "@baseboard_fab2_lib.baseboard_fab2(sch_1):m_g_ma(16)" )
			)
			( signal "M_G_MA<17>"
				( objectStatus "@baseboard_fab2_lib.baseboard_fab2(sch_1):m_g_ma(17)" )
			)
			( signal "M_G_ODT<0>"
				( objectStatus "@baseboard_fab2_lib.baseboard_fab2(sch_1):m_g_odt(0)" )
			)
			( signal "M_G_ODT<1>"
				( objectStatus "@baseboard_fab2_lib.baseboard_fab2(sch_1):m_g_odt(1)" )
			)
			( signal "M_G_ODT<2>"
				( objectStatus "@baseboard_fab2_lib.baseboard_fab2(sch_1):m_g_odt(2)" )
			)
			( signal "M_G_ODT<3>"
				( objectStatus "@baseboard_fab2_lib.baseboard_fab2(sch_1):m_g_odt(3)" )
			)
			( signal "M_G_PAR"
				( objectStatus "@baseboard_fab2_lib.baseboard_fab2(sch_1):m_g_par" )
			)
			( signal "M_H_ACT_N"
				( objectStatus "@baseboard_fab2_lib.baseboard_fab2(sch_1):m_h_act_n" )
			)
			( signal "M_H_ALERT_N"
				( objectStatus "@baseboard_fab2_lib.baseboard_fab2(sch_1):m_h_alert_n" )
			)
			( signal "M_H_BA<0>"
				( objectStatus "@baseboard_fab2_lib.baseboard_fab2(sch_1):m_h_ba(0)" )
			)
			( signal "M_H_BA<1>"
				( objectStatus "@baseboard_fab2_lib.baseboard_fab2(sch_1):m_h_ba(1)" )
			)
			( signal "M_H_BG<0>"
				( objectStatus "@baseboard_fab2_lib.baseboard_fab2(sch_1):m_h_bg(0)" )
			)
			( signal "M_H_BG<1>"
				( objectStatus "@baseboard_fab2_lib.baseboard_fab2(sch_1):m_h_bg(1)" )
			)
			( signal "M_H_C<2>"
				( objectStatus "@baseboard_fab2_lib.baseboard_fab2(sch_1):m_h_c(2)" )
			)
			( signal "M_H_CKE<0>"
				( objectStatus "@baseboard_fab2_lib.baseboard_fab2(sch_1):m_h_cke(0)" )
			)
			( signal "M_H_CKE<1>"
				( objectStatus "@baseboard_fab2_lib.baseboard_fab2(sch_1):m_h_cke(1)" )
			)
			( signal "M_H_CKE<2>"
				( objectStatus "@baseboard_fab2_lib.baseboard_fab2(sch_1):m_h_cke(2)" )
			)
			( signal "M_H_CKE<3>"
				( objectStatus "@baseboard_fab2_lib.baseboard_fab2(sch_1):m_h_cke(3)" )
			)
			( signal "M_H_CLK_DN<0>"
				( objectStatus "@baseboard_fab2_lib.baseboard_fab2(sch_1):m_h_clk_dn(0)" )
			)
			( signal "M_H_CLK_DN<1>"
				( objectStatus "@baseboard_fab2_lib.baseboard_fab2(sch_1):m_h_clk_dn(1)" )
			)
			( signal "M_H_CLK_DN<2>"
				( objectStatus "@baseboard_fab2_lib.baseboard_fab2(sch_1):m_h_clk_dn(2)" )
			)
			( signal "M_H_CLK_DN<3>"
				( objectStatus "@baseboard_fab2_lib.baseboard_fab2(sch_1):m_h_clk_dn(3)" )
			)
			( signal "M_H_CLK_DP<0>"
				( objectStatus "@baseboard_fab2_lib.baseboard_fab2(sch_1):m_h_clk_dp(0)" )
			)
			( signal "M_H_CLK_DP<1>"
				( objectStatus "@baseboard_fab2_lib.baseboard_fab2(sch_1):m_h_clk_dp(1)" )
			)
			( signal "M_H_CLK_DP<2>"
				( objectStatus "@baseboard_fab2_lib.baseboard_fab2(sch_1):m_h_clk_dp(2)" )
			)
			( signal "M_H_CLK_DP<3>"
				( objectStatus "@baseboard_fab2_lib.baseboard_fab2(sch_1):m_h_clk_dp(3)" )
			)
			( signal "M_H_CS_N<0>"
				( objectStatus "@baseboard_fab2_lib.baseboard_fab2(sch_1):m_h_cs_n(0)" )
			)
			( signal "M_H_CS_N<1>"
				( objectStatus "@baseboard_fab2_lib.baseboard_fab2(sch_1):m_h_cs_n(1)" )
			)
			( signal "M_H_CS_N<2>"
				( objectStatus "@baseboard_fab2_lib.baseboard_fab2(sch_1):m_h_cs_n(2)" )
			)
			( signal "M_H_CS_N<3>"
				( objectStatus "@baseboard_fab2_lib.baseboard_fab2(sch_1):m_h_cs_n(3)" )
			)
			( signal "M_H_CS_N<4>"
				( objectStatus "@baseboard_fab2_lib.baseboard_fab2(sch_1):m_h_cs_n(4)" )
			)
			( signal "M_H_CS_N<5>"
				( objectStatus "@baseboard_fab2_lib.baseboard_fab2(sch_1):m_h_cs_n(5)" )
			)
			( signal "M_H_CS_N<6>"
				( objectStatus "@baseboard_fab2_lib.baseboard_fab2(sch_1):m_h_cs_n(6)" )
			)
			( signal "M_H_CS_N<7>"
				( objectStatus "@baseboard_fab2_lib.baseboard_fab2(sch_1):m_h_cs_n(7)" )
			)
			( signal "M_H_DQ<0>"
				( objectStatus "@baseboard_fab2_lib.baseboard_fab2(sch_1):m_h_dq(0)" )
			)
			( signal "M_H_DQ<1>"
				( objectStatus "@baseboard_fab2_lib.baseboard_fab2(sch_1):m_h_dq(1)" )
			)
			( signal "M_H_DQ<2>"
				( objectStatus "@baseboard_fab2_lib.baseboard_fab2(sch_1):m_h_dq(2)" )
			)
			( signal "M_H_DQ<3>"
				( objectStatus "@baseboard_fab2_lib.baseboard_fab2(sch_1):m_h_dq(3)" )
			)
			( signal "M_H_DQ<4>"
				( objectStatus "@baseboard_fab2_lib.baseboard_fab2(sch_1):m_h_dq(4)" )
			)
			( signal "M_H_DQ<5>"
				( objectStatus "@baseboard_fab2_lib.baseboard_fab2(sch_1):m_h_dq(5)" )
			)
			( signal "M_H_DQ<6>"
				( objectStatus "@baseboard_fab2_lib.baseboard_fab2(sch_1):m_h_dq(6)" )
			)
			( signal "M_H_DQ<7>"
				( objectStatus "@baseboard_fab2_lib.baseboard_fab2(sch_1):m_h_dq(7)" )
			)
			( signal "M_H_DQ<8>"
				( objectStatus "@baseboard_fab2_lib.baseboard_fab2(sch_1):m_h_dq(8)" )
			)
			( signal "M_H_DQ<9>"
				( objectStatus "@baseboard_fab2_lib.baseboard_fab2(sch_1):m_h_dq(9)" )
			)
			( signal "M_H_DQ<10>"
				( objectStatus "@baseboard_fab2_lib.baseboard_fab2(sch_1):m_h_dq(10)" )
			)
			( signal "M_H_DQ<11>"
				( objectStatus "@baseboard_fab2_lib.baseboard_fab2(sch_1):m_h_dq(11)" )
			)
			( signal "M_H_DQ<12>"
				( objectStatus "@baseboard_fab2_lib.baseboard_fab2(sch_1):m_h_dq(12)" )
			)
			( signal "M_H_DQ<13>"
				( objectStatus "@baseboard_fab2_lib.baseboard_fab2(sch_1):m_h_dq(13)" )
			)
			( signal "M_H_DQ<14>"
				( objectStatus "@baseboard_fab2_lib.baseboard_fab2(sch_1):m_h_dq(14)" )
			)
			( signal "M_H_DQ<15>"
				( objectStatus "@baseboard_fab2_lib.baseboard_fab2(sch_1):m_h_dq(15)" )
			)
			( signal "M_H_DQ<16>"
				( objectStatus "@baseboard_fab2_lib.baseboard_fab2(sch_1):m_h_dq(16)" )
			)
			( signal "M_H_DQ<17>"
				( objectStatus "@baseboard_fab2_lib.baseboard_fab2(sch_1):m_h_dq(17)" )
			)
			( signal "M_H_DQ<18>"
				( objectStatus "@baseboard_fab2_lib.baseboard_fab2(sch_1):m_h_dq(18)" )
			)
			( signal "M_H_DQ<19>"
				( objectStatus "@baseboard_fab2_lib.baseboard_fab2(sch_1):m_h_dq(19)" )
			)
			( signal "M_H_DQ<20>"
				( objectStatus "@baseboard_fab2_lib.baseboard_fab2(sch_1):m_h_dq(20)" )
			)
			( signal "M_H_DQ<21>"
				( objectStatus "@baseboard_fab2_lib.baseboard_fab2(sch_1):m_h_dq(21)" )
			)
			( signal "M_H_DQ<22>"
				( objectStatus "@baseboard_fab2_lib.baseboard_fab2(sch_1):m_h_dq(22)" )
			)
			( signal "M_H_DQ<23>"
				( objectStatus "@baseboard_fab2_lib.baseboard_fab2(sch_1):m_h_dq(23)" )
			)
			( signal "M_H_DQ<24>"
				( objectStatus "@baseboard_fab2_lib.baseboard_fab2(sch_1):m_h_dq(24)" )
			)
			( signal "M_H_DQ<25>"
				( objectStatus "@baseboard_fab2_lib.baseboard_fab2(sch_1):m_h_dq(25)" )
			)
			( signal "M_H_DQ<26>"
				( objectStatus "@baseboard_fab2_lib.baseboard_fab2(sch_1):m_h_dq(26)" )
			)
			( signal "M_H_DQ<27>"
				( objectStatus "@baseboard_fab2_lib.baseboard_fab2(sch_1):m_h_dq(27)" )
			)
			( signal "M_H_DQ<28>"
				( objectStatus "@baseboard_fab2_lib.baseboard_fab2(sch_1):m_h_dq(28)" )
			)
			( signal "M_H_DQ<29>"
				( objectStatus "@baseboard_fab2_lib.baseboard_fab2(sch_1):m_h_dq(29)" )
			)
			( signal "M_H_DQ<30>"
				( objectStatus "@baseboard_fab2_lib.baseboard_fab2(sch_1):m_h_dq(30)" )
			)
			( signal "M_H_DQ<31>"
				( objectStatus "@baseboard_fab2_lib.baseboard_fab2(sch_1):m_h_dq(31)" )
			)
			( signal "M_H_DQ<32>"
				( objectStatus "@baseboard_fab2_lib.baseboard_fab2(sch_1):m_h_dq(32)" )
			)
			( signal "M_H_DQ<33>"
				( objectStatus "@baseboard_fab2_lib.baseboard_fab2(sch_1):m_h_dq(33)" )
			)
			( signal "M_H_DQ<34>"
				( objectStatus "@baseboard_fab2_lib.baseboard_fab2(sch_1):m_h_dq(34)" )
			)
			( signal "M_H_DQ<35>"
				( objectStatus "@baseboard_fab2_lib.baseboard_fab2(sch_1):m_h_dq(35)" )
			)
			( signal "M_H_DQ<36>"
				( objectStatus "@baseboard_fab2_lib.baseboard_fab2(sch_1):m_h_dq(36)" )
			)
			( signal "M_H_DQ<37>"
				( objectStatus "@baseboard_fab2_lib.baseboard_fab2(sch_1):m_h_dq(37)" )
			)
			( signal "M_H_DQ<38>"
				( objectStatus "@baseboard_fab2_lib.baseboard_fab2(sch_1):m_h_dq(38)" )
			)
			( signal "M_H_DQ<39>"
				( objectStatus "@baseboard_fab2_lib.baseboard_fab2(sch_1):m_h_dq(39)" )
			)
			( signal "M_H_DQ<40>"
				( objectStatus "@baseboard_fab2_lib.baseboard_fab2(sch_1):m_h_dq(40)" )
			)
			( signal "M_H_DQ<41>"
				( objectStatus "@baseboard_fab2_lib.baseboard_fab2(sch_1):m_h_dq(41)" )
			)
			( signal "M_H_DQ<42>"
				( objectStatus "@baseboard_fab2_lib.baseboard_fab2(sch_1):m_h_dq(42)" )
			)
			( signal "M_H_DQ<43>"
				( objectStatus "@baseboard_fab2_lib.baseboard_fab2(sch_1):m_h_dq(43)" )
			)
			( signal "M_H_DQ<44>"
				( objectStatus "@baseboard_fab2_lib.baseboard_fab2(sch_1):m_h_dq(44)" )
			)
			( signal "M_H_DQ<45>"
				( objectStatus "@baseboard_fab2_lib.baseboard_fab2(sch_1):m_h_dq(45)" )
			)
			( signal "M_H_DQ<46>"
				( objectStatus "@baseboard_fab2_lib.baseboard_fab2(sch_1):m_h_dq(46)" )
			)
			( signal "M_H_DQ<47>"
				( objectStatus "@baseboard_fab2_lib.baseboard_fab2(sch_1):m_h_dq(47)" )
			)
			( signal "M_H_DQ<48>"
				( objectStatus "@baseboard_fab2_lib.baseboard_fab2(sch_1):m_h_dq(48)" )
			)
			( signal "M_H_DQ<49>"
				( objectStatus "@baseboard_fab2_lib.baseboard_fab2(sch_1):m_h_dq(49)" )
			)
			( signal "M_H_DQ<50>"
				( objectStatus "@baseboard_fab2_lib.baseboard_fab2(sch_1):m_h_dq(50)" )
			)
			( signal "M_H_DQ<51>"
				( objectStatus "@baseboard_fab2_lib.baseboard_fab2(sch_1):m_h_dq(51)" )
			)
			( signal "M_H_DQ<52>"
				( objectStatus "@baseboard_fab2_lib.baseboard_fab2(sch_1):m_h_dq(52)" )
			)
			( signal "M_H_DQ<53>"
				( objectStatus "@baseboard_fab2_lib.baseboard_fab2(sch_1):m_h_dq(53)" )
			)
			( signal "M_H_DQ<54>"
				( objectStatus "@baseboard_fab2_lib.baseboard_fab2(sch_1):m_h_dq(54)" )
			)
			( signal "M_H_DQ<55>"
				( objectStatus "@baseboard_fab2_lib.baseboard_fab2(sch_1):m_h_dq(55)" )
			)
			( signal "M_H_DQ<56>"
				( objectStatus "@baseboard_fab2_lib.baseboard_fab2(sch_1):m_h_dq(56)" )
			)
			( signal "M_H_DQ<57>"
				( objectStatus "@baseboard_fab2_lib.baseboard_fab2(sch_1):m_h_dq(57)" )
			)
			( signal "M_H_DQ<58>"
				( objectStatus "@baseboard_fab2_lib.baseboard_fab2(sch_1):m_h_dq(58)" )
			)
			( signal "M_H_DQ<59>"
				( objectStatus "@baseboard_fab2_lib.baseboard_fab2(sch_1):m_h_dq(59)" )
			)
			( signal "M_H_DQ<60>"
				( objectStatus "@baseboard_fab2_lib.baseboard_fab2(sch_1):m_h_dq(60)" )
			)
			( signal "M_H_DQ<61>"
				( objectStatus "@baseboard_fab2_lib.baseboard_fab2(sch_1):m_h_dq(61)" )
			)
			( signal "M_H_DQ<62>"
				( objectStatus "@baseboard_fab2_lib.baseboard_fab2(sch_1):m_h_dq(62)" )
			)
			( signal "M_H_DQ<63>"
				( objectStatus "@baseboard_fab2_lib.baseboard_fab2(sch_1):m_h_dq(63)" )
			)
			( signal "M_H_DQS_DN<0>"
				( objectStatus "@baseboard_fab2_lib.baseboard_fab2(sch_1):m_h_dqs_dn(0)" )
			)
			( signal "M_H_DQS_DN<1>"
				( objectStatus "@baseboard_fab2_lib.baseboard_fab2(sch_1):m_h_dqs_dn(1)" )
			)
			( signal "M_H_DQS_DN<2>"
				( objectStatus "@baseboard_fab2_lib.baseboard_fab2(sch_1):m_h_dqs_dn(2)" )
			)
			( signal "M_H_DQS_DN<3>"
				( objectStatus "@baseboard_fab2_lib.baseboard_fab2(sch_1):m_h_dqs_dn(3)" )
			)
			( signal "M_H_DQS_DN<4>"
				( objectStatus "@baseboard_fab2_lib.baseboard_fab2(sch_1):m_h_dqs_dn(4)" )
			)
			( signal "M_H_DQS_DN<5>"
				( objectStatus "@baseboard_fab2_lib.baseboard_fab2(sch_1):m_h_dqs_dn(5)" )
			)
			( signal "M_H_DQS_DN<6>"
				( objectStatus "@baseboard_fab2_lib.baseboard_fab2(sch_1):m_h_dqs_dn(6)" )
			)
			( signal "M_H_DQS_DN<7>"
				( objectStatus "@baseboard_fab2_lib.baseboard_fab2(sch_1):m_h_dqs_dn(7)" )
			)
			( signal "M_H_DQS_DN<8>"
				( objectStatus "@baseboard_fab2_lib.baseboard_fab2(sch_1):m_h_dqs_dn(8)" )
			)
			( signal "M_H_DQS_DN<9>"
				( objectStatus "@baseboard_fab2_lib.baseboard_fab2(sch_1):m_h_dqs_dn(9)" )
			)
			( signal "M_H_DQS_DN<10>"
				( objectStatus "@baseboard_fab2_lib.baseboard_fab2(sch_1):m_h_dqs_dn(10)" )
			)
			( signal "M_H_DQS_DN<11>"
				( objectStatus "@baseboard_fab2_lib.baseboard_fab2(sch_1):m_h_dqs_dn(11)" )
			)
			( signal "M_H_DQS_DN<12>"
				( objectStatus "@baseboard_fab2_lib.baseboard_fab2(sch_1):m_h_dqs_dn(12)" )
			)
			( signal "M_H_DQS_DN<13>"
				( objectStatus "@baseboard_fab2_lib.baseboard_fab2(sch_1):m_h_dqs_dn(13)" )
			)
			( signal "M_H_DQS_DN<14>"
				( objectStatus "@baseboard_fab2_lib.baseboard_fab2(sch_1):m_h_dqs_dn(14)" )
			)
			( signal "M_H_DQS_DN<15>"
				( objectStatus "@baseboard_fab2_lib.baseboard_fab2(sch_1):m_h_dqs_dn(15)" )
			)
			( signal "M_H_DQS_DN<16>"
				( objectStatus "@baseboard_fab2_lib.baseboard_fab2(sch_1):m_h_dqs_dn(16)" )
			)
			( signal "M_H_DQS_DN<17>"
				( objectStatus "@baseboard_fab2_lib.baseboard_fab2(sch_1):m_h_dqs_dn(17)" )
			)
			( signal "M_H_DQS_DP<0>"
				( objectStatus "@baseboard_fab2_lib.baseboard_fab2(sch_1):m_h_dqs_dp(0)" )
			)
			( signal "M_H_DQS_DP<1>"
				( objectStatus "@baseboard_fab2_lib.baseboard_fab2(sch_1):m_h_dqs_dp(1)" )
			)
			( signal "M_H_DQS_DP<2>"
				( objectStatus "@baseboard_fab2_lib.baseboard_fab2(sch_1):m_h_dqs_dp(2)" )
			)
			( signal "M_H_DQS_DP<3>"
				( objectStatus "@baseboard_fab2_lib.baseboard_fab2(sch_1):m_h_dqs_dp(3)" )
			)
			( signal "M_H_DQS_DP<4>"
				( objectStatus "@baseboard_fab2_lib.baseboard_fab2(sch_1):m_h_dqs_dp(4)" )
			)
			( signal "M_H_DQS_DP<5>"
				( objectStatus "@baseboard_fab2_lib.baseboard_fab2(sch_1):m_h_dqs_dp(5)" )
			)
			( signal "M_H_DQS_DP<6>"
				( objectStatus "@baseboard_fab2_lib.baseboard_fab2(sch_1):m_h_dqs_dp(6)" )
			)
			( signal "M_H_DQS_DP<7>"
				( objectStatus "@baseboard_fab2_lib.baseboard_fab2(sch_1):m_h_dqs_dp(7)" )
			)
			( signal "M_H_DQS_DP<8>"
				( objectStatus "@baseboard_fab2_lib.baseboard_fab2(sch_1):m_h_dqs_dp(8)" )
			)
			( signal "M_H_DQS_DP<9>"
				( objectStatus "@baseboard_fab2_lib.baseboard_fab2(sch_1):m_h_dqs_dp(9)" )
			)
			( signal "M_H_DQS_DP<10>"
				( objectStatus "@baseboard_fab2_lib.baseboard_fab2(sch_1):m_h_dqs_dp(10)" )
			)
			( signal "M_H_DQS_DP<11>"
				( objectStatus "@baseboard_fab2_lib.baseboard_fab2(sch_1):m_h_dqs_dp(11)" )
			)
			( signal "M_H_DQS_DP<12>"
				( objectStatus "@baseboard_fab2_lib.baseboard_fab2(sch_1):m_h_dqs_dp(12)" )
			)
			( signal "M_H_DQS_DP<13>"
				( objectStatus "@baseboard_fab2_lib.baseboard_fab2(sch_1):m_h_dqs_dp(13)" )
			)
			( signal "M_H_DQS_DP<14>"
				( objectStatus "@baseboard_fab2_lib.baseboard_fab2(sch_1):m_h_dqs_dp(14)" )
			)
			( signal "M_H_DQS_DP<15>"
				( objectStatus "@baseboard_fab2_lib.baseboard_fab2(sch_1):m_h_dqs_dp(15)" )
			)
			( signal "M_H_DQS_DP<16>"
				( objectStatus "@baseboard_fab2_lib.baseboard_fab2(sch_1):m_h_dqs_dp(16)" )
			)
			( signal "M_H_DQS_DP<17>"
				( objectStatus "@baseboard_fab2_lib.baseboard_fab2(sch_1):m_h_dqs_dp(17)" )
			)
			( signal "M_H_ECC<0>"
				( objectStatus "@baseboard_fab2_lib.baseboard_fab2(sch_1):m_h_ecc(0)" )
			)
			( signal "M_H_ECC<1>"
				( objectStatus "@baseboard_fab2_lib.baseboard_fab2(sch_1):m_h_ecc(1)" )
			)
			( signal "M_H_ECC<2>"
				( objectStatus "@baseboard_fab2_lib.baseboard_fab2(sch_1):m_h_ecc(2)" )
			)
			( signal "M_H_ECC<3>"
				( objectStatus "@baseboard_fab2_lib.baseboard_fab2(sch_1):m_h_ecc(3)" )
			)
			( signal "M_H_ECC<4>"
				( objectStatus "@baseboard_fab2_lib.baseboard_fab2(sch_1):m_h_ecc(4)" )
			)
			( signal "M_H_ECC<5>"
				( objectStatus "@baseboard_fab2_lib.baseboard_fab2(sch_1):m_h_ecc(5)" )
			)
			( signal "M_H_ECC<6>"
				( objectStatus "@baseboard_fab2_lib.baseboard_fab2(sch_1):m_h_ecc(6)" )
			)
			( signal "M_H_ECC<7>"
				( objectStatus "@baseboard_fab2_lib.baseboard_fab2(sch_1):m_h_ecc(7)" )
			)
			( signal "M_H_MA<0>"
				( objectStatus "@baseboard_fab2_lib.baseboard_fab2(sch_1):m_h_ma(0)" )
			)
			( signal "M_H_MA<1>"
				( objectStatus "@baseboard_fab2_lib.baseboard_fab2(sch_1):m_h_ma(1)" )
			)
			( signal "M_H_MA<2>"
				( objectStatus "@baseboard_fab2_lib.baseboard_fab2(sch_1):m_h_ma(2)" )
			)
			( signal "M_H_MA<3>"
				( objectStatus "@baseboard_fab2_lib.baseboard_fab2(sch_1):m_h_ma(3)" )
			)
			( signal "M_H_MA<4>"
				( objectStatus "@baseboard_fab2_lib.baseboard_fab2(sch_1):m_h_ma(4)" )
			)
			( signal "M_H_MA<5>"
				( objectStatus "@baseboard_fab2_lib.baseboard_fab2(sch_1):m_h_ma(5)" )
			)
			( signal "M_H_MA<6>"
				( objectStatus "@baseboard_fab2_lib.baseboard_fab2(sch_1):m_h_ma(6)" )
			)
			( signal "M_H_MA<7>"
				( objectStatus "@baseboard_fab2_lib.baseboard_fab2(sch_1):m_h_ma(7)" )
			)
			( signal "M_H_MA<8>"
				( objectStatus "@baseboard_fab2_lib.baseboard_fab2(sch_1):m_h_ma(8)" )
			)
			( signal "M_H_MA<9>"
				( objectStatus "@baseboard_fab2_lib.baseboard_fab2(sch_1):m_h_ma(9)" )
			)
			( signal "M_H_MA<10>"
				( objectStatus "@baseboard_fab2_lib.baseboard_fab2(sch_1):m_h_ma(10)" )
			)
			( signal "M_H_MA<11>"
				( objectStatus "@baseboard_fab2_lib.baseboard_fab2(sch_1):m_h_ma(11)" )
			)
			( signal "M_H_MA<12>"
				( objectStatus "@baseboard_fab2_lib.baseboard_fab2(sch_1):m_h_ma(12)" )
			)
			( signal "M_H_MA<13>"
				( objectStatus "@baseboard_fab2_lib.baseboard_fab2(sch_1):m_h_ma(13)" )
			)
			( signal "M_H_MA<14>"
				( objectStatus "@baseboard_fab2_lib.baseboard_fab2(sch_1):m_h_ma(14)" )
			)
			( signal "M_H_MA<15>"
				( objectStatus "@baseboard_fab2_lib.baseboard_fab2(sch_1):m_h_ma(15)" )
			)
			( signal "M_H_MA<16>"
				( objectStatus "@baseboard_fab2_lib.baseboard_fab2(sch_1):m_h_ma(16)" )
			)
			( signal "M_H_MA<17>"
				( objectStatus "@baseboard_fab2_lib.baseboard_fab2(sch_1):m_h_ma(17)" )
			)
			( signal "M_H_ODT<0>"
				( objectStatus "@baseboard_fab2_lib.baseboard_fab2(sch_1):m_h_odt(0)" )
			)
			( signal "M_H_ODT<1>"
				( objectStatus "@baseboard_fab2_lib.baseboard_fab2(sch_1):m_h_odt(1)" )
			)
			( signal "M_H_ODT<2>"
				( objectStatus "@baseboard_fab2_lib.baseboard_fab2(sch_1):m_h_odt(2)" )
			)
			( signal "M_H_ODT<3>"
				( objectStatus "@baseboard_fab2_lib.baseboard_fab2(sch_1):m_h_odt(3)" )
			)
			( signal "M_H_PAR"
				( objectStatus "@baseboard_fab2_lib.baseboard_fab2(sch_1):m_h_par" )
			)
			( signal "M_J_ACT_N"
				( objectStatus "@baseboard_fab2_lib.baseboard_fab2(sch_1):m_j_act_n" )
			)
			( signal "M_J_ALERT_N"
				( objectStatus "@baseboard_fab2_lib.baseboard_fab2(sch_1):m_j_alert_n" )
			)
			( signal "M_J_BA<0>"
				( objectStatus "@baseboard_fab2_lib.baseboard_fab2(sch_1):m_j_ba(0)" )
			)
			( signal "M_J_BA<1>"
				( objectStatus "@baseboard_fab2_lib.baseboard_fab2(sch_1):m_j_ba(1)" )
			)
			( signal "M_J_BG<0>"
				( objectStatus "@baseboard_fab2_lib.baseboard_fab2(sch_1):m_j_bg(0)" )
			)
			( signal "M_J_BG<1>"
				( objectStatus "@baseboard_fab2_lib.baseboard_fab2(sch_1):m_j_bg(1)" )
			)
			( signal "M_J_C<2>"
				( objectStatus "@baseboard_fab2_lib.baseboard_fab2(sch_1):m_j_c(2)" )
			)
			( signal "M_J_CKE<0>"
				( objectStatus "@baseboard_fab2_lib.baseboard_fab2(sch_1):m_j_cke(0)" )
			)
			( signal "M_J_CKE<1>"
				( objectStatus "@baseboard_fab2_lib.baseboard_fab2(sch_1):m_j_cke(1)" )
			)
			( signal "M_J_CKE<2>"
				( objectStatus "@baseboard_fab2_lib.baseboard_fab2(sch_1):m_j_cke(2)" )
			)
			( signal "M_J_CKE<3>"
				( objectStatus "@baseboard_fab2_lib.baseboard_fab2(sch_1):m_j_cke(3)" )
			)
			( signal "M_J_CLK_DN<0>"
				( objectStatus "@baseboard_fab2_lib.baseboard_fab2(sch_1):m_j_clk_dn(0)" )
			)
			( signal "M_J_CLK_DN<1>"
				( objectStatus "@baseboard_fab2_lib.baseboard_fab2(sch_1):m_j_clk_dn(1)" )
			)
			( signal "M_J_CLK_DN<2>"
				( objectStatus "@baseboard_fab2_lib.baseboard_fab2(sch_1):m_j_clk_dn(2)" )
			)
			( signal "M_J_CLK_DN<3>"
				( objectStatus "@baseboard_fab2_lib.baseboard_fab2(sch_1):m_j_clk_dn(3)" )
			)
			( signal "M_J_CLK_DP<0>"
				( objectStatus "@baseboard_fab2_lib.baseboard_fab2(sch_1):m_j_clk_dp(0)" )
			)
			( signal "M_J_CLK_DP<1>"
				( objectStatus "@baseboard_fab2_lib.baseboard_fab2(sch_1):m_j_clk_dp(1)" )
			)
			( signal "M_J_CLK_DP<2>"
				( objectStatus "@baseboard_fab2_lib.baseboard_fab2(sch_1):m_j_clk_dp(2)" )
			)
			( signal "M_J_CLK_DP<3>"
				( objectStatus "@baseboard_fab2_lib.baseboard_fab2(sch_1):m_j_clk_dp(3)" )
			)
			( signal "M_J_CS_N<0>"
				( objectStatus "@baseboard_fab2_lib.baseboard_fab2(sch_1):m_j_cs_n(0)" )
			)
			( signal "M_J_CS_N<1>"
				( objectStatus "@baseboard_fab2_lib.baseboard_fab2(sch_1):m_j_cs_n(1)" )
			)
			( signal "M_J_CS_N<2>"
				( objectStatus "@baseboard_fab2_lib.baseboard_fab2(sch_1):m_j_cs_n(2)" )
			)
			( signal "M_J_CS_N<3>"
				( objectStatus "@baseboard_fab2_lib.baseboard_fab2(sch_1):m_j_cs_n(3)" )
			)
			( signal "M_J_CS_N<4>"
				( objectStatus "@baseboard_fab2_lib.baseboard_fab2(sch_1):m_j_cs_n(4)" )
			)
			( signal "M_J_CS_N<5>"
				( objectStatus "@baseboard_fab2_lib.baseboard_fab2(sch_1):m_j_cs_n(5)" )
			)
			( signal "M_J_CS_N<6>"
				( objectStatus "@baseboard_fab2_lib.baseboard_fab2(sch_1):m_j_cs_n(6)" )
			)
			( signal "M_J_CS_N<7>"
				( objectStatus "@baseboard_fab2_lib.baseboard_fab2(sch_1):m_j_cs_n(7)" )
			)
			( signal "M_J_DQ<0>"
				( objectStatus "@baseboard_fab2_lib.baseboard_fab2(sch_1):m_j_dq(0)" )
			)
			( signal "M_J_DQ<1>"
				( objectStatus "@baseboard_fab2_lib.baseboard_fab2(sch_1):m_j_dq(1)" )
			)
			( signal "M_J_DQ<2>"
				( objectStatus "@baseboard_fab2_lib.baseboard_fab2(sch_1):m_j_dq(2)" )
			)
			( signal "M_J_DQ<3>"
				( objectStatus "@baseboard_fab2_lib.baseboard_fab2(sch_1):m_j_dq(3)" )
			)
			( signal "M_J_DQ<4>"
				( objectStatus "@baseboard_fab2_lib.baseboard_fab2(sch_1):m_j_dq(4)" )
			)
			( signal "M_J_DQ<5>"
				( objectStatus "@baseboard_fab2_lib.baseboard_fab2(sch_1):m_j_dq(5)" )
			)
			( signal "M_J_DQ<6>"
				( objectStatus "@baseboard_fab2_lib.baseboard_fab2(sch_1):m_j_dq(6)" )
			)
			( signal "M_J_DQ<7>"
				( objectStatus "@baseboard_fab2_lib.baseboard_fab2(sch_1):m_j_dq(7)" )
			)
			( signal "M_J_DQ<8>"
				( objectStatus "@baseboard_fab2_lib.baseboard_fab2(sch_1):m_j_dq(8)" )
			)
			( signal "M_J_DQ<9>"
				( objectStatus "@baseboard_fab2_lib.baseboard_fab2(sch_1):m_j_dq(9)" )
			)
			( signal "M_J_DQ<10>"
				( objectStatus "@baseboard_fab2_lib.baseboard_fab2(sch_1):m_j_dq(10)" )
			)
			( signal "M_J_DQ<11>"
				( objectStatus "@baseboard_fab2_lib.baseboard_fab2(sch_1):m_j_dq(11)" )
			)
			( signal "M_J_DQ<12>"
				( objectStatus "@baseboard_fab2_lib.baseboard_fab2(sch_1):m_j_dq(12)" )
			)
			( signal "M_J_DQ<13>"
				( objectStatus "@baseboard_fab2_lib.baseboard_fab2(sch_1):m_j_dq(13)" )
			)
			( signal "M_J_DQ<14>"
				( objectStatus "@baseboard_fab2_lib.baseboard_fab2(sch_1):m_j_dq(14)" )
			)
			( signal "M_J_DQ<15>"
				( objectStatus "@baseboard_fab2_lib.baseboard_fab2(sch_1):m_j_dq(15)" )
			)
			( signal "M_J_DQ<16>"
				( objectStatus "@baseboard_fab2_lib.baseboard_fab2(sch_1):m_j_dq(16)" )
			)
			( signal "M_J_DQ<17>"
				( objectStatus "@baseboard_fab2_lib.baseboard_fab2(sch_1):m_j_dq(17)" )
			)
			( signal "M_J_DQ<18>"
				( objectStatus "@baseboard_fab2_lib.baseboard_fab2(sch_1):m_j_dq(18)" )
			)
			( signal "M_J_DQ<19>"
				( objectStatus "@baseboard_fab2_lib.baseboard_fab2(sch_1):m_j_dq(19)" )
			)
			( signal "M_J_DQ<20>"
				( objectStatus "@baseboard_fab2_lib.baseboard_fab2(sch_1):m_j_dq(20)" )
			)
			( signal "M_J_DQ<21>"
				( objectStatus "@baseboard_fab2_lib.baseboard_fab2(sch_1):m_j_dq(21)" )
			)
			( signal "M_J_DQ<22>"
				( objectStatus "@baseboard_fab2_lib.baseboard_fab2(sch_1):m_j_dq(22)" )
			)
			( signal "M_J_DQ<23>"
				( objectStatus "@baseboard_fab2_lib.baseboard_fab2(sch_1):m_j_dq(23)" )
			)
			( signal "M_J_DQ<24>"
				( objectStatus "@baseboard_fab2_lib.baseboard_fab2(sch_1):m_j_dq(24)" )
			)
			( signal "M_J_DQ<25>"
				( objectStatus "@baseboard_fab2_lib.baseboard_fab2(sch_1):m_j_dq(25)" )
			)
			( signal "M_J_DQ<26>"
				( objectStatus "@baseboard_fab2_lib.baseboard_fab2(sch_1):m_j_dq(26)" )
			)
			( signal "M_J_DQ<27>"
				( objectStatus "@baseboard_fab2_lib.baseboard_fab2(sch_1):m_j_dq(27)" )
			)
			( signal "M_J_DQ<28>"
				( objectStatus "@baseboard_fab2_lib.baseboard_fab2(sch_1):m_j_dq(28)" )
			)
			( signal "M_J_DQ<29>"
				( objectStatus "@baseboard_fab2_lib.baseboard_fab2(sch_1):m_j_dq(29)" )
			)
			( signal "M_J_DQ<30>"
				( objectStatus "@baseboard_fab2_lib.baseboard_fab2(sch_1):m_j_dq(30)" )
			)
			( signal "M_J_DQ<31>"
				( objectStatus "@baseboard_fab2_lib.baseboard_fab2(sch_1):m_j_dq(31)" )
			)
			( signal "M_J_DQ<32>"
				( objectStatus "@baseboard_fab2_lib.baseboard_fab2(sch_1):m_j_dq(32)" )
			)
			( signal "M_J_DQ<33>"
				( objectStatus "@baseboard_fab2_lib.baseboard_fab2(sch_1):m_j_dq(33)" )
			)
			( signal "M_J_DQ<34>"
				( objectStatus "@baseboard_fab2_lib.baseboard_fab2(sch_1):m_j_dq(34)" )
			)
			( signal "M_J_DQ<35>"
				( objectStatus "@baseboard_fab2_lib.baseboard_fab2(sch_1):m_j_dq(35)" )
			)
			( signal "M_J_DQ<36>"
				( objectStatus "@baseboard_fab2_lib.baseboard_fab2(sch_1):m_j_dq(36)" )
			)
			( signal "M_J_DQ<37>"
				( objectStatus "@baseboard_fab2_lib.baseboard_fab2(sch_1):m_j_dq(37)" )
			)
			( signal "M_J_DQ<38>"
				( objectStatus "@baseboard_fab2_lib.baseboard_fab2(sch_1):m_j_dq(38)" )
			)
			( signal "M_J_DQ<39>"
				( objectStatus "@baseboard_fab2_lib.baseboard_fab2(sch_1):m_j_dq(39)" )
			)
			( signal "M_J_DQ<40>"
				( objectStatus "@baseboard_fab2_lib.baseboard_fab2(sch_1):m_j_dq(40)" )
			)
			( signal "M_J_DQ<41>"
				( objectStatus "@baseboard_fab2_lib.baseboard_fab2(sch_1):m_j_dq(41)" )
			)
			( signal "M_J_DQ<42>"
				( objectStatus "@baseboard_fab2_lib.baseboard_fab2(sch_1):m_j_dq(42)" )
			)
			( signal "M_J_DQ<43>"
				( objectStatus "@baseboard_fab2_lib.baseboard_fab2(sch_1):m_j_dq(43)" )
			)
			( signal "M_J_DQ<44>"
				( objectStatus "@baseboard_fab2_lib.baseboard_fab2(sch_1):m_j_dq(44)" )
			)
			( signal "M_J_DQ<45>"
				( objectStatus "@baseboard_fab2_lib.baseboard_fab2(sch_1):m_j_dq(45)" )
			)
			( signal "M_J_DQ<46>"
				( objectStatus "@baseboard_fab2_lib.baseboard_fab2(sch_1):m_j_dq(46)" )
			)
			( signal "M_J_DQ<47>"
				( objectStatus "@baseboard_fab2_lib.baseboard_fab2(sch_1):m_j_dq(47)" )
			)
			( signal "M_J_DQ<48>"
				( objectStatus "@baseboard_fab2_lib.baseboard_fab2(sch_1):m_j_dq(48)" )
			)
			( signal "M_J_DQ<49>"
				( objectStatus "@baseboard_fab2_lib.baseboard_fab2(sch_1):m_j_dq(49)" )
			)
			( signal "M_J_DQ<50>"
				( objectStatus "@baseboard_fab2_lib.baseboard_fab2(sch_1):m_j_dq(50)" )
			)
			( signal "M_J_DQ<51>"
				( objectStatus "@baseboard_fab2_lib.baseboard_fab2(sch_1):m_j_dq(51)" )
			)
			( signal "M_J_DQ<52>"
				( objectStatus "@baseboard_fab2_lib.baseboard_fab2(sch_1):m_j_dq(52)" )
			)
			( signal "M_J_DQ<53>"
				( objectStatus "@baseboard_fab2_lib.baseboard_fab2(sch_1):m_j_dq(53)" )
			)
			( signal "M_J_DQ<54>"
				( objectStatus "@baseboard_fab2_lib.baseboard_fab2(sch_1):m_j_dq(54)" )
			)
			( signal "M_J_DQ<55>"
				( objectStatus "@baseboard_fab2_lib.baseboard_fab2(sch_1):m_j_dq(55)" )
			)
			( signal "M_J_DQ<56>"
				( objectStatus "@baseboard_fab2_lib.baseboard_fab2(sch_1):m_j_dq(56)" )
			)
			( signal "M_J_DQ<57>"
				( objectStatus "@baseboard_fab2_lib.baseboard_fab2(sch_1):m_j_dq(57)" )
			)
			( signal "M_J_DQ<58>"
				( objectStatus "@baseboard_fab2_lib.baseboard_fab2(sch_1):m_j_dq(58)" )
			)
			( signal "M_J_DQ<59>"
				( objectStatus "@baseboard_fab2_lib.baseboard_fab2(sch_1):m_j_dq(59)" )
			)
			( signal "M_J_DQ<60>"
				( objectStatus "@baseboard_fab2_lib.baseboard_fab2(sch_1):m_j_dq(60)" )
			)
			( signal "M_J_DQ<61>"
				( objectStatus "@baseboard_fab2_lib.baseboard_fab2(sch_1):m_j_dq(61)" )
			)
			( signal "M_J_DQ<62>"
				( objectStatus "@baseboard_fab2_lib.baseboard_fab2(sch_1):m_j_dq(62)" )
			)
			( signal "M_J_DQ<63>"
				( objectStatus "@baseboard_fab2_lib.baseboard_fab2(sch_1):m_j_dq(63)" )
			)
			( signal "M_J_DQS_DN<0>"
				( objectStatus "@baseboard_fab2_lib.baseboard_fab2(sch_1):m_j_dqs_dn(0)" )
			)
			( signal "M_J_DQS_DN<1>"
				( objectStatus "@baseboard_fab2_lib.baseboard_fab2(sch_1):m_j_dqs_dn(1)" )
			)
			( signal "M_J_DQS_DN<2>"
				( objectStatus "@baseboard_fab2_lib.baseboard_fab2(sch_1):m_j_dqs_dn(2)" )
			)
			( signal "M_J_DQS_DN<3>"
				( objectStatus "@baseboard_fab2_lib.baseboard_fab2(sch_1):m_j_dqs_dn(3)" )
			)
			( signal "M_J_DQS_DN<4>"
				( objectStatus "@baseboard_fab2_lib.baseboard_fab2(sch_1):m_j_dqs_dn(4)" )
			)
			( signal "M_J_DQS_DN<5>"
				( objectStatus "@baseboard_fab2_lib.baseboard_fab2(sch_1):m_j_dqs_dn(5)" )
			)
			( signal "M_J_DQS_DN<6>"
				( objectStatus "@baseboard_fab2_lib.baseboard_fab2(sch_1):m_j_dqs_dn(6)" )
			)
			( signal "M_J_DQS_DN<7>"
				( objectStatus "@baseboard_fab2_lib.baseboard_fab2(sch_1):m_j_dqs_dn(7)" )
			)
			( signal "M_J_DQS_DN<8>"
				( objectStatus "@baseboard_fab2_lib.baseboard_fab2(sch_1):m_j_dqs_dn(8)" )
			)
			( signal "M_J_DQS_DN<9>"
				( objectStatus "@baseboard_fab2_lib.baseboard_fab2(sch_1):m_j_dqs_dn(9)" )
			)
			( signal "M_J_DQS_DN<10>"
				( objectStatus "@baseboard_fab2_lib.baseboard_fab2(sch_1):m_j_dqs_dn(10)" )
			)
			( signal "M_J_DQS_DN<11>"
				( objectStatus "@baseboard_fab2_lib.baseboard_fab2(sch_1):m_j_dqs_dn(11)" )
			)
			( signal "M_J_DQS_DN<12>"
				( objectStatus "@baseboard_fab2_lib.baseboard_fab2(sch_1):m_j_dqs_dn(12)" )
			)
			( signal "M_J_DQS_DN<13>"
				( objectStatus "@baseboard_fab2_lib.baseboard_fab2(sch_1):m_j_dqs_dn(13)" )
			)
			( signal "M_J_DQS_DN<14>"
				( objectStatus "@baseboard_fab2_lib.baseboard_fab2(sch_1):m_j_dqs_dn(14)" )
			)
			( signal "M_J_DQS_DN<15>"
				( objectStatus "@baseboard_fab2_lib.baseboard_fab2(sch_1):m_j_dqs_dn(15)" )
			)
			( signal "M_J_DQS_DN<16>"
				( objectStatus "@baseboard_fab2_lib.baseboard_fab2(sch_1):m_j_dqs_dn(16)" )
			)
			( signal "M_J_DQS_DN<17>"
				( objectStatus "@baseboard_fab2_lib.baseboard_fab2(sch_1):m_j_dqs_dn(17)" )
			)
			( signal "M_J_DQS_DP<0>"
				( objectStatus "@baseboard_fab2_lib.baseboard_fab2(sch_1):m_j_dqs_dp(0)" )
			)
			( signal "M_J_DQS_DP<1>"
				( objectStatus "@baseboard_fab2_lib.baseboard_fab2(sch_1):m_j_dqs_dp(1)" )
			)
			( signal "M_J_DQS_DP<2>"
				( objectStatus "@baseboard_fab2_lib.baseboard_fab2(sch_1):m_j_dqs_dp(2)" )
			)
			( signal "M_J_DQS_DP<3>"
				( objectStatus "@baseboard_fab2_lib.baseboard_fab2(sch_1):m_j_dqs_dp(3)" )
			)
			( signal "M_J_DQS_DP<4>"
				( objectStatus "@baseboard_fab2_lib.baseboard_fab2(sch_1):m_j_dqs_dp(4)" )
			)
			( signal "M_J_DQS_DP<5>"
				( objectStatus "@baseboard_fab2_lib.baseboard_fab2(sch_1):m_j_dqs_dp(5)" )
			)
			( signal "M_J_DQS_DP<6>"
				( objectStatus "@baseboard_fab2_lib.baseboard_fab2(sch_1):m_j_dqs_dp(6)" )
			)
			( signal "M_J_DQS_DP<7>"
				( objectStatus "@baseboard_fab2_lib.baseboard_fab2(sch_1):m_j_dqs_dp(7)" )
			)
			( signal "M_J_DQS_DP<8>"
				( objectStatus "@baseboard_fab2_lib.baseboard_fab2(sch_1):m_j_dqs_dp(8)" )
			)
			( signal "M_J_DQS_DP<9>"
				( objectStatus "@baseboard_fab2_lib.baseboard_fab2(sch_1):m_j_dqs_dp(9)" )
			)
			( signal "M_J_DQS_DP<10>"
				( objectStatus "@baseboard_fab2_lib.baseboard_fab2(sch_1):m_j_dqs_dp(10)" )
			)
			( signal "M_J_DQS_DP<11>"
				( objectStatus "@baseboard_fab2_lib.baseboard_fab2(sch_1):m_j_dqs_dp(11)" )
			)
			( signal "M_J_DQS_DP<12>"
				( objectStatus "@baseboard_fab2_lib.baseboard_fab2(sch_1):m_j_dqs_dp(12)" )
			)
			( signal "M_J_DQS_DP<13>"
				( objectStatus "@baseboard_fab2_lib.baseboard_fab2(sch_1):m_j_dqs_dp(13)" )
			)
			( signal "M_J_DQS_DP<14>"
				( objectStatus "@baseboard_fab2_lib.baseboard_fab2(sch_1):m_j_dqs_dp(14)" )
			)
			( signal "M_J_DQS_DP<15>"
				( objectStatus "@baseboard_fab2_lib.baseboard_fab2(sch_1):m_j_dqs_dp(15)" )
			)
			( signal "M_J_DQS_DP<16>"
				( objectStatus "@baseboard_fab2_lib.baseboard_fab2(sch_1):m_j_dqs_dp(16)" )
			)
			( signal "M_J_DQS_DP<17>"
				( objectStatus "@baseboard_fab2_lib.baseboard_fab2(sch_1):m_j_dqs_dp(17)" )
			)
			( signal "M_J_ECC<0>"
				( objectStatus "@baseboard_fab2_lib.baseboard_fab2(sch_1):m_j_ecc(0)" )
			)
			( signal "M_J_ECC<1>"
				( objectStatus "@baseboard_fab2_lib.baseboard_fab2(sch_1):m_j_ecc(1)" )
			)
			( signal "M_J_ECC<2>"
				( objectStatus "@baseboard_fab2_lib.baseboard_fab2(sch_1):m_j_ecc(2)" )
			)
			( signal "M_J_ECC<3>"
				( objectStatus "@baseboard_fab2_lib.baseboard_fab2(sch_1):m_j_ecc(3)" )
			)
			( signal "M_J_ECC<4>"
				( objectStatus "@baseboard_fab2_lib.baseboard_fab2(sch_1):m_j_ecc(4)" )
			)
			( signal "M_J_ECC<5>"
				( objectStatus "@baseboard_fab2_lib.baseboard_fab2(sch_1):m_j_ecc(5)" )
			)
			( signal "M_J_ECC<6>"
				( objectStatus "@baseboard_fab2_lib.baseboard_fab2(sch_1):m_j_ecc(6)" )
			)
			( signal "M_J_ECC<7>"
				( objectStatus "@baseboard_fab2_lib.baseboard_fab2(sch_1):m_j_ecc(7)" )
			)
			( signal "M_J_MA<0>"
				( objectStatus "@baseboard_fab2_lib.baseboard_fab2(sch_1):m_j_ma(0)" )
			)
			( signal "M_J_MA<1>"
				( objectStatus "@baseboard_fab2_lib.baseboard_fab2(sch_1):m_j_ma(1)" )
			)
			( signal "M_J_MA<2>"
				( objectStatus "@baseboard_fab2_lib.baseboard_fab2(sch_1):m_j_ma(2)" )
			)
			( signal "M_J_MA<3>"
				( objectStatus "@baseboard_fab2_lib.baseboard_fab2(sch_1):m_j_ma(3)" )
			)
			( signal "M_J_MA<4>"
				( objectStatus "@baseboard_fab2_lib.baseboard_fab2(sch_1):m_j_ma(4)" )
			)
			( signal "M_J_MA<5>"
				( objectStatus "@baseboard_fab2_lib.baseboard_fab2(sch_1):m_j_ma(5)" )
			)
			( signal "M_J_MA<6>"
				( objectStatus "@baseboard_fab2_lib.baseboard_fab2(sch_1):m_j_ma(6)" )
			)
			( signal "M_J_MA<7>"
				( objectStatus "@baseboard_fab2_lib.baseboard_fab2(sch_1):m_j_ma(7)" )
			)
			( signal "M_J_MA<8>"
				( objectStatus "@baseboard_fab2_lib.baseboard_fab2(sch_1):m_j_ma(8)" )
			)
			( signal "M_J_MA<9>"
				( objectStatus "@baseboard_fab2_lib.baseboard_fab2(sch_1):m_j_ma(9)" )
			)
			( signal "M_J_MA<10>"
				( objectStatus "@baseboard_fab2_lib.baseboard_fab2(sch_1):m_j_ma(10)" )
			)
			( signal "M_J_MA<11>"
				( objectStatus "@baseboard_fab2_lib.baseboard_fab2(sch_1):m_j_ma(11)" )
			)
			( signal "M_J_MA<12>"
				( objectStatus "@baseboard_fab2_lib.baseboard_fab2(sch_1):m_j_ma(12)" )
			)
			( signal "M_J_MA<13>"
				( objectStatus "@baseboard_fab2_lib.baseboard_fab2(sch_1):m_j_ma(13)" )
			)
			( signal "M_J_MA<14>"
				( objectStatus "@baseboard_fab2_lib.baseboard_fab2(sch_1):m_j_ma(14)" )
			)
			( signal "M_J_MA<15>"
				( objectStatus "@baseboard_fab2_lib.baseboard_fab2(sch_1):m_j_ma(15)" )
			)
			( signal "M_J_MA<16>"
				( objectStatus "@baseboard_fab2_lib.baseboard_fab2(sch_1):m_j_ma(16)" )
			)
			( signal "M_J_MA<17>"
				( objectStatus "@baseboard_fab2_lib.baseboard_fab2(sch_1):m_j_ma(17)" )
			)
			( signal "M_J_ODT<0>"
				( objectStatus "@baseboard_fab2_lib.baseboard_fab2(sch_1):m_j_odt(0)" )
			)
			( signal "M_J_ODT<1>"
				( objectStatus "@baseboard_fab2_lib.baseboard_fab2(sch_1):m_j_odt(1)" )
			)
			( signal "M_J_ODT<2>"
				( objectStatus "@baseboard_fab2_lib.baseboard_fab2(sch_1):m_j_odt(2)" )
			)
			( signal "M_J_ODT<3>"
				( objectStatus "@baseboard_fab2_lib.baseboard_fab2(sch_1):m_j_odt(3)" )
			)
			( signal "M_J_PAR"
				( objectStatus "@baseboard_fab2_lib.baseboard_fab2(sch_1):m_j_par" )
			)
			( signal "M_K_ACT_N"
				( objectStatus "@baseboard_fab2_lib.baseboard_fab2(sch_1):m_k_act_n" )
			)
			( signal "M_K_ALERT_N"
				( objectStatus "@baseboard_fab2_lib.baseboard_fab2(sch_1):m_k_alert_n" )
			)
			( signal "M_K_BA<0>"
				( objectStatus "@baseboard_fab2_lib.baseboard_fab2(sch_1):m_k_ba(0)" )
			)
			( signal "M_K_BA<1>"
				( objectStatus "@baseboard_fab2_lib.baseboard_fab2(sch_1):m_k_ba(1)" )
			)
			( signal "M_K_BG<0>"
				( objectStatus "@baseboard_fab2_lib.baseboard_fab2(sch_1):m_k_bg(0)" )
			)
			( signal "M_K_BG<1>"
				( objectStatus "@baseboard_fab2_lib.baseboard_fab2(sch_1):m_k_bg(1)" )
			)
			( signal "M_K_C<2>"
				( objectStatus "@baseboard_fab2_lib.baseboard_fab2(sch_1):m_k_c(2)" )
			)
			( signal "M_K_CKE<0>"
				( objectStatus "@baseboard_fab2_lib.baseboard_fab2(sch_1):m_k_cke(0)" )
			)
			( signal "M_K_CKE<1>"
				( objectStatus "@baseboard_fab2_lib.baseboard_fab2(sch_1):m_k_cke(1)" )
			)
			( signal "M_K_CKE<2>"
				( objectStatus "@baseboard_fab2_lib.baseboard_fab2(sch_1):m_k_cke(2)" )
			)
			( signal "M_K_CKE<3>"
				( objectStatus "@baseboard_fab2_lib.baseboard_fab2(sch_1):m_k_cke(3)" )
			)
			( signal "M_K_CLK_DN<0>"
				( objectStatus "@baseboard_fab2_lib.baseboard_fab2(sch_1):m_k_clk_dn(0)" )
			)
			( signal "M_K_CLK_DN<1>"
				( objectStatus "@baseboard_fab2_lib.baseboard_fab2(sch_1):m_k_clk_dn(1)" )
			)
			( signal "M_K_CLK_DN<2>"
				( objectStatus "@baseboard_fab2_lib.baseboard_fab2(sch_1):m_k_clk_dn(2)" )
			)
			( signal "M_K_CLK_DN<3>"
				( objectStatus "@baseboard_fab2_lib.baseboard_fab2(sch_1):m_k_clk_dn(3)" )
			)
			( signal "M_K_CLK_DP<0>"
				( objectStatus "@baseboard_fab2_lib.baseboard_fab2(sch_1):m_k_clk_dp(0)" )
			)
			( signal "M_K_CLK_DP<1>"
				( objectStatus "@baseboard_fab2_lib.baseboard_fab2(sch_1):m_k_clk_dp(1)" )
			)
			( signal "M_K_CLK_DP<2>"
				( objectStatus "@baseboard_fab2_lib.baseboard_fab2(sch_1):m_k_clk_dp(2)" )
			)
			( signal "M_K_CLK_DP<3>"
				( objectStatus "@baseboard_fab2_lib.baseboard_fab2(sch_1):m_k_clk_dp(3)" )
			)
			( signal "M_K_CS_N<0>"
				( objectStatus "@baseboard_fab2_lib.baseboard_fab2(sch_1):m_k_cs_n(0)" )
			)
			( signal "M_K_CS_N<1>"
				( objectStatus "@baseboard_fab2_lib.baseboard_fab2(sch_1):m_k_cs_n(1)" )
			)
			( signal "M_K_CS_N<2>"
				( objectStatus "@baseboard_fab2_lib.baseboard_fab2(sch_1):m_k_cs_n(2)" )
			)
			( signal "M_K_CS_N<3>"
				( objectStatus "@baseboard_fab2_lib.baseboard_fab2(sch_1):m_k_cs_n(3)" )
			)
			( signal "M_K_CS_N<4>"
				( objectStatus "@baseboard_fab2_lib.baseboard_fab2(sch_1):m_k_cs_n(4)" )
			)
			( signal "M_K_CS_N<5>"
				( objectStatus "@baseboard_fab2_lib.baseboard_fab2(sch_1):m_k_cs_n(5)" )
			)
			( signal "M_K_CS_N<6>"
				( objectStatus "@baseboard_fab2_lib.baseboard_fab2(sch_1):m_k_cs_n(6)" )
			)
			( signal "M_K_CS_N<7>"
				( objectStatus "@baseboard_fab2_lib.baseboard_fab2(sch_1):m_k_cs_n(7)" )
			)
			( signal "M_K_DQ<0>"
				( objectStatus "@baseboard_fab2_lib.baseboard_fab2(sch_1):m_k_dq(0)" )
			)
			( signal "M_K_DQ<1>"
				( objectStatus "@baseboard_fab2_lib.baseboard_fab2(sch_1):m_k_dq(1)" )
			)
			( signal "M_K_DQ<2>"
				( objectStatus "@baseboard_fab2_lib.baseboard_fab2(sch_1):m_k_dq(2)" )
			)
			( signal "M_K_DQ<3>"
				( objectStatus "@baseboard_fab2_lib.baseboard_fab2(sch_1):m_k_dq(3)" )
			)
			( signal "M_K_DQ<4>"
				( objectStatus "@baseboard_fab2_lib.baseboard_fab2(sch_1):m_k_dq(4)" )
			)
			( signal "M_K_DQ<5>"
				( objectStatus "@baseboard_fab2_lib.baseboard_fab2(sch_1):m_k_dq(5)" )
			)
			( signal "M_K_DQ<6>"
				( objectStatus "@baseboard_fab2_lib.baseboard_fab2(sch_1):m_k_dq(6)" )
			)
			( signal "M_K_DQ<7>"
				( objectStatus "@baseboard_fab2_lib.baseboard_fab2(sch_1):m_k_dq(7)" )
			)
			( signal "M_K_DQ<8>"
				( objectStatus "@baseboard_fab2_lib.baseboard_fab2(sch_1):m_k_dq(8)" )
			)
			( signal "M_K_DQ<9>"
				( objectStatus "@baseboard_fab2_lib.baseboard_fab2(sch_1):m_k_dq(9)" )
			)
			( signal "M_K_DQ<10>"
				( objectStatus "@baseboard_fab2_lib.baseboard_fab2(sch_1):m_k_dq(10)" )
			)
			( signal "M_K_DQ<11>"
				( objectStatus "@baseboard_fab2_lib.baseboard_fab2(sch_1):m_k_dq(11)" )
			)
			( signal "M_K_DQ<12>"
				( objectStatus "@baseboard_fab2_lib.baseboard_fab2(sch_1):m_k_dq(12)" )
			)
			( signal "M_K_DQ<13>"
				( objectStatus "@baseboard_fab2_lib.baseboard_fab2(sch_1):m_k_dq(13)" )
			)
			( signal "M_K_DQ<14>"
				( objectStatus "@baseboard_fab2_lib.baseboard_fab2(sch_1):m_k_dq(14)" )
			)
			( signal "M_K_DQ<15>"
				( objectStatus "@baseboard_fab2_lib.baseboard_fab2(sch_1):m_k_dq(15)" )
			)
			( signal "M_K_DQ<16>"
				( objectStatus "@baseboard_fab2_lib.baseboard_fab2(sch_1):m_k_dq(16)" )
			)
			( signal "M_K_DQ<17>"
				( objectStatus "@baseboard_fab2_lib.baseboard_fab2(sch_1):m_k_dq(17)" )
			)
			( signal "M_K_DQ<18>"
				( objectStatus "@baseboard_fab2_lib.baseboard_fab2(sch_1):m_k_dq(18)" )
			)
			( signal "M_K_DQ<19>"
				( objectStatus "@baseboard_fab2_lib.baseboard_fab2(sch_1):m_k_dq(19)" )
			)
			( signal "M_K_DQ<20>"
				( objectStatus "@baseboard_fab2_lib.baseboard_fab2(sch_1):m_k_dq(20)" )
			)
			( signal "M_K_DQ<21>"
				( objectStatus "@baseboard_fab2_lib.baseboard_fab2(sch_1):m_k_dq(21)" )
			)
			( signal "M_K_DQ<22>"
				( objectStatus "@baseboard_fab2_lib.baseboard_fab2(sch_1):m_k_dq(22)" )
			)
			( signal "M_K_DQ<23>"
				( objectStatus "@baseboard_fab2_lib.baseboard_fab2(sch_1):m_k_dq(23)" )
			)
			( signal "M_K_DQ<24>"
				( objectStatus "@baseboard_fab2_lib.baseboard_fab2(sch_1):m_k_dq(24)" )
			)
			( signal "M_K_DQ<25>"
				( objectStatus "@baseboard_fab2_lib.baseboard_fab2(sch_1):m_k_dq(25)" )
			)
			( signal "M_K_DQ<26>"
				( objectStatus "@baseboard_fab2_lib.baseboard_fab2(sch_1):m_k_dq(26)" )
			)
			( signal "M_K_DQ<27>"
				( objectStatus "@baseboard_fab2_lib.baseboard_fab2(sch_1):m_k_dq(27)" )
			)
			( signal "M_K_DQ<28>"
				( objectStatus "@baseboard_fab2_lib.baseboard_fab2(sch_1):m_k_dq(28)" )
			)
			( signal "M_K_DQ<29>"
				( objectStatus "@baseboard_fab2_lib.baseboard_fab2(sch_1):m_k_dq(29)" )
			)
			( signal "M_K_DQ<30>"
				( objectStatus "@baseboard_fab2_lib.baseboard_fab2(sch_1):m_k_dq(30)" )
			)
			( signal "M_K_DQ<31>"
				( objectStatus "@baseboard_fab2_lib.baseboard_fab2(sch_1):m_k_dq(31)" )
			)
			( signal "M_K_DQ<32>"
				( objectStatus "@baseboard_fab2_lib.baseboard_fab2(sch_1):m_k_dq(32)" )
			)
			( signal "M_K_DQ<33>"
				( objectStatus "@baseboard_fab2_lib.baseboard_fab2(sch_1):m_k_dq(33)" )
			)
			( signal "M_K_DQ<34>"
				( objectStatus "@baseboard_fab2_lib.baseboard_fab2(sch_1):m_k_dq(34)" )
			)
			( signal "M_K_DQ<35>"
				( objectStatus "@baseboard_fab2_lib.baseboard_fab2(sch_1):m_k_dq(35)" )
			)
			( signal "M_K_DQ<36>"
				( objectStatus "@baseboard_fab2_lib.baseboard_fab2(sch_1):m_k_dq(36)" )
			)
			( signal "M_K_DQ<37>"
				( objectStatus "@baseboard_fab2_lib.baseboard_fab2(sch_1):m_k_dq(37)" )
			)
			( signal "M_K_DQ<38>"
				( objectStatus "@baseboard_fab2_lib.baseboard_fab2(sch_1):m_k_dq(38)" )
			)
			( signal "M_K_DQ<39>"
				( objectStatus "@baseboard_fab2_lib.baseboard_fab2(sch_1):m_k_dq(39)" )
			)
			( signal "M_K_DQ<40>"
				( objectStatus "@baseboard_fab2_lib.baseboard_fab2(sch_1):m_k_dq(40)" )
			)
			( signal "M_K_DQ<41>"
				( objectStatus "@baseboard_fab2_lib.baseboard_fab2(sch_1):m_k_dq(41)" )
			)
			( signal "M_K_DQ<42>"
				( objectStatus "@baseboard_fab2_lib.baseboard_fab2(sch_1):m_k_dq(42)" )
			)
			( signal "M_K_DQ<43>"
				( objectStatus "@baseboard_fab2_lib.baseboard_fab2(sch_1):m_k_dq(43)" )
			)
			( signal "M_K_DQ<44>"
				( objectStatus "@baseboard_fab2_lib.baseboard_fab2(sch_1):m_k_dq(44)" )
			)
			( signal "M_K_DQ<45>"
				( objectStatus "@baseboard_fab2_lib.baseboard_fab2(sch_1):m_k_dq(45)" )
			)
			( signal "M_K_DQ<46>"
				( objectStatus "@baseboard_fab2_lib.baseboard_fab2(sch_1):m_k_dq(46)" )
			)
			( signal "M_K_DQ<47>"
				( objectStatus "@baseboard_fab2_lib.baseboard_fab2(sch_1):m_k_dq(47)" )
			)
			( signal "M_K_DQ<48>"
				( objectStatus "@baseboard_fab2_lib.baseboard_fab2(sch_1):m_k_dq(48)" )
			)
			( signal "M_K_DQ<49>"
				( objectStatus "@baseboard_fab2_lib.baseboard_fab2(sch_1):m_k_dq(49)" )
			)
			( signal "M_K_DQ<50>"
				( objectStatus "@baseboard_fab2_lib.baseboard_fab2(sch_1):m_k_dq(50)" )
			)
			( signal "M_K_DQ<51>"
				( objectStatus "@baseboard_fab2_lib.baseboard_fab2(sch_1):m_k_dq(51)" )
			)
			( signal "M_K_DQ<52>"
				( objectStatus "@baseboard_fab2_lib.baseboard_fab2(sch_1):m_k_dq(52)" )
			)
			( signal "M_K_DQ<53>"
				( objectStatus "@baseboard_fab2_lib.baseboard_fab2(sch_1):m_k_dq(53)" )
			)
			( signal "M_K_DQ<54>"
				( objectStatus "@baseboard_fab2_lib.baseboard_fab2(sch_1):m_k_dq(54)" )
			)
			( signal "M_K_DQ<55>"
				( objectStatus "@baseboard_fab2_lib.baseboard_fab2(sch_1):m_k_dq(55)" )
			)
			( signal "M_K_DQ<56>"
				( objectStatus "@baseboard_fab2_lib.baseboard_fab2(sch_1):m_k_dq(56)" )
			)
			( signal "M_K_DQ<57>"
				( objectStatus "@baseboard_fab2_lib.baseboard_fab2(sch_1):m_k_dq(57)" )
			)
			( signal "M_K_DQ<58>"
				( objectStatus "@baseboard_fab2_lib.baseboard_fab2(sch_1):m_k_dq(58)" )
			)
			( signal "M_K_DQ<59>"
				( objectStatus "@baseboard_fab2_lib.baseboard_fab2(sch_1):m_k_dq(59)" )
			)
			( signal "M_K_DQ<60>"
				( objectStatus "@baseboard_fab2_lib.baseboard_fab2(sch_1):m_k_dq(60)" )
			)
			( signal "M_K_DQ<61>"
				( objectStatus "@baseboard_fab2_lib.baseboard_fab2(sch_1):m_k_dq(61)" )
			)
			( signal "M_K_DQ<62>"
				( objectStatus "@baseboard_fab2_lib.baseboard_fab2(sch_1):m_k_dq(62)" )
			)
			( signal "M_K_DQ<63>"
				( objectStatus "@baseboard_fab2_lib.baseboard_fab2(sch_1):m_k_dq(63)" )
			)
			( signal "M_K_DQS_DN<0>"
				( objectStatus "@baseboard_fab2_lib.baseboard_fab2(sch_1):m_k_dqs_dn(0)" )
			)
			( signal "M_K_DQS_DN<1>"
				( objectStatus "@baseboard_fab2_lib.baseboard_fab2(sch_1):m_k_dqs_dn(1)" )
			)
			( signal "M_K_DQS_DN<2>"
				( objectStatus "@baseboard_fab2_lib.baseboard_fab2(sch_1):m_k_dqs_dn(2)" )
			)
			( signal "M_K_DQS_DN<3>"
				( objectStatus "@baseboard_fab2_lib.baseboard_fab2(sch_1):m_k_dqs_dn(3)" )
			)
			( signal "M_K_DQS_DN<4>"
				( objectStatus "@baseboard_fab2_lib.baseboard_fab2(sch_1):m_k_dqs_dn(4)" )
			)
			( signal "M_K_DQS_DN<5>"
				( objectStatus "@baseboard_fab2_lib.baseboard_fab2(sch_1):m_k_dqs_dn(5)" )
			)
			( signal "M_K_DQS_DN<6>"
				( objectStatus "@baseboard_fab2_lib.baseboard_fab2(sch_1):m_k_dqs_dn(6)" )
			)
			( signal "M_K_DQS_DN<7>"
				( objectStatus "@baseboard_fab2_lib.baseboard_fab2(sch_1):m_k_dqs_dn(7)" )
			)
			( signal "M_K_DQS_DN<8>"
				( objectStatus "@baseboard_fab2_lib.baseboard_fab2(sch_1):m_k_dqs_dn(8)" )
			)
			( signal "M_K_DQS_DN<9>"
				( objectStatus "@baseboard_fab2_lib.baseboard_fab2(sch_1):m_k_dqs_dn(9)" )
			)
			( signal "M_K_DQS_DN<10>"
				( objectStatus "@baseboard_fab2_lib.baseboard_fab2(sch_1):m_k_dqs_dn(10)" )
			)
			( signal "M_K_DQS_DN<11>"
				( objectStatus "@baseboard_fab2_lib.baseboard_fab2(sch_1):m_k_dqs_dn(11)" )
			)
			( signal "M_K_DQS_DN<12>"
				( objectStatus "@baseboard_fab2_lib.baseboard_fab2(sch_1):m_k_dqs_dn(12)" )
			)
			( signal "M_K_DQS_DN<13>"
				( objectStatus "@baseboard_fab2_lib.baseboard_fab2(sch_1):m_k_dqs_dn(13)" )
			)
			( signal "M_K_DQS_DN<14>"
				( objectStatus "@baseboard_fab2_lib.baseboard_fab2(sch_1):m_k_dqs_dn(14)" )
			)
			( signal "M_K_DQS_DN<15>"
				( objectStatus "@baseboard_fab2_lib.baseboard_fab2(sch_1):m_k_dqs_dn(15)" )
			)
			( signal "M_K_DQS_DN<16>"
				( objectStatus "@baseboard_fab2_lib.baseboard_fab2(sch_1):m_k_dqs_dn(16)" )
			)
			( signal "M_K_DQS_DN<17>"
				( objectStatus "@baseboard_fab2_lib.baseboard_fab2(sch_1):m_k_dqs_dn(17)" )
			)
			( signal "M_K_DQS_DP<0>"
				( objectStatus "@baseboard_fab2_lib.baseboard_fab2(sch_1):m_k_dqs_dp(0)" )
			)
			( signal "M_K_DQS_DP<1>"
				( objectStatus "@baseboard_fab2_lib.baseboard_fab2(sch_1):m_k_dqs_dp(1)" )
			)
			( signal "M_K_DQS_DP<2>"
				( objectStatus "@baseboard_fab2_lib.baseboard_fab2(sch_1):m_k_dqs_dp(2)" )
			)
			( signal "M_K_DQS_DP<3>"
				( objectStatus "@baseboard_fab2_lib.baseboard_fab2(sch_1):m_k_dqs_dp(3)" )
			)
			( signal "M_K_DQS_DP<4>"
				( objectStatus "@baseboard_fab2_lib.baseboard_fab2(sch_1):m_k_dqs_dp(4)" )
			)
			( signal "M_K_DQS_DP<5>"
				( objectStatus "@baseboard_fab2_lib.baseboard_fab2(sch_1):m_k_dqs_dp(5)" )
			)
			( signal "M_K_DQS_DP<6>"
				( objectStatus "@baseboard_fab2_lib.baseboard_fab2(sch_1):m_k_dqs_dp(6)" )
			)
			( signal "M_K_DQS_DP<7>"
				( objectStatus "@baseboard_fab2_lib.baseboard_fab2(sch_1):m_k_dqs_dp(7)" )
			)
			( signal "M_K_DQS_DP<8>"
				( objectStatus "@baseboard_fab2_lib.baseboard_fab2(sch_1):m_k_dqs_dp(8)" )
			)
			( signal "M_K_DQS_DP<9>"
				( objectStatus "@baseboard_fab2_lib.baseboard_fab2(sch_1):m_k_dqs_dp(9)" )
			)
			( signal "M_K_DQS_DP<10>"
				( objectStatus "@baseboard_fab2_lib.baseboard_fab2(sch_1):m_k_dqs_dp(10)" )
			)
			( signal "M_K_DQS_DP<11>"
				( objectStatus "@baseboard_fab2_lib.baseboard_fab2(sch_1):m_k_dqs_dp(11)" )
			)
			( signal "M_K_DQS_DP<12>"
				( objectStatus "@baseboard_fab2_lib.baseboard_fab2(sch_1):m_k_dqs_dp(12)" )
			)
			( signal "M_K_DQS_DP<13>"
				( objectStatus "@baseboard_fab2_lib.baseboard_fab2(sch_1):m_k_dqs_dp(13)" )
			)
			( signal "M_K_DQS_DP<14>"
				( objectStatus "@baseboard_fab2_lib.baseboard_fab2(sch_1):m_k_dqs_dp(14)" )
			)
			( signal "M_K_DQS_DP<15>"
				( objectStatus "@baseboard_fab2_lib.baseboard_fab2(sch_1):m_k_dqs_dp(15)" )
			)
			( signal "M_K_DQS_DP<16>"
				( objectStatus "@baseboard_fab2_lib.baseboard_fab2(sch_1):m_k_dqs_dp(16)" )
			)
			( signal "M_K_DQS_DP<17>"
				( objectStatus "@baseboard_fab2_lib.baseboard_fab2(sch_1):m_k_dqs_dp(17)" )
			)
			( signal "M_K_ECC<0>"
				( objectStatus "@baseboard_fab2_lib.baseboard_fab2(sch_1):m_k_ecc(0)" )
			)
			( signal "M_K_ECC<1>"
				( objectStatus "@baseboard_fab2_lib.baseboard_fab2(sch_1):m_k_ecc(1)" )
			)
			( signal "M_K_ECC<2>"
				( objectStatus "@baseboard_fab2_lib.baseboard_fab2(sch_1):m_k_ecc(2)" )
			)
			( signal "M_K_ECC<3>"
				( objectStatus "@baseboard_fab2_lib.baseboard_fab2(sch_1):m_k_ecc(3)" )
			)
			( signal "M_K_ECC<4>"
				( objectStatus "@baseboard_fab2_lib.baseboard_fab2(sch_1):m_k_ecc(4)" )
			)
			( signal "M_K_ECC<5>"
				( objectStatus "@baseboard_fab2_lib.baseboard_fab2(sch_1):m_k_ecc(5)" )
			)
			( signal "M_K_ECC<6>"
				( objectStatus "@baseboard_fab2_lib.baseboard_fab2(sch_1):m_k_ecc(6)" )
			)
			( signal "M_K_ECC<7>"
				( objectStatus "@baseboard_fab2_lib.baseboard_fab2(sch_1):m_k_ecc(7)" )
			)
			( signal "M_K_MA<0>"
				( objectStatus "@baseboard_fab2_lib.baseboard_fab2(sch_1):m_k_ma(0)" )
			)
			( signal "M_K_MA<1>"
				( objectStatus "@baseboard_fab2_lib.baseboard_fab2(sch_1):m_k_ma(1)" )
			)
			( signal "M_K_MA<2>"
				( objectStatus "@baseboard_fab2_lib.baseboard_fab2(sch_1):m_k_ma(2)" )
			)
			( signal "M_K_MA<3>"
				( objectStatus "@baseboard_fab2_lib.baseboard_fab2(sch_1):m_k_ma(3)" )
			)
			( signal "M_K_MA<4>"
				( objectStatus "@baseboard_fab2_lib.baseboard_fab2(sch_1):m_k_ma(4)" )
			)
			( signal "M_K_MA<5>"
				( objectStatus "@baseboard_fab2_lib.baseboard_fab2(sch_1):m_k_ma(5)" )
			)
			( signal "M_K_MA<6>"
				( objectStatus "@baseboard_fab2_lib.baseboard_fab2(sch_1):m_k_ma(6)" )
			)
			( signal "M_K_MA<7>"
				( objectStatus "@baseboard_fab2_lib.baseboard_fab2(sch_1):m_k_ma(7)" )
			)
			( signal "M_K_MA<8>"
				( objectStatus "@baseboard_fab2_lib.baseboard_fab2(sch_1):m_k_ma(8)" )
			)
			( signal "M_K_MA<9>"
				( objectStatus "@baseboard_fab2_lib.baseboard_fab2(sch_1):m_k_ma(9)" )
			)
			( signal "M_K_MA<10>"
				( objectStatus "@baseboard_fab2_lib.baseboard_fab2(sch_1):m_k_ma(10)" )
			)
			( signal "M_K_MA<11>"
				( objectStatus "@baseboard_fab2_lib.baseboard_fab2(sch_1):m_k_ma(11)" )
			)
			( signal "M_K_MA<12>"
				( objectStatus "@baseboard_fab2_lib.baseboard_fab2(sch_1):m_k_ma(12)" )
			)
			( signal "M_K_MA<13>"
				( objectStatus "@baseboard_fab2_lib.baseboard_fab2(sch_1):m_k_ma(13)" )
			)
			( signal "M_K_MA<14>"
				( objectStatus "@baseboard_fab2_lib.baseboard_fab2(sch_1):m_k_ma(14)" )
			)
			( signal "M_K_MA<15>"
				( objectStatus "@baseboard_fab2_lib.baseboard_fab2(sch_1):m_k_ma(15)" )
			)
			( signal "M_K_MA<16>"
				( objectStatus "@baseboard_fab2_lib.baseboard_fab2(sch_1):m_k_ma(16)" )
			)
			( signal "M_K_MA<17>"
				( objectStatus "@baseboard_fab2_lib.baseboard_fab2(sch_1):m_k_ma(17)" )
			)
			( signal "M_K_ODT<0>"
				( objectStatus "@baseboard_fab2_lib.baseboard_fab2(sch_1):m_k_odt(0)" )
			)
			( signal "M_K_ODT<1>"
				( objectStatus "@baseboard_fab2_lib.baseboard_fab2(sch_1):m_k_odt(1)" )
			)
			( signal "M_K_ODT<2>"
				( objectStatus "@baseboard_fab2_lib.baseboard_fab2(sch_1):m_k_odt(2)" )
			)
			( signal "M_K_ODT<3>"
				( objectStatus "@baseboard_fab2_lib.baseboard_fab2(sch_1):m_k_odt(3)" )
			)
			( signal "M_K_PAR"
				( objectStatus "@baseboard_fab2_lib.baseboard_fab2(sch_1):m_k_par" )
			)
			( signal "M_L_ACT_N"
				( objectStatus "@baseboard_fab2_lib.baseboard_fab2(sch_1):m_l_act_n" )
			)
			( signal "M_L_ALERT_N"
				( objectStatus "@baseboard_fab2_lib.baseboard_fab2(sch_1):m_l_alert_n" )
			)
			( signal "M_L_BA<0>"
				( objectStatus "@baseboard_fab2_lib.baseboard_fab2(sch_1):m_l_ba(0)" )
			)
			( signal "M_L_BA<1>"
				( objectStatus "@baseboard_fab2_lib.baseboard_fab2(sch_1):m_l_ba(1)" )
			)
			( signal "M_L_BG<0>"
				( objectStatus "@baseboard_fab2_lib.baseboard_fab2(sch_1):m_l_bg(0)" )
			)
			( signal "M_L_BG<1>"
				( objectStatus "@baseboard_fab2_lib.baseboard_fab2(sch_1):m_l_bg(1)" )
			)
			( signal "M_L_C<2>"
				( objectStatus "@baseboard_fab2_lib.baseboard_fab2(sch_1):m_l_c(2)" )
			)
			( signal "M_L_CKE<0>"
				( objectStatus "@baseboard_fab2_lib.baseboard_fab2(sch_1):m_l_cke(0)" )
			)
			( signal "M_L_CKE<1>"
				( objectStatus "@baseboard_fab2_lib.baseboard_fab2(sch_1):m_l_cke(1)" )
			)
			( signal "M_L_CKE<2>"
				( objectStatus "@baseboard_fab2_lib.baseboard_fab2(sch_1):m_l_cke(2)" )
			)
			( signal "M_L_CKE<3>"
				( objectStatus "@baseboard_fab2_lib.baseboard_fab2(sch_1):m_l_cke(3)" )
			)
			( signal "M_L_CLK_DN<0>"
				( objectStatus "@baseboard_fab2_lib.baseboard_fab2(sch_1):m_l_clk_dn(0)" )
			)
			( signal "M_L_CLK_DN<1>"
				( objectStatus "@baseboard_fab2_lib.baseboard_fab2(sch_1):m_l_clk_dn(1)" )
			)
			( signal "M_L_CLK_DN<2>"
				( objectStatus "@baseboard_fab2_lib.baseboard_fab2(sch_1):m_l_clk_dn(2)" )
			)
			( signal "M_L_CLK_DN<3>"
				( objectStatus "@baseboard_fab2_lib.baseboard_fab2(sch_1):m_l_clk_dn(3)" )
			)
			( signal "M_L_CLK_DP<0>"
				( objectStatus "@baseboard_fab2_lib.baseboard_fab2(sch_1):m_l_clk_dp(0)" )
			)
			( signal "M_L_CLK_DP<1>"
				( objectStatus "@baseboard_fab2_lib.baseboard_fab2(sch_1):m_l_clk_dp(1)" )
			)
			( signal "M_L_CLK_DP<2>"
				( objectStatus "@baseboard_fab2_lib.baseboard_fab2(sch_1):m_l_clk_dp(2)" )
			)
			( signal "M_L_CLK_DP<3>"
				( objectStatus "@baseboard_fab2_lib.baseboard_fab2(sch_1):m_l_clk_dp(3)" )
			)
			( signal "M_L_CS_N<0>"
				( objectStatus "@baseboard_fab2_lib.baseboard_fab2(sch_1):m_l_cs_n(0)" )
			)
			( signal "M_L_CS_N<1>"
				( objectStatus "@baseboard_fab2_lib.baseboard_fab2(sch_1):m_l_cs_n(1)" )
			)
			( signal "M_L_CS_N<2>"
				( objectStatus "@baseboard_fab2_lib.baseboard_fab2(sch_1):m_l_cs_n(2)" )
			)
			( signal "M_L_CS_N<3>"
				( objectStatus "@baseboard_fab2_lib.baseboard_fab2(sch_1):m_l_cs_n(3)" )
			)
			( signal "M_L_CS_N<4>"
				( objectStatus "@baseboard_fab2_lib.baseboard_fab2(sch_1):m_l_cs_n(4)" )
			)
			( signal "M_L_CS_N<5>"
				( objectStatus "@baseboard_fab2_lib.baseboard_fab2(sch_1):m_l_cs_n(5)" )
			)
			( signal "M_L_CS_N<6>"
				( objectStatus "@baseboard_fab2_lib.baseboard_fab2(sch_1):m_l_cs_n(6)" )
			)
			( signal "M_L_CS_N<7>"
				( objectStatus "@baseboard_fab2_lib.baseboard_fab2(sch_1):m_l_cs_n(7)" )
			)
			( signal "M_L_DQ<0>"
				( objectStatus "@baseboard_fab2_lib.baseboard_fab2(sch_1):m_l_dq(0)" )
			)
			( signal "M_L_DQ<1>"
				( objectStatus "@baseboard_fab2_lib.baseboard_fab2(sch_1):m_l_dq(1)" )
			)
			( signal "M_L_DQ<2>"
				( objectStatus "@baseboard_fab2_lib.baseboard_fab2(sch_1):m_l_dq(2)" )
			)
			( signal "M_L_DQ<3>"
				( objectStatus "@baseboard_fab2_lib.baseboard_fab2(sch_1):m_l_dq(3)" )
			)
			( signal "M_L_DQ<4>"
				( objectStatus "@baseboard_fab2_lib.baseboard_fab2(sch_1):m_l_dq(4)" )
			)
			( signal "M_L_DQ<5>"
				( objectStatus "@baseboard_fab2_lib.baseboard_fab2(sch_1):m_l_dq(5)" )
			)
			( signal "M_L_DQ<6>"
				( objectStatus "@baseboard_fab2_lib.baseboard_fab2(sch_1):m_l_dq(6)" )
			)
			( signal "M_L_DQ<7>"
				( objectStatus "@baseboard_fab2_lib.baseboard_fab2(sch_1):m_l_dq(7)" )
			)
			( signal "M_L_DQ<8>"
				( objectStatus "@baseboard_fab2_lib.baseboard_fab2(sch_1):m_l_dq(8)" )
			)
			( signal "M_L_DQ<9>"
				( objectStatus "@baseboard_fab2_lib.baseboard_fab2(sch_1):m_l_dq(9)" )
			)
			( signal "M_L_DQ<10>"
				( objectStatus "@baseboard_fab2_lib.baseboard_fab2(sch_1):m_l_dq(10)" )
			)
			( signal "M_L_DQ<11>"
				( objectStatus "@baseboard_fab2_lib.baseboard_fab2(sch_1):m_l_dq(11)" )
			)
			( signal "M_L_DQ<12>"
				( objectStatus "@baseboard_fab2_lib.baseboard_fab2(sch_1):m_l_dq(12)" )
			)
			( signal "M_L_DQ<13>"
				( objectStatus "@baseboard_fab2_lib.baseboard_fab2(sch_1):m_l_dq(13)" )
			)
			( signal "M_L_DQ<14>"
				( objectStatus "@baseboard_fab2_lib.baseboard_fab2(sch_1):m_l_dq(14)" )
			)
			( signal "M_L_DQ<15>"
				( objectStatus "@baseboard_fab2_lib.baseboard_fab2(sch_1):m_l_dq(15)" )
			)
			( signal "M_L_DQ<16>"
				( objectStatus "@baseboard_fab2_lib.baseboard_fab2(sch_1):m_l_dq(16)" )
			)
			( signal "M_L_DQ<17>"
				( objectStatus "@baseboard_fab2_lib.baseboard_fab2(sch_1):m_l_dq(17)" )
			)
			( signal "M_L_DQ<18>"
				( objectStatus "@baseboard_fab2_lib.baseboard_fab2(sch_1):m_l_dq(18)" )
			)
			( signal "M_L_DQ<19>"
				( objectStatus "@baseboard_fab2_lib.baseboard_fab2(sch_1):m_l_dq(19)" )
			)
			( signal "M_L_DQ<20>"
				( objectStatus "@baseboard_fab2_lib.baseboard_fab2(sch_1):m_l_dq(20)" )
			)
			( signal "M_L_DQ<21>"
				( objectStatus "@baseboard_fab2_lib.baseboard_fab2(sch_1):m_l_dq(21)" )
			)
			( signal "M_L_DQ<22>"
				( objectStatus "@baseboard_fab2_lib.baseboard_fab2(sch_1):m_l_dq(22)" )
			)
			( signal "M_L_DQ<23>"
				( objectStatus "@baseboard_fab2_lib.baseboard_fab2(sch_1):m_l_dq(23)" )
			)
			( signal "M_L_DQ<24>"
				( objectStatus "@baseboard_fab2_lib.baseboard_fab2(sch_1):m_l_dq(24)" )
			)
			( signal "M_L_DQ<25>"
				( objectStatus "@baseboard_fab2_lib.baseboard_fab2(sch_1):m_l_dq(25)" )
			)
			( signal "M_L_DQ<26>"
				( objectStatus "@baseboard_fab2_lib.baseboard_fab2(sch_1):m_l_dq(26)" )
			)
			( signal "M_L_DQ<27>"
				( objectStatus "@baseboard_fab2_lib.baseboard_fab2(sch_1):m_l_dq(27)" )
			)
			( signal "M_L_DQ<28>"
				( objectStatus "@baseboard_fab2_lib.baseboard_fab2(sch_1):m_l_dq(28)" )
			)
			( signal "M_L_DQ<29>"
				( objectStatus "@baseboard_fab2_lib.baseboard_fab2(sch_1):m_l_dq(29)" )
			)
			( signal "M_L_DQ<30>"
				( objectStatus "@baseboard_fab2_lib.baseboard_fab2(sch_1):m_l_dq(30)" )
			)
			( signal "M_L_DQ<31>"
				( objectStatus "@baseboard_fab2_lib.baseboard_fab2(sch_1):m_l_dq(31)" )
			)
			( signal "M_L_DQ<32>"
				( objectStatus "@baseboard_fab2_lib.baseboard_fab2(sch_1):m_l_dq(32)" )
			)
			( signal "M_L_DQ<33>"
				( objectStatus "@baseboard_fab2_lib.baseboard_fab2(sch_1):m_l_dq(33)" )
			)
			( signal "M_L_DQ<34>"
				( objectStatus "@baseboard_fab2_lib.baseboard_fab2(sch_1):m_l_dq(34)" )
			)
			( signal "M_L_DQ<35>"
				( objectStatus "@baseboard_fab2_lib.baseboard_fab2(sch_1):m_l_dq(35)" )
			)
			( signal "M_L_DQ<36>"
				( objectStatus "@baseboard_fab2_lib.baseboard_fab2(sch_1):m_l_dq(36)" )
			)
			( signal "M_L_DQ<37>"
				( objectStatus "@baseboard_fab2_lib.baseboard_fab2(sch_1):m_l_dq(37)" )
			)
			( signal "M_L_DQ<38>"
				( objectStatus "@baseboard_fab2_lib.baseboard_fab2(sch_1):m_l_dq(38)" )
			)
			( signal "M_L_DQ<39>"
				( objectStatus "@baseboard_fab2_lib.baseboard_fab2(sch_1):m_l_dq(39)" )
			)
			( signal "M_L_DQ<40>"
				( objectStatus "@baseboard_fab2_lib.baseboard_fab2(sch_1):m_l_dq(40)" )
			)
			( signal "M_L_DQ<41>"
				( objectStatus "@baseboard_fab2_lib.baseboard_fab2(sch_1):m_l_dq(41)" )
			)
			( signal "M_L_DQ<42>"
				( objectStatus "@baseboard_fab2_lib.baseboard_fab2(sch_1):m_l_dq(42)" )
			)
			( signal "M_L_DQ<43>"
				( objectStatus "@baseboard_fab2_lib.baseboard_fab2(sch_1):m_l_dq(43)" )
			)
			( signal "M_L_DQ<44>"
				( objectStatus "@baseboard_fab2_lib.baseboard_fab2(sch_1):m_l_dq(44)" )
			)
			( signal "M_L_DQ<45>"
				( objectStatus "@baseboard_fab2_lib.baseboard_fab2(sch_1):m_l_dq(45)" )
			)
			( signal "M_L_DQ<46>"
				( objectStatus "@baseboard_fab2_lib.baseboard_fab2(sch_1):m_l_dq(46)" )
			)
			( signal "M_L_DQ<47>"
				( objectStatus "@baseboard_fab2_lib.baseboard_fab2(sch_1):m_l_dq(47)" )
			)
			( signal "M_L_DQ<48>"
				( objectStatus "@baseboard_fab2_lib.baseboard_fab2(sch_1):m_l_dq(48)" )
			)
			( signal "M_L_DQ<49>"
				( objectStatus "@baseboard_fab2_lib.baseboard_fab2(sch_1):m_l_dq(49)" )
			)
			( signal "M_L_DQ<50>"
				( objectStatus "@baseboard_fab2_lib.baseboard_fab2(sch_1):m_l_dq(50)" )
			)
			( signal "M_L_DQ<51>"
				( objectStatus "@baseboard_fab2_lib.baseboard_fab2(sch_1):m_l_dq(51)" )
			)
			( signal "M_L_DQ<52>"
				( objectStatus "@baseboard_fab2_lib.baseboard_fab2(sch_1):m_l_dq(52)" )
			)
			( signal "M_L_DQ<53>"
				( objectStatus "@baseboard_fab2_lib.baseboard_fab2(sch_1):m_l_dq(53)" )
			)
			( signal "M_L_DQ<54>"
				( objectStatus "@baseboard_fab2_lib.baseboard_fab2(sch_1):m_l_dq(54)" )
			)
			( signal "M_L_DQ<55>"
				( objectStatus "@baseboard_fab2_lib.baseboard_fab2(sch_1):m_l_dq(55)" )
			)
			( signal "M_L_DQ<56>"
				( objectStatus "@baseboard_fab2_lib.baseboard_fab2(sch_1):m_l_dq(56)" )
			)
			( signal "M_L_DQ<57>"
				( objectStatus "@baseboard_fab2_lib.baseboard_fab2(sch_1):m_l_dq(57)" )
			)
			( signal "M_L_DQ<58>"
				( objectStatus "@baseboard_fab2_lib.baseboard_fab2(sch_1):m_l_dq(58)" )
			)
			( signal "M_L_DQ<59>"
				( objectStatus "@baseboard_fab2_lib.baseboard_fab2(sch_1):m_l_dq(59)" )
			)
			( signal "M_L_DQ<60>"
				( objectStatus "@baseboard_fab2_lib.baseboard_fab2(sch_1):m_l_dq(60)" )
			)
			( signal "M_L_DQ<61>"
				( objectStatus "@baseboard_fab2_lib.baseboard_fab2(sch_1):m_l_dq(61)" )
			)
			( signal "M_L_DQ<62>"
				( objectStatus "@baseboard_fab2_lib.baseboard_fab2(sch_1):m_l_dq(62)" )
			)
			( signal "M_L_DQ<63>"
				( objectStatus "@baseboard_fab2_lib.baseboard_fab2(sch_1):m_l_dq(63)" )
			)
			( signal "M_L_DQS_DN<0>"
				( objectStatus "@baseboard_fab2_lib.baseboard_fab2(sch_1):m_l_dqs_dn(0)" )
			)
			( signal "M_L_DQS_DN<1>"
				( objectStatus "@baseboard_fab2_lib.baseboard_fab2(sch_1):m_l_dqs_dn(1)" )
			)
			( signal "M_L_DQS_DN<2>"
				( objectStatus "@baseboard_fab2_lib.baseboard_fab2(sch_1):m_l_dqs_dn(2)" )
			)
			( signal "M_L_DQS_DN<3>"
				( objectStatus "@baseboard_fab2_lib.baseboard_fab2(sch_1):m_l_dqs_dn(3)" )
			)
			( signal "M_L_DQS_DN<4>"
				( objectStatus "@baseboard_fab2_lib.baseboard_fab2(sch_1):m_l_dqs_dn(4)" )
			)
			( signal "M_L_DQS_DN<5>"
				( objectStatus "@baseboard_fab2_lib.baseboard_fab2(sch_1):m_l_dqs_dn(5)" )
			)
			( signal "M_L_DQS_DN<6>"
				( objectStatus "@baseboard_fab2_lib.baseboard_fab2(sch_1):m_l_dqs_dn(6)" )
			)
			( signal "M_L_DQS_DN<7>"
				( objectStatus "@baseboard_fab2_lib.baseboard_fab2(sch_1):m_l_dqs_dn(7)" )
			)
			( signal "M_L_DQS_DN<8>"
				( objectStatus "@baseboard_fab2_lib.baseboard_fab2(sch_1):m_l_dqs_dn(8)" )
			)
			( signal "M_L_DQS_DN<9>"
				( objectStatus "@baseboard_fab2_lib.baseboard_fab2(sch_1):m_l_dqs_dn(9)" )
			)
			( signal "M_L_DQS_DN<10>"
				( objectStatus "@baseboard_fab2_lib.baseboard_fab2(sch_1):m_l_dqs_dn(10)" )
			)
			( signal "M_L_DQS_DN<11>"
				( objectStatus "@baseboard_fab2_lib.baseboard_fab2(sch_1):m_l_dqs_dn(11)" )
			)
			( signal "M_L_DQS_DN<12>"
				( objectStatus "@baseboard_fab2_lib.baseboard_fab2(sch_1):m_l_dqs_dn(12)" )
			)
			( signal "M_L_DQS_DN<13>"
				( objectStatus "@baseboard_fab2_lib.baseboard_fab2(sch_1):m_l_dqs_dn(13)" )
			)
			( signal "M_L_DQS_DN<14>"
				( objectStatus "@baseboard_fab2_lib.baseboard_fab2(sch_1):m_l_dqs_dn(14)" )
			)
			( signal "M_L_DQS_DN<15>"
				( objectStatus "@baseboard_fab2_lib.baseboard_fab2(sch_1):m_l_dqs_dn(15)" )
			)
			( signal "M_L_DQS_DN<16>"
				( objectStatus "@baseboard_fab2_lib.baseboard_fab2(sch_1):m_l_dqs_dn(16)" )
			)
			( signal "M_L_DQS_DN<17>"
				( objectStatus "@baseboard_fab2_lib.baseboard_fab2(sch_1):m_l_dqs_dn(17)" )
			)
			( signal "M_L_DQS_DP<0>"
				( objectStatus "@baseboard_fab2_lib.baseboard_fab2(sch_1):m_l_dqs_dp(0)" )
			)
			( signal "M_L_DQS_DP<1>"
				( objectStatus "@baseboard_fab2_lib.baseboard_fab2(sch_1):m_l_dqs_dp(1)" )
			)
			( signal "M_L_DQS_DP<2>"
				( objectStatus "@baseboard_fab2_lib.baseboard_fab2(sch_1):m_l_dqs_dp(2)" )
			)
			( signal "M_L_DQS_DP<3>"
				( objectStatus "@baseboard_fab2_lib.baseboard_fab2(sch_1):m_l_dqs_dp(3)" )
			)
			( signal "M_L_DQS_DP<4>"
				( objectStatus "@baseboard_fab2_lib.baseboard_fab2(sch_1):m_l_dqs_dp(4)" )
			)
			( signal "M_L_DQS_DP<5>"
				( objectStatus "@baseboard_fab2_lib.baseboard_fab2(sch_1):m_l_dqs_dp(5)" )
			)
			( signal "M_L_DQS_DP<6>"
				( objectStatus "@baseboard_fab2_lib.baseboard_fab2(sch_1):m_l_dqs_dp(6)" )
			)
			( signal "M_L_DQS_DP<7>"
				( objectStatus "@baseboard_fab2_lib.baseboard_fab2(sch_1):m_l_dqs_dp(7)" )
			)
			( signal "M_L_DQS_DP<8>"
				( objectStatus "@baseboard_fab2_lib.baseboard_fab2(sch_1):m_l_dqs_dp(8)" )
			)
			( signal "M_L_DQS_DP<9>"
				( objectStatus "@baseboard_fab2_lib.baseboard_fab2(sch_1):m_l_dqs_dp(9)" )
			)
			( signal "M_L_DQS_DP<10>"
				( objectStatus "@baseboard_fab2_lib.baseboard_fab2(sch_1):m_l_dqs_dp(10)" )
			)
			( signal "M_L_DQS_DP<11>"
				( objectStatus "@baseboard_fab2_lib.baseboard_fab2(sch_1):m_l_dqs_dp(11)" )
			)
			( signal "M_L_DQS_DP<12>"
				( objectStatus "@baseboard_fab2_lib.baseboard_fab2(sch_1):m_l_dqs_dp(12)" )
			)
			( signal "M_L_DQS_DP<13>"
				( objectStatus "@baseboard_fab2_lib.baseboard_fab2(sch_1):m_l_dqs_dp(13)" )
			)
			( signal "M_L_DQS_DP<14>"
				( objectStatus "@baseboard_fab2_lib.baseboard_fab2(sch_1):m_l_dqs_dp(14)" )
			)
			( signal "M_L_DQS_DP<15>"
				( objectStatus "@baseboard_fab2_lib.baseboard_fab2(sch_1):m_l_dqs_dp(15)" )
			)
			( signal "M_L_DQS_DP<16>"
				( objectStatus "@baseboard_fab2_lib.baseboard_fab2(sch_1):m_l_dqs_dp(16)" )
			)
			( signal "M_L_DQS_DP<17>"
				( objectStatus "@baseboard_fab2_lib.baseboard_fab2(sch_1):m_l_dqs_dp(17)" )
			)
			( signal "M_L_ECC<0>"
				( objectStatus "@baseboard_fab2_lib.baseboard_fab2(sch_1):m_l_ecc(0)" )
			)
			( signal "M_L_ECC<1>"
				( objectStatus "@baseboard_fab2_lib.baseboard_fab2(sch_1):m_l_ecc(1)" )
			)
			( signal "M_L_ECC<2>"
				( objectStatus "@baseboard_fab2_lib.baseboard_fab2(sch_1):m_l_ecc(2)" )
			)
			( signal "M_L_ECC<3>"
				( objectStatus "@baseboard_fab2_lib.baseboard_fab2(sch_1):m_l_ecc(3)" )
			)
			( signal "M_L_ECC<4>"
				( objectStatus "@baseboard_fab2_lib.baseboard_fab2(sch_1):m_l_ecc(4)" )
			)
			( signal "M_L_ECC<5>"
				( objectStatus "@baseboard_fab2_lib.baseboard_fab2(sch_1):m_l_ecc(5)" )
			)
			( signal "M_L_ECC<6>"
				( objectStatus "@baseboard_fab2_lib.baseboard_fab2(sch_1):m_l_ecc(6)" )
			)
			( signal "M_L_ECC<7>"
				( objectStatus "@baseboard_fab2_lib.baseboard_fab2(sch_1):m_l_ecc(7)" )
			)
			( signal "M_L_MA<0>"
				( objectStatus "@baseboard_fab2_lib.baseboard_fab2(sch_1):m_l_ma(0)" )
			)
			( signal "M_L_MA<1>"
				( objectStatus "@baseboard_fab2_lib.baseboard_fab2(sch_1):m_l_ma(1)" )
			)
			( signal "M_L_MA<2>"
				( objectStatus "@baseboard_fab2_lib.baseboard_fab2(sch_1):m_l_ma(2)" )
			)
			( signal "M_L_MA<3>"
				( objectStatus "@baseboard_fab2_lib.baseboard_fab2(sch_1):m_l_ma(3)" )
			)
			( signal "M_L_MA<4>"
				( objectStatus "@baseboard_fab2_lib.baseboard_fab2(sch_1):m_l_ma(4)" )
			)
			( signal "M_L_MA<5>"
				( objectStatus "@baseboard_fab2_lib.baseboard_fab2(sch_1):m_l_ma(5)" )
			)
			( signal "M_L_MA<6>"
				( objectStatus "@baseboard_fab2_lib.baseboard_fab2(sch_1):m_l_ma(6)" )
			)
			( signal "M_L_MA<7>"
				( objectStatus "@baseboard_fab2_lib.baseboard_fab2(sch_1):m_l_ma(7)" )
			)
			( signal "M_L_MA<8>"
				( objectStatus "@baseboard_fab2_lib.baseboard_fab2(sch_1):m_l_ma(8)" )
			)
			( signal "M_L_MA<9>"
				( objectStatus "@baseboard_fab2_lib.baseboard_fab2(sch_1):m_l_ma(9)" )
			)
			( signal "M_L_MA<10>"
				( objectStatus "@baseboard_fab2_lib.baseboard_fab2(sch_1):m_l_ma(10)" )
			)
			( signal "M_L_MA<11>"
				( objectStatus "@baseboard_fab2_lib.baseboard_fab2(sch_1):m_l_ma(11)" )
			)
			( signal "M_L_MA<12>"
				( objectStatus "@baseboard_fab2_lib.baseboard_fab2(sch_1):m_l_ma(12)" )
			)
			( signal "M_L_MA<13>"
				( objectStatus "@baseboard_fab2_lib.baseboard_fab2(sch_1):m_l_ma(13)" )
			)
			( signal "M_L_MA<14>"
				( objectStatus "@baseboard_fab2_lib.baseboard_fab2(sch_1):m_l_ma(14)" )
			)
			( signal "M_L_MA<15>"
				( objectStatus "@baseboard_fab2_lib.baseboard_fab2(sch_1):m_l_ma(15)" )
			)
			( signal "M_L_MA<16>"
				( objectStatus "@baseboard_fab2_lib.baseboard_fab2(sch_1):m_l_ma(16)" )
			)
			( signal "M_L_MA<17>"
				( objectStatus "@baseboard_fab2_lib.baseboard_fab2(sch_1):m_l_ma(17)" )
			)
			( signal "M_L_ODT<0>"
				( objectStatus "@baseboard_fab2_lib.baseboard_fab2(sch_1):m_l_odt(0)" )
			)
			( signal "M_L_ODT<1>"
				( objectStatus "@baseboard_fab2_lib.baseboard_fab2(sch_1):m_l_odt(1)" )
			)
			( signal "M_L_ODT<2>"
				( objectStatus "@baseboard_fab2_lib.baseboard_fab2(sch_1):m_l_odt(2)" )
			)
			( signal "M_L_ODT<3>"
				( objectStatus "@baseboard_fab2_lib.baseboard_fab2(sch_1):m_l_odt(3)" )
			)
			( signal "M_L_PAR"
				( objectStatus "@baseboard_fab2_lib.baseboard_fab2(sch_1):m_l_par" )
			)
			( signal "M_M_ACT_N"
				( objectStatus "@baseboard_fab2_lib.baseboard_fab2(sch_1):m_m_act_n" )
			)
			( signal "M_M_ALERT_N"
				( objectStatus "@baseboard_fab2_lib.baseboard_fab2(sch_1):m_m_alert_n" )
			)
			( signal "M_M_BA<0>"
				( objectStatus "@baseboard_fab2_lib.baseboard_fab2(sch_1):m_m_ba(0)" )
			)
			( signal "M_M_BA<1>"
				( objectStatus "@baseboard_fab2_lib.baseboard_fab2(sch_1):m_m_ba(1)" )
			)
			( signal "M_M_BG<0>"
				( objectStatus "@baseboard_fab2_lib.baseboard_fab2(sch_1):m_m_bg(0)" )
			)
			( signal "M_M_BG<1>"
				( objectStatus "@baseboard_fab2_lib.baseboard_fab2(sch_1):m_m_bg(1)" )
			)
			( signal "M_M_C<2>"
				( objectStatus "@baseboard_fab2_lib.baseboard_fab2(sch_1):m_m_c(2)" )
			)
			( signal "M_M_CKE<0>"
				( objectStatus "@baseboard_fab2_lib.baseboard_fab2(sch_1):m_m_cke(0)" )
			)
			( signal "M_M_CKE<1>"
				( objectStatus "@baseboard_fab2_lib.baseboard_fab2(sch_1):m_m_cke(1)" )
			)
			( signal "M_M_CKE<2>"
				( objectStatus "@baseboard_fab2_lib.baseboard_fab2(sch_1):m_m_cke(2)" )
			)
			( signal "M_M_CKE<3>"
				( objectStatus "@baseboard_fab2_lib.baseboard_fab2(sch_1):m_m_cke(3)" )
			)
			( signal "M_M_CLK_DN<0>"
				( objectStatus "@baseboard_fab2_lib.baseboard_fab2(sch_1):m_m_clk_dn(0)" )
			)
			( signal "M_M_CLK_DN<1>"
				( objectStatus "@baseboard_fab2_lib.baseboard_fab2(sch_1):m_m_clk_dn(1)" )
			)
			( signal "M_M_CLK_DN<2>"
				( objectStatus "@baseboard_fab2_lib.baseboard_fab2(sch_1):m_m_clk_dn(2)" )
			)
			( signal "M_M_CLK_DN<3>"
				( objectStatus "@baseboard_fab2_lib.baseboard_fab2(sch_1):m_m_clk_dn(3)" )
			)
			( signal "M_M_CLK_DP<0>"
				( objectStatus "@baseboard_fab2_lib.baseboard_fab2(sch_1):m_m_clk_dp(0)" )
			)
			( signal "M_M_CLK_DP<1>"
				( objectStatus "@baseboard_fab2_lib.baseboard_fab2(sch_1):m_m_clk_dp(1)" )
			)
			( signal "M_M_CLK_DP<2>"
				( objectStatus "@baseboard_fab2_lib.baseboard_fab2(sch_1):m_m_clk_dp(2)" )
			)
			( signal "M_M_CLK_DP<3>"
				( objectStatus "@baseboard_fab2_lib.baseboard_fab2(sch_1):m_m_clk_dp(3)" )
			)
			( signal "M_M_CS_N<0>"
				( objectStatus "@baseboard_fab2_lib.baseboard_fab2(sch_1):m_m_cs_n(0)" )
			)
			( signal "M_M_CS_N<1>"
				( objectStatus "@baseboard_fab2_lib.baseboard_fab2(sch_1):m_m_cs_n(1)" )
			)
			( signal "M_M_CS_N<2>"
				( objectStatus "@baseboard_fab2_lib.baseboard_fab2(sch_1):m_m_cs_n(2)" )
			)
			( signal "M_M_CS_N<3>"
				( objectStatus "@baseboard_fab2_lib.baseboard_fab2(sch_1):m_m_cs_n(3)" )
			)
			( signal "M_M_CS_N<4>"
				( objectStatus "@baseboard_fab2_lib.baseboard_fab2(sch_1):m_m_cs_n(4)" )
			)
			( signal "M_M_CS_N<5>"
				( objectStatus "@baseboard_fab2_lib.baseboard_fab2(sch_1):m_m_cs_n(5)" )
			)
			( signal "M_M_CS_N<6>"
				( objectStatus "@baseboard_fab2_lib.baseboard_fab2(sch_1):m_m_cs_n(6)" )
			)
			( signal "M_M_CS_N<7>"
				( objectStatus "@baseboard_fab2_lib.baseboard_fab2(sch_1):m_m_cs_n(7)" )
			)
			( signal "M_M_DQ<0>"
				( objectStatus "@baseboard_fab2_lib.baseboard_fab2(sch_1):m_m_dq(0)" )
			)
			( signal "M_M_DQ<1>"
				( objectStatus "@baseboard_fab2_lib.baseboard_fab2(sch_1):m_m_dq(1)" )
			)
			( signal "M_M_DQ<2>"
				( objectStatus "@baseboard_fab2_lib.baseboard_fab2(sch_1):m_m_dq(2)" )
			)
			( signal "M_M_DQ<3>"
				( objectStatus "@baseboard_fab2_lib.baseboard_fab2(sch_1):m_m_dq(3)" )
			)
			( signal "M_M_DQ<4>"
				( objectStatus "@baseboard_fab2_lib.baseboard_fab2(sch_1):m_m_dq(4)" )
			)
			( signal "M_M_DQ<5>"
				( objectStatus "@baseboard_fab2_lib.baseboard_fab2(sch_1):m_m_dq(5)" )
			)
			( signal "M_M_DQ<6>"
				( objectStatus "@baseboard_fab2_lib.baseboard_fab2(sch_1):m_m_dq(6)" )
			)
			( signal "M_M_DQ<7>"
				( objectStatus "@baseboard_fab2_lib.baseboard_fab2(sch_1):m_m_dq(7)" )
			)
			( signal "M_M_DQ<8>"
				( objectStatus "@baseboard_fab2_lib.baseboard_fab2(sch_1):m_m_dq(8)" )
			)
			( signal "M_M_DQ<9>"
				( objectStatus "@baseboard_fab2_lib.baseboard_fab2(sch_1):m_m_dq(9)" )
			)
			( signal "M_M_DQ<10>"
				( objectStatus "@baseboard_fab2_lib.baseboard_fab2(sch_1):m_m_dq(10)" )
			)
			( signal "M_M_DQ<11>"
				( objectStatus "@baseboard_fab2_lib.baseboard_fab2(sch_1):m_m_dq(11)" )
			)
			( signal "M_M_DQ<12>"
				( objectStatus "@baseboard_fab2_lib.baseboard_fab2(sch_1):m_m_dq(12)" )
			)
			( signal "M_M_DQ<13>"
				( objectStatus "@baseboard_fab2_lib.baseboard_fab2(sch_1):m_m_dq(13)" )
			)
			( signal "M_M_DQ<14>"
				( objectStatus "@baseboard_fab2_lib.baseboard_fab2(sch_1):m_m_dq(14)" )
			)
			( signal "M_M_DQ<15>"
				( objectStatus "@baseboard_fab2_lib.baseboard_fab2(sch_1):m_m_dq(15)" )
			)
			( signal "M_M_DQ<16>"
				( objectStatus "@baseboard_fab2_lib.baseboard_fab2(sch_1):m_m_dq(16)" )
			)
			( signal "M_M_DQ<17>"
				( objectStatus "@baseboard_fab2_lib.baseboard_fab2(sch_1):m_m_dq(17)" )
			)
			( signal "M_M_DQ<18>"
				( objectStatus "@baseboard_fab2_lib.baseboard_fab2(sch_1):m_m_dq(18)" )
			)
			( signal "M_M_DQ<19>"
				( objectStatus "@baseboard_fab2_lib.baseboard_fab2(sch_1):m_m_dq(19)" )
			)
			( signal "M_M_DQ<20>"
				( objectStatus "@baseboard_fab2_lib.baseboard_fab2(sch_1):m_m_dq(20)" )
			)
			( signal "M_M_DQ<21>"
				( objectStatus "@baseboard_fab2_lib.baseboard_fab2(sch_1):m_m_dq(21)" )
			)
			( signal "M_M_DQ<22>"
				( objectStatus "@baseboard_fab2_lib.baseboard_fab2(sch_1):m_m_dq(22)" )
			)
			( signal "M_M_DQ<23>"
				( objectStatus "@baseboard_fab2_lib.baseboard_fab2(sch_1):m_m_dq(23)" )
			)
			( signal "M_M_DQ<24>"
				( objectStatus "@baseboard_fab2_lib.baseboard_fab2(sch_1):m_m_dq(24)" )
			)
			( signal "M_M_DQ<25>"
				( objectStatus "@baseboard_fab2_lib.baseboard_fab2(sch_1):m_m_dq(25)" )
			)
			( signal "M_M_DQ<26>"
				( objectStatus "@baseboard_fab2_lib.baseboard_fab2(sch_1):m_m_dq(26)" )
			)
			( signal "M_M_DQ<27>"
				( objectStatus "@baseboard_fab2_lib.baseboard_fab2(sch_1):m_m_dq(27)" )
			)
			( signal "M_M_DQ<28>"
				( objectStatus "@baseboard_fab2_lib.baseboard_fab2(sch_1):m_m_dq(28)" )
			)
			( signal "M_M_DQ<29>"
				( objectStatus "@baseboard_fab2_lib.baseboard_fab2(sch_1):m_m_dq(29)" )
			)
			( signal "M_M_DQ<30>"
				( objectStatus "@baseboard_fab2_lib.baseboard_fab2(sch_1):m_m_dq(30)" )
			)
			( signal "M_M_DQ<31>"
				( objectStatus "@baseboard_fab2_lib.baseboard_fab2(sch_1):m_m_dq(31)" )
			)
			( signal "M_M_DQ<32>"
				( objectStatus "@baseboard_fab2_lib.baseboard_fab2(sch_1):m_m_dq(32)" )
			)
			( signal "M_M_DQ<33>"
				( objectStatus "@baseboard_fab2_lib.baseboard_fab2(sch_1):m_m_dq(33)" )
			)
			( signal "M_M_DQ<34>"
				( objectStatus "@baseboard_fab2_lib.baseboard_fab2(sch_1):m_m_dq(34)" )
			)
			( signal "M_M_DQ<35>"
				( objectStatus "@baseboard_fab2_lib.baseboard_fab2(sch_1):m_m_dq(35)" )
			)
			( signal "M_M_DQ<36>"
				( objectStatus "@baseboard_fab2_lib.baseboard_fab2(sch_1):m_m_dq(36)" )
			)
			( signal "M_M_DQ<37>"
				( objectStatus "@baseboard_fab2_lib.baseboard_fab2(sch_1):m_m_dq(37)" )
			)
			( signal "M_M_DQ<38>"
				( objectStatus "@baseboard_fab2_lib.baseboard_fab2(sch_1):m_m_dq(38)" )
			)
			( signal "M_M_DQ<39>"
				( objectStatus "@baseboard_fab2_lib.baseboard_fab2(sch_1):m_m_dq(39)" )
			)
			( signal "M_M_DQ<40>"
				( objectStatus "@baseboard_fab2_lib.baseboard_fab2(sch_1):m_m_dq(40)" )
			)
			( signal "M_M_DQ<41>"
				( objectStatus "@baseboard_fab2_lib.baseboard_fab2(sch_1):m_m_dq(41)" )
			)
			( signal "M_M_DQ<42>"
				( objectStatus "@baseboard_fab2_lib.baseboard_fab2(sch_1):m_m_dq(42)" )
			)
			( signal "M_M_DQ<43>"
				( objectStatus "@baseboard_fab2_lib.baseboard_fab2(sch_1):m_m_dq(43)" )
			)
			( signal "M_M_DQ<44>"
				( objectStatus "@baseboard_fab2_lib.baseboard_fab2(sch_1):m_m_dq(44)" )
			)
			( signal "M_M_DQ<45>"
				( objectStatus "@baseboard_fab2_lib.baseboard_fab2(sch_1):m_m_dq(45)" )
			)
			( signal "M_M_DQ<46>"
				( objectStatus "@baseboard_fab2_lib.baseboard_fab2(sch_1):m_m_dq(46)" )
			)
			( signal "M_M_DQ<47>"
				( objectStatus "@baseboard_fab2_lib.baseboard_fab2(sch_1):m_m_dq(47)" )
			)
			( signal "M_M_DQ<48>"
				( objectStatus "@baseboard_fab2_lib.baseboard_fab2(sch_1):m_m_dq(48)" )
			)
			( signal "M_M_DQ<49>"
				( objectStatus "@baseboard_fab2_lib.baseboard_fab2(sch_1):m_m_dq(49)" )
			)
			( signal "M_M_DQ<50>"
				( objectStatus "@baseboard_fab2_lib.baseboard_fab2(sch_1):m_m_dq(50)" )
			)
			( signal "M_M_DQ<51>"
				( objectStatus "@baseboard_fab2_lib.baseboard_fab2(sch_1):m_m_dq(51)" )
			)
			( signal "M_M_DQ<52>"
				( objectStatus "@baseboard_fab2_lib.baseboard_fab2(sch_1):m_m_dq(52)" )
			)
			( signal "M_M_DQ<53>"
				( objectStatus "@baseboard_fab2_lib.baseboard_fab2(sch_1):m_m_dq(53)" )
			)
			( signal "M_M_DQ<54>"
				( objectStatus "@baseboard_fab2_lib.baseboard_fab2(sch_1):m_m_dq(54)" )
			)
			( signal "M_M_DQ<55>"
				( objectStatus "@baseboard_fab2_lib.baseboard_fab2(sch_1):m_m_dq(55)" )
			)
			( signal "M_M_DQ<56>"
				( objectStatus "@baseboard_fab2_lib.baseboard_fab2(sch_1):m_m_dq(56)" )
			)
			( signal "M_M_DQ<57>"
				( objectStatus "@baseboard_fab2_lib.baseboard_fab2(sch_1):m_m_dq(57)" )
			)
			( signal "M_M_DQ<58>"
				( objectStatus "@baseboard_fab2_lib.baseboard_fab2(sch_1):m_m_dq(58)" )
			)
			( signal "M_M_DQ<59>"
				( objectStatus "@baseboard_fab2_lib.baseboard_fab2(sch_1):m_m_dq(59)" )
			)
			( signal "M_M_DQ<60>"
				( objectStatus "@baseboard_fab2_lib.baseboard_fab2(sch_1):m_m_dq(60)" )
			)
			( signal "M_M_DQ<61>"
				( objectStatus "@baseboard_fab2_lib.baseboard_fab2(sch_1):m_m_dq(61)" )
			)
			( signal "M_M_DQ<62>"
				( objectStatus "@baseboard_fab2_lib.baseboard_fab2(sch_1):m_m_dq(62)" )
			)
			( signal "M_M_DQ<63>"
				( objectStatus "@baseboard_fab2_lib.baseboard_fab2(sch_1):m_m_dq(63)" )
			)
			( signal "M_M_DQS_DN<0>"
				( objectStatus "@baseboard_fab2_lib.baseboard_fab2(sch_1):m_m_dqs_dn(0)" )
			)
			( signal "M_M_DQS_DN<1>"
				( objectStatus "@baseboard_fab2_lib.baseboard_fab2(sch_1):m_m_dqs_dn(1)" )
			)
			( signal "M_M_DQS_DN<2>"
				( objectStatus "@baseboard_fab2_lib.baseboard_fab2(sch_1):m_m_dqs_dn(2)" )
			)
			( signal "M_M_DQS_DN<3>"
				( objectStatus "@baseboard_fab2_lib.baseboard_fab2(sch_1):m_m_dqs_dn(3)" )
			)
			( signal "M_M_DQS_DN<4>"
				( objectStatus "@baseboard_fab2_lib.baseboard_fab2(sch_1):m_m_dqs_dn(4)" )
			)
			( signal "M_M_DQS_DN<5>"
				( objectStatus "@baseboard_fab2_lib.baseboard_fab2(sch_1):m_m_dqs_dn(5)" )
			)
			( signal "M_M_DQS_DN<6>"
				( objectStatus "@baseboard_fab2_lib.baseboard_fab2(sch_1):m_m_dqs_dn(6)" )
			)
			( signal "M_M_DQS_DN<7>"
				( objectStatus "@baseboard_fab2_lib.baseboard_fab2(sch_1):m_m_dqs_dn(7)" )
			)
			( signal "M_M_DQS_DN<8>"
				( objectStatus "@baseboard_fab2_lib.baseboard_fab2(sch_1):m_m_dqs_dn(8)" )
			)
			( signal "M_M_DQS_DN<9>"
				( objectStatus "@baseboard_fab2_lib.baseboard_fab2(sch_1):m_m_dqs_dn(9)" )
			)
			( signal "M_M_DQS_DN<10>"
				( objectStatus "@baseboard_fab2_lib.baseboard_fab2(sch_1):m_m_dqs_dn(10)" )
			)
			( signal "M_M_DQS_DN<11>"
				( objectStatus "@baseboard_fab2_lib.baseboard_fab2(sch_1):m_m_dqs_dn(11)" )
			)
			( signal "M_M_DQS_DN<12>"
				( objectStatus "@baseboard_fab2_lib.baseboard_fab2(sch_1):m_m_dqs_dn(12)" )
			)
			( signal "M_M_DQS_DN<13>"
				( objectStatus "@baseboard_fab2_lib.baseboard_fab2(sch_1):m_m_dqs_dn(13)" )
			)
			( signal "M_M_DQS_DN<14>"
				( objectStatus "@baseboard_fab2_lib.baseboard_fab2(sch_1):m_m_dqs_dn(14)" )
			)
			( signal "M_M_DQS_DN<15>"
				( objectStatus "@baseboard_fab2_lib.baseboard_fab2(sch_1):m_m_dqs_dn(15)" )
			)
			( signal "M_M_DQS_DN<16>"
				( objectStatus "@baseboard_fab2_lib.baseboard_fab2(sch_1):m_m_dqs_dn(16)" )
			)
			( signal "M_M_DQS_DN<17>"
				( objectStatus "@baseboard_fab2_lib.baseboard_fab2(sch_1):m_m_dqs_dn(17)" )
			)
			( signal "M_M_DQS_DP<0>"
				( objectStatus "@baseboard_fab2_lib.baseboard_fab2(sch_1):m_m_dqs_dp(0)" )
			)
			( signal "M_M_DQS_DP<1>"
				( objectStatus "@baseboard_fab2_lib.baseboard_fab2(sch_1):m_m_dqs_dp(1)" )
			)
			( signal "M_M_DQS_DP<2>"
				( objectStatus "@baseboard_fab2_lib.baseboard_fab2(sch_1):m_m_dqs_dp(2)" )
			)
			( signal "M_M_DQS_DP<3>"
				( objectStatus "@baseboard_fab2_lib.baseboard_fab2(sch_1):m_m_dqs_dp(3)" )
			)
			( signal "M_M_DQS_DP<4>"
				( objectStatus "@baseboard_fab2_lib.baseboard_fab2(sch_1):m_m_dqs_dp(4)" )
			)
			( signal "M_M_DQS_DP<5>"
				( objectStatus "@baseboard_fab2_lib.baseboard_fab2(sch_1):m_m_dqs_dp(5)" )
			)
			( signal "M_M_DQS_DP<6>"
				( objectStatus "@baseboard_fab2_lib.baseboard_fab2(sch_1):m_m_dqs_dp(6)" )
			)
			( signal "M_M_DQS_DP<7>"
				( objectStatus "@baseboard_fab2_lib.baseboard_fab2(sch_1):m_m_dqs_dp(7)" )
			)
			( signal "M_M_DQS_DP<8>"
				( objectStatus "@baseboard_fab2_lib.baseboard_fab2(sch_1):m_m_dqs_dp(8)" )
			)
			( signal "M_M_DQS_DP<9>"
				( objectStatus "@baseboard_fab2_lib.baseboard_fab2(sch_1):m_m_dqs_dp(9)" )
			)
			( signal "M_M_DQS_DP<10>"
				( objectStatus "@baseboard_fab2_lib.baseboard_fab2(sch_1):m_m_dqs_dp(10)" )
			)
			( signal "M_M_DQS_DP<11>"
				( objectStatus "@baseboard_fab2_lib.baseboard_fab2(sch_1):m_m_dqs_dp(11)" )
			)
			( signal "M_M_DQS_DP<12>"
				( objectStatus "@baseboard_fab2_lib.baseboard_fab2(sch_1):m_m_dqs_dp(12)" )
			)
			( signal "M_M_DQS_DP<13>"
				( objectStatus "@baseboard_fab2_lib.baseboard_fab2(sch_1):m_m_dqs_dp(13)" )
			)
			( signal "M_M_DQS_DP<14>"
				( objectStatus "@baseboard_fab2_lib.baseboard_fab2(sch_1):m_m_dqs_dp(14)" )
			)
			( signal "M_M_DQS_DP<15>"
				( objectStatus "@baseboard_fab2_lib.baseboard_fab2(sch_1):m_m_dqs_dp(15)" )
			)
			( signal "M_M_DQS_DP<16>"
				( objectStatus "@baseboard_fab2_lib.baseboard_fab2(sch_1):m_m_dqs_dp(16)" )
			)
			( signal "M_M_DQS_DP<17>"
				( objectStatus "@baseboard_fab2_lib.baseboard_fab2(sch_1):m_m_dqs_dp(17)" )
			)
			( signal "M_M_ECC<0>"
				( objectStatus "@baseboard_fab2_lib.baseboard_fab2(sch_1):m_m_ecc(0)" )
			)
			( signal "M_M_ECC<1>"
				( objectStatus "@baseboard_fab2_lib.baseboard_fab2(sch_1):m_m_ecc(1)" )
			)
			( signal "M_M_ECC<2>"
				( objectStatus "@baseboard_fab2_lib.baseboard_fab2(sch_1):m_m_ecc(2)" )
			)
			( signal "M_M_ECC<3>"
				( objectStatus "@baseboard_fab2_lib.baseboard_fab2(sch_1):m_m_ecc(3)" )
			)
			( signal "M_M_ECC<4>"
				( objectStatus "@baseboard_fab2_lib.baseboard_fab2(sch_1):m_m_ecc(4)" )
			)
			( signal "M_M_ECC<5>"
				( objectStatus "@baseboard_fab2_lib.baseboard_fab2(sch_1):m_m_ecc(5)" )
			)
			( signal "M_M_ECC<6>"
				( objectStatus "@baseboard_fab2_lib.baseboard_fab2(sch_1):m_m_ecc(6)" )
			)
			( signal "M_M_ECC<7>"
				( objectStatus "@baseboard_fab2_lib.baseboard_fab2(sch_1):m_m_ecc(7)" )
			)
			( signal "M_M_MA<0>"
				( objectStatus "@baseboard_fab2_lib.baseboard_fab2(sch_1):m_m_ma(0)" )
			)
			( signal "M_M_MA<1>"
				( objectStatus "@baseboard_fab2_lib.baseboard_fab2(sch_1):m_m_ma(1)" )
			)
			( signal "M_M_MA<2>"
				( objectStatus "@baseboard_fab2_lib.baseboard_fab2(sch_1):m_m_ma(2)" )
			)
			( signal "M_M_MA<3>"
				( objectStatus "@baseboard_fab2_lib.baseboard_fab2(sch_1):m_m_ma(3)" )
			)
			( signal "M_M_MA<4>"
				( objectStatus "@baseboard_fab2_lib.baseboard_fab2(sch_1):m_m_ma(4)" )
			)
			( signal "M_M_MA<5>"
				( objectStatus "@baseboard_fab2_lib.baseboard_fab2(sch_1):m_m_ma(5)" )
			)
			( signal "M_M_MA<6>"
				( objectStatus "@baseboard_fab2_lib.baseboard_fab2(sch_1):m_m_ma(6)" )
			)
			( signal "M_M_MA<7>"
				( objectStatus "@baseboard_fab2_lib.baseboard_fab2(sch_1):m_m_ma(7)" )
			)
			( signal "M_M_MA<8>"
				( objectStatus "@baseboard_fab2_lib.baseboard_fab2(sch_1):m_m_ma(8)" )
			)
			( signal "M_M_MA<9>"
				( objectStatus "@baseboard_fab2_lib.baseboard_fab2(sch_1):m_m_ma(9)" )
			)
			( signal "M_M_MA<10>"
				( objectStatus "@baseboard_fab2_lib.baseboard_fab2(sch_1):m_m_ma(10)" )
			)
			( signal "M_M_MA<11>"
				( objectStatus "@baseboard_fab2_lib.baseboard_fab2(sch_1):m_m_ma(11)" )
			)
			( signal "M_M_MA<12>"
				( objectStatus "@baseboard_fab2_lib.baseboard_fab2(sch_1):m_m_ma(12)" )
			)
			( signal "M_M_MA<13>"
				( objectStatus "@baseboard_fab2_lib.baseboard_fab2(sch_1):m_m_ma(13)" )
			)
			( signal "M_M_MA<14>"
				( objectStatus "@baseboard_fab2_lib.baseboard_fab2(sch_1):m_m_ma(14)" )
			)
			( signal "M_M_MA<15>"
				( objectStatus "@baseboard_fab2_lib.baseboard_fab2(sch_1):m_m_ma(15)" )
			)
			( signal "M_M_MA<16>"
				( objectStatus "@baseboard_fab2_lib.baseboard_fab2(sch_1):m_m_ma(16)" )
			)
			( signal "M_M_MA<17>"
				( objectStatus "@baseboard_fab2_lib.baseboard_fab2(sch_1):m_m_ma(17)" )
			)
			( signal "M_M_ODT<0>"
				( objectStatus "@baseboard_fab2_lib.baseboard_fab2(sch_1):m_m_odt(0)" )
			)
			( signal "M_M_ODT<1>"
				( objectStatus "@baseboard_fab2_lib.baseboard_fab2(sch_1):m_m_odt(1)" )
			)
			( signal "M_M_ODT<2>"
				( objectStatus "@baseboard_fab2_lib.baseboard_fab2(sch_1):m_m_odt(2)" )
			)
			( signal "M_M_ODT<3>"
				( objectStatus "@baseboard_fab2_lib.baseboard_fab2(sch_1):m_m_odt(3)" )
			)
			( signal "M_M_PAR"
				( objectStatus "@baseboard_fab2_lib.baseboard_fab2(sch_1):m_m_par" )
			)
			( signal "CLK_100M_CPU1_PE_REFCLK_DN"
				( objectStatus "@baseboard_fab2_lib.baseboard_fab2(sch_1):clk_100m_cpu1_pe_refclk_dn" )
			)
			( signal "CLK_100M_CPU1_PE_REFCLK_DP"
				( objectStatus "@baseboard_fab2_lib.baseboard_fab2(sch_1):clk_100m_cpu1_pe_refclk_dp" )
			)
			( signal "CLK_156M_OSC_CPU1_HFI_DN"
				( objectStatus "@baseboard_fab2_lib.baseboard_fab2(sch_1):clk_156m_osc_cpu1_hfi_dn" )
			)
			( signal "CLK_156M_OSC_CPU1_HFI_DP"
				( objectStatus "@baseboard_fab2_lib.baseboard_fab2(sch_1):clk_156m_osc_cpu1_hfi_dp" )
			)
			( signal "JTAG_MCP_CPU1_TDI"
				( objectStatus "@baseboard_fab2_lib.baseboard_fab2(sch_1):jtag_mcp_cpu1_tdi" )
			)
			( signal "JTAG_MCP_CPU1_TDO"
				( objectStatus "@baseboard_fab2_lib.baseboard_fab2(sch_1):jtag_mcp_cpu1_tdo" )
			)
			( signal "RST_CD_CPU1_POR_N"
				( objectStatus "@baseboard_fab2_lib.baseboard_fab2(sch_1):rst_cd_cpu1_por_n" )
			)
			( signal "TP_CD_HFI1_CPU1_I2CDAT"
				( objectStatus "@baseboard_fab2_lib.baseboard_fab2(sch_1):tp_cd_hfi1_cpu1_i2cdat" )
			)
			( signal "TP_CD_HFI1_CPU1_I2CLK"
				( objectStatus "@baseboard_fab2_lib.baseboard_fab2(sch_1):tp_cd_hfi1_cpu1_i2clk" )
			)
			( signal "TP_CD_HFI1_CPU1_INT_N"
				( objectStatus "@baseboard_fab2_lib.baseboard_fab2(sch_1):tp_cd_hfi1_cpu1_int_n" )
			)
			( signal "TP_CD_HFI1_CPU1_LED_N"
				( objectStatus "@baseboard_fab2_lib.baseboard_fab2(sch_1):tp_cd_hfi1_cpu1_led_n" )
			)
			( signal "TP_CD_HFI1_CPU1_MODPRST_N"
				( objectStatus "@baseboard_fab2_lib.baseboard_fab2(sch_1):tp_cd_hfi1_cpu1_modprst_n" )
			)
			( signal "TP_CD_HFI1_CPU1_RESET_N"
				( objectStatus "@baseboard_fab2_lib.baseboard_fab2(sch_1):tp_cd_hfi1_cpu1_reset_n" )
			)
			( signal "TP_CPU1_DMI_RX_DN0"
				( objectStatus "@baseboard_fab2_lib.baseboard_fab2(sch_1):tp_cpu1_dmi_rx_dn0" )
			)
			( signal "TP_CPU1_DMI_RX_DN1"
				( objectStatus "@baseboard_fab2_lib.baseboard_fab2(sch_1):tp_cpu1_dmi_rx_dn1" )
			)
			( signal "TP_CPU1_DMI_RX_DN2"
				( objectStatus "@baseboard_fab2_lib.baseboard_fab2(sch_1):tp_cpu1_dmi_rx_dn2" )
			)
			( signal "TP_CPU1_DMI_RX_DN3"
				( objectStatus "@baseboard_fab2_lib.baseboard_fab2(sch_1):tp_cpu1_dmi_rx_dn3" )
			)
			( signal "TP_CPU1_DMI_RX_DP0"
				( objectStatus "@baseboard_fab2_lib.baseboard_fab2(sch_1):tp_cpu1_dmi_rx_dp0" )
			)
			( signal "TP_CPU1_DMI_RX_DP1"
				( objectStatus "@baseboard_fab2_lib.baseboard_fab2(sch_1):tp_cpu1_dmi_rx_dp1" )
			)
			( signal "TP_CPU1_DMI_RX_DP2"
				( objectStatus "@baseboard_fab2_lib.baseboard_fab2(sch_1):tp_cpu1_dmi_rx_dp2" )
			)
			( signal "TP_CPU1_DMI_RX_DP3"
				( objectStatus "@baseboard_fab2_lib.baseboard_fab2(sch_1):tp_cpu1_dmi_rx_dp3" )
			)
			( signal "TP_CPU1_DMI_TX_DN0"
				( objectStatus "@baseboard_fab2_lib.baseboard_fab2(sch_1):tp_cpu1_dmi_tx_dn0" )
			)
			( signal "TP_CPU1_DMI_TX_DN1"
				( objectStatus "@baseboard_fab2_lib.baseboard_fab2(sch_1):tp_cpu1_dmi_tx_dn1" )
			)
			( signal "TP_CPU1_DMI_TX_DN2"
				( objectStatus "@baseboard_fab2_lib.baseboard_fab2(sch_1):tp_cpu1_dmi_tx_dn2" )
			)
			( signal "TP_CPU1_DMI_TX_DN3"
				( objectStatus "@baseboard_fab2_lib.baseboard_fab2(sch_1):tp_cpu1_dmi_tx_dn3" )
			)
			( signal "TP_CPU1_DMI_TX_DP0"
				( objectStatus "@baseboard_fab2_lib.baseboard_fab2(sch_1):tp_cpu1_dmi_tx_dp0" )
			)
			( signal "TP_CPU1_DMI_TX_DP1"
				( objectStatus "@baseboard_fab2_lib.baseboard_fab2(sch_1):tp_cpu1_dmi_tx_dp1" )
			)
			( signal "TP_CPU1_DMI_TX_DP2"
				( objectStatus "@baseboard_fab2_lib.baseboard_fab2(sch_1):tp_cpu1_dmi_tx_dp2" )
			)
			( signal "TP_CPU1_DMI_TX_DP3"
				( objectStatus "@baseboard_fab2_lib.baseboard_fab2(sch_1):tp_cpu1_dmi_tx_dp3" )
			)
			( signal "TP_CPU1_RSVD_172"
				( objectStatus "@baseboard_fab2_lib.baseboard_fab2(sch_1):tp_cpu1_rsvd_172" )
			)
			( signal "TP_CPU1_RSVD_173"
				( objectStatus "@baseboard_fab2_lib.baseboard_fab2(sch_1):tp_cpu1_rsvd_173" )
			)
			( signal "TP_CPU1_RSVD_174"
				( objectStatus "@baseboard_fab2_lib.baseboard_fab2(sch_1):tp_cpu1_rsvd_174" )
			)
			( signal "TP_CPU1_RSVD_175"
				( objectStatus "@baseboard_fab2_lib.baseboard_fab2(sch_1):tp_cpu1_rsvd_175" )
			)
			( signal "TP_CPU1_RSVD_176"
				( objectStatus "@baseboard_fab2_lib.baseboard_fab2(sch_1):tp_cpu1_rsvd_176" )
			)
			( signal "TP_CPU1_RSVD_177"
				( objectStatus "@baseboard_fab2_lib.baseboard_fab2(sch_1):tp_cpu1_rsvd_177" )
			)
			( signal "TP_CPU1_RSVD_178"
				( objectStatus "@baseboard_fab2_lib.baseboard_fab2(sch_1):tp_cpu1_rsvd_178" )
			)
			( signal "TP_CPU1_RSVD_179"
				( objectStatus "@baseboard_fab2_lib.baseboard_fab2(sch_1):tp_cpu1_rsvd_179" )
			)
			( signal "TP_CPU1_RSVD_180"
				( objectStatus "@baseboard_fab2_lib.baseboard_fab2(sch_1):tp_cpu1_rsvd_180" )
			)
			( signal "TP_CPU1_RSVD_181"
				( objectStatus "@baseboard_fab2_lib.baseboard_fab2(sch_1):tp_cpu1_rsvd_181" )
			)
			( signal "TP_CPU1_RSVD_182"
				( objectStatus "@baseboard_fab2_lib.baseboard_fab2(sch_1):tp_cpu1_rsvd_182" )
			)
			( signal "TP_CPU1_RSVD_183"
				( objectStatus "@baseboard_fab2_lib.baseboard_fab2(sch_1):tp_cpu1_rsvd_183" )
			)
			( signal "TP_CPU1_RSVD_184"
				( objectStatus "@baseboard_fab2_lib.baseboard_fab2(sch_1):tp_cpu1_rsvd_184" )
			)
			( signal "TP_CPU1_RSVD_186"
				( objectStatus "@baseboard_fab2_lib.baseboard_fab2(sch_1):tp_cpu1_rsvd_186" )
			)
			( signal "TP_CPU1_RSVD_189"
				( objectStatus "@baseboard_fab2_lib.baseboard_fab2(sch_1):tp_cpu1_rsvd_189" )
			)
			( signal "TP_CPU1_RSVD_190"
				( objectStatus "@baseboard_fab2_lib.baseboard_fab2(sch_1):tp_cpu1_rsvd_190" )
			)
			( signal "TP_FM_CPU1_CD_HFI0_MODPRST_N"
				( objectStatus "@baseboard_fab2_lib.baseboard_fab2(sch_1):tp_fm_cpu1_cd_hfi0_modprst_n" )
			)
			( signal "TP_IRQ_CPU1_CD_HFI0_N"
				( objectStatus "@baseboard_fab2_lib.baseboard_fab2(sch_1):tp_irq_cpu1_cd_hfi0_n" )
			)
			( signal "TP_LED_CPU1_CD_HFI0_N"
				( objectStatus "@baseboard_fab2_lib.baseboard_fab2(sch_1):tp_led_cpu1_cd_hfi0_n" )
			)
			( signal "TP_RST_CPU1_CD_HFI0_N"
				( objectStatus "@baseboard_fab2_lib.baseboard_fab2(sch_1):tp_rst_cpu1_cd_hfi0_n" )
			)
			( signal "TP_SMB_CPU1_CD_HFI0_I2CCLK"
				( objectStatus "@baseboard_fab2_lib.baseboard_fab2(sch_1):tp_smb_cpu1_cd_hfi0_i2cclk" )
			)
			( signal "TP_SMB_CPU1_CD_HFI0_I2CDAT"
				( objectStatus "@baseboard_fab2_lib.baseboard_fab2(sch_1):tp_smb_cpu1_cd_hfi0_i2cdat" )
			)
			( signal "TP_P3E_CPU1_PE1_MP_RXN<0>"
				( objectStatus "@baseboard_fab2_lib.baseboard_fab2(sch_1):tp_p3e_cpu1_pe1_mp_rxn(0)" )
			)
			( signal "TP_P3E_CPU1_PE1_MP_RXN<1>"
				( objectStatus "@baseboard_fab2_lib.baseboard_fab2(sch_1):tp_p3e_cpu1_pe1_mp_rxn(1)" )
			)
			( signal "TP_P3E_CPU1_PE1_MP_RXN<2>"
				( objectStatus "@baseboard_fab2_lib.baseboard_fab2(sch_1):tp_p3e_cpu1_pe1_mp_rxn(2)" )
			)
			( signal "TP_P3E_CPU1_PE1_MP_RXN<3>"
				( objectStatus "@baseboard_fab2_lib.baseboard_fab2(sch_1):tp_p3e_cpu1_pe1_mp_rxn(3)" )
			)
			( signal "TP_P3E_CPU1_PE1_MP_RXN<4>"
				( objectStatus "@baseboard_fab2_lib.baseboard_fab2(sch_1):tp_p3e_cpu1_pe1_mp_rxn(4)" )
			)
			( signal "TP_P3E_CPU1_PE1_MP_RXN<5>"
				( objectStatus "@baseboard_fab2_lib.baseboard_fab2(sch_1):tp_p3e_cpu1_pe1_mp_rxn(5)" )
			)
			( signal "TP_P3E_CPU1_PE1_MP_RXN<6>"
				( objectStatus "@baseboard_fab2_lib.baseboard_fab2(sch_1):tp_p3e_cpu1_pe1_mp_rxn(6)" )
			)
			( signal "TP_P3E_CPU1_PE1_MP_RXN<7>"
				( objectStatus "@baseboard_fab2_lib.baseboard_fab2(sch_1):tp_p3e_cpu1_pe1_mp_rxn(7)" )
			)
			( signal "TP_P3E_CPU1_PE1_MP_RXP<0>"
				( objectStatus "@baseboard_fab2_lib.baseboard_fab2(sch_1):tp_p3e_cpu1_pe1_mp_rxp(0)" )
			)
			( signal "TP_P3E_CPU1_PE1_MP_RXP<1>"
				( objectStatus "@baseboard_fab2_lib.baseboard_fab2(sch_1):tp_p3e_cpu1_pe1_mp_rxp(1)" )
			)
			( signal "TP_P3E_CPU1_PE1_MP_RXP<2>"
				( objectStatus "@baseboard_fab2_lib.baseboard_fab2(sch_1):tp_p3e_cpu1_pe1_mp_rxp(2)" )
			)
			( signal "TP_P3E_CPU1_PE1_MP_RXP<3>"
				( objectStatus "@baseboard_fab2_lib.baseboard_fab2(sch_1):tp_p3e_cpu1_pe1_mp_rxp(3)" )
			)
			( signal "TP_P3E_CPU1_PE1_MP_RXP<4>"
				( objectStatus "@baseboard_fab2_lib.baseboard_fab2(sch_1):tp_p3e_cpu1_pe1_mp_rxp(4)" )
			)
			( signal "TP_P3E_CPU1_PE1_MP_RXP<5>"
				( objectStatus "@baseboard_fab2_lib.baseboard_fab2(sch_1):tp_p3e_cpu1_pe1_mp_rxp(5)" )
			)
			( signal "TP_P3E_CPU1_PE1_MP_RXP<6>"
				( objectStatus "@baseboard_fab2_lib.baseboard_fab2(sch_1):tp_p3e_cpu1_pe1_mp_rxp(6)" )
			)
			( signal "TP_P3E_CPU1_PE1_MP_RXP<7>"
				( objectStatus "@baseboard_fab2_lib.baseboard_fab2(sch_1):tp_p3e_cpu1_pe1_mp_rxp(7)" )
			)
			( signal "TP_P3E_CPU1_PE1_MP_TXN<0>"
				( objectStatus "@baseboard_fab2_lib.baseboard_fab2(sch_1):tp_p3e_cpu1_pe1_mp_txn(0)" )
			)
			( signal "TP_P3E_CPU1_PE1_MP_TXN<1>"
				( objectStatus "@baseboard_fab2_lib.baseboard_fab2(sch_1):tp_p3e_cpu1_pe1_mp_txn(1)" )
			)
			( signal "TP_P3E_CPU1_PE1_MP_TXN<2>"
				( objectStatus "@baseboard_fab2_lib.baseboard_fab2(sch_1):tp_p3e_cpu1_pe1_mp_txn(2)" )
			)
			( signal "TP_P3E_CPU1_PE1_MP_TXN<3>"
				( objectStatus "@baseboard_fab2_lib.baseboard_fab2(sch_1):tp_p3e_cpu1_pe1_mp_txn(3)" )
			)
			( signal "TP_P3E_CPU1_PE1_MP_TXN<4>"
				( objectStatus "@baseboard_fab2_lib.baseboard_fab2(sch_1):tp_p3e_cpu1_pe1_mp_txn(4)" )
			)
			( signal "TP_P3E_CPU1_PE1_MP_TXN<5>"
				( objectStatus "@baseboard_fab2_lib.baseboard_fab2(sch_1):tp_p3e_cpu1_pe1_mp_txn(5)" )
			)
			( signal "TP_P3E_CPU1_PE1_MP_TXN<6>"
				( objectStatus "@baseboard_fab2_lib.baseboard_fab2(sch_1):tp_p3e_cpu1_pe1_mp_txn(6)" )
			)
			( signal "TP_P3E_CPU1_PE1_MP_TXN<7>"
				( objectStatus "@baseboard_fab2_lib.baseboard_fab2(sch_1):tp_p3e_cpu1_pe1_mp_txn(7)" )
			)
			( signal "TP_P3E_CPU1_PE1_MP_TXP<0>"
				( objectStatus "@baseboard_fab2_lib.baseboard_fab2(sch_1):tp_p3e_cpu1_pe1_mp_txp(0)" )
			)
			( signal "TP_P3E_CPU1_PE1_MP_TXP<1>"
				( objectStatus "@baseboard_fab2_lib.baseboard_fab2(sch_1):tp_p3e_cpu1_pe1_mp_txp(1)" )
			)
			( signal "TP_P3E_CPU1_PE1_MP_TXP<2>"
				( objectStatus "@baseboard_fab2_lib.baseboard_fab2(sch_1):tp_p3e_cpu1_pe1_mp_txp(2)" )
			)
			( signal "TP_P3E_CPU1_PE1_MP_TXP<3>"
				( objectStatus "@baseboard_fab2_lib.baseboard_fab2(sch_1):tp_p3e_cpu1_pe1_mp_txp(3)" )
			)
			( signal "TP_P3E_CPU1_PE1_MP_TXP<4>"
				( objectStatus "@baseboard_fab2_lib.baseboard_fab2(sch_1):tp_p3e_cpu1_pe1_mp_txp(4)" )
			)
			( signal "TP_P3E_CPU1_PE1_MP_TXP<5>"
				( objectStatus "@baseboard_fab2_lib.baseboard_fab2(sch_1):tp_p3e_cpu1_pe1_mp_txp(5)" )
			)
			( signal "TP_P3E_CPU1_PE1_MP_TXP<6>"
				( objectStatus "@baseboard_fab2_lib.baseboard_fab2(sch_1):tp_p3e_cpu1_pe1_mp_txp(6)" )
			)
			( signal "TP_P3E_CPU1_PE1_MP_TXP<7>"
				( objectStatus "@baseboard_fab2_lib.baseboard_fab2(sch_1):tp_p3e_cpu1_pe1_mp_txp(7)" )
			)
			( signal "TP_P3E_CPU1_PE1_RSR3_RXN<8>"
				( objectStatus "@baseboard_fab2_lib.baseboard_fab2(sch_1):tp_p3e_cpu1_pe1_rsr3_rxn(8)" )
			)
			( signal "TP_P3E_CPU1_PE1_RSR3_RXN<9>"
				( objectStatus "@baseboard_fab2_lib.baseboard_fab2(sch_1):tp_p3e_cpu1_pe1_rsr3_rxn(9)" )
			)
			( signal "TP_P3E_CPU1_PE1_RSR3_RXN<10>"
				( objectStatus "@baseboard_fab2_lib.baseboard_fab2(sch_1):tp_p3e_cpu1_pe1_rsr3_rxn(10)" )
			)
			( signal "TP_P3E_CPU1_PE1_RSR3_RXN<11>"
				( objectStatus "@baseboard_fab2_lib.baseboard_fab2(sch_1):tp_p3e_cpu1_pe1_rsr3_rxn(11)" )
			)
			( signal "TP_P3E_CPU1_PE1_RSR3_RXN<12>"
				( objectStatus "@baseboard_fab2_lib.baseboard_fab2(sch_1):tp_p3e_cpu1_pe1_rsr3_rxn(12)" )
			)
			( signal "TP_P3E_CPU1_PE1_RSR3_RXN<13>"
				( objectStatus "@baseboard_fab2_lib.baseboard_fab2(sch_1):tp_p3e_cpu1_pe1_rsr3_rxn(13)" )
			)
			( signal "TP_P3E_CPU1_PE1_RSR3_RXN<14>"
				( objectStatus "@baseboard_fab2_lib.baseboard_fab2(sch_1):tp_p3e_cpu1_pe1_rsr3_rxn(14)" )
			)
			( signal "TP_P3E_CPU1_PE1_RSR3_RXN<15>"
				( objectStatus "@baseboard_fab2_lib.baseboard_fab2(sch_1):tp_p3e_cpu1_pe1_rsr3_rxn(15)" )
			)
			( signal "TP_P3E_CPU1_PE1_RSR3_RXP<8>"
				( objectStatus "@baseboard_fab2_lib.baseboard_fab2(sch_1):tp_p3e_cpu1_pe1_rsr3_rxp(8)" )
			)
			( signal "TP_P3E_CPU1_PE1_RSR3_RXP<9>"
				( objectStatus "@baseboard_fab2_lib.baseboard_fab2(sch_1):tp_p3e_cpu1_pe1_rsr3_rxp(9)" )
			)
			( signal "TP_P3E_CPU1_PE1_RSR3_RXP<10>"
				( objectStatus "@baseboard_fab2_lib.baseboard_fab2(sch_1):tp_p3e_cpu1_pe1_rsr3_rxp(10)" )
			)
			( signal "TP_P3E_CPU1_PE1_RSR3_RXP<11>"
				( objectStatus "@baseboard_fab2_lib.baseboard_fab2(sch_1):tp_p3e_cpu1_pe1_rsr3_rxp(11)" )
			)
			( signal "TP_P3E_CPU1_PE1_RSR3_RXP<12>"
				( objectStatus "@baseboard_fab2_lib.baseboard_fab2(sch_1):tp_p3e_cpu1_pe1_rsr3_rxp(12)" )
			)
			( signal "TP_P3E_CPU1_PE1_RSR3_RXP<13>"
				( objectStatus "@baseboard_fab2_lib.baseboard_fab2(sch_1):tp_p3e_cpu1_pe1_rsr3_rxp(13)" )
			)
			( signal "TP_P3E_CPU1_PE1_RSR3_RXP<14>"
				( objectStatus "@baseboard_fab2_lib.baseboard_fab2(sch_1):tp_p3e_cpu1_pe1_rsr3_rxp(14)" )
			)
			( signal "TP_P3E_CPU1_PE1_RSR3_RXP<15>"
				( objectStatus "@baseboard_fab2_lib.baseboard_fab2(sch_1):tp_p3e_cpu1_pe1_rsr3_rxp(15)" )
			)
			( signal "TP_P3E_CPU1_PE1_RSR3_TXN<8>"
				( objectStatus "@baseboard_fab2_lib.baseboard_fab2(sch_1):tp_p3e_cpu1_pe1_rsr3_txn(8)" )
			)
			( signal "TP_P3E_CPU1_PE1_RSR3_TXN<9>"
				( objectStatus "@baseboard_fab2_lib.baseboard_fab2(sch_1):tp_p3e_cpu1_pe1_rsr3_txn(9)" )
			)
			( signal "TP_P3E_CPU1_PE1_RSR3_TXN<10>"
				( objectStatus "@baseboard_fab2_lib.baseboard_fab2(sch_1):tp_p3e_cpu1_pe1_rsr3_txn(10)" )
			)
			( signal "TP_P3E_CPU1_PE1_RSR3_TXN<11>"
				( objectStatus "@baseboard_fab2_lib.baseboard_fab2(sch_1):tp_p3e_cpu1_pe1_rsr3_txn(11)" )
			)
			( signal "TP_P3E_CPU1_PE1_RSR3_TXN<12>"
				( objectStatus "@baseboard_fab2_lib.baseboard_fab2(sch_1):tp_p3e_cpu1_pe1_rsr3_txn(12)" )
			)
			( signal "TP_P3E_CPU1_PE1_RSR3_TXN<13>"
				( objectStatus "@baseboard_fab2_lib.baseboard_fab2(sch_1):tp_p3e_cpu1_pe1_rsr3_txn(13)" )
			)
			( signal "TP_P3E_CPU1_PE1_RSR3_TXN<14>"
				( objectStatus "@baseboard_fab2_lib.baseboard_fab2(sch_1):tp_p3e_cpu1_pe1_rsr3_txn(14)" )
			)
			( signal "TP_P3E_CPU1_PE1_RSR3_TXN<15>"
				( objectStatus "@baseboard_fab2_lib.baseboard_fab2(sch_1):tp_p3e_cpu1_pe1_rsr3_txn(15)" )
			)
			( signal "TP_P3E_CPU1_PE1_RSR3_TXP<8>"
				( objectStatus "@baseboard_fab2_lib.baseboard_fab2(sch_1):tp_p3e_cpu1_pe1_rsr3_txp(8)" )
			)
			( signal "TP_P3E_CPU1_PE1_RSR3_TXP<9>"
				( objectStatus "@baseboard_fab2_lib.baseboard_fab2(sch_1):tp_p3e_cpu1_pe1_rsr3_txp(9)" )
			)
			( signal "TP_P3E_CPU1_PE1_RSR3_TXP<10>"
				( objectStatus "@baseboard_fab2_lib.baseboard_fab2(sch_1):tp_p3e_cpu1_pe1_rsr3_txp(10)" )
			)
			( signal "TP_P3E_CPU1_PE1_RSR3_TXP<11>"
				( objectStatus "@baseboard_fab2_lib.baseboard_fab2(sch_1):tp_p3e_cpu1_pe1_rsr3_txp(11)" )
			)
			( signal "TP_P3E_CPU1_PE1_RSR3_TXP<12>"
				( objectStatus "@baseboard_fab2_lib.baseboard_fab2(sch_1):tp_p3e_cpu1_pe1_rsr3_txp(12)" )
			)
			( signal "TP_P3E_CPU1_PE1_RSR3_TXP<13>"
				( objectStatus "@baseboard_fab2_lib.baseboard_fab2(sch_1):tp_p3e_cpu1_pe1_rsr3_txp(13)" )
			)
			( signal "TP_P3E_CPU1_PE1_RSR3_TXP<14>"
				( objectStatus "@baseboard_fab2_lib.baseboard_fab2(sch_1):tp_p3e_cpu1_pe1_rsr3_txp(14)" )
			)
			( signal "TP_P3E_CPU1_PE1_RSR3_TXP<15>"
				( objectStatus "@baseboard_fab2_lib.baseboard_fab2(sch_1):tp_p3e_cpu1_pe1_rsr3_txp(15)" )
			)
			( signal "TP_P3E_CPU1_PE2_RSR_RXN<0>"
				( objectStatus "@baseboard_fab2_lib.baseboard_fab2(sch_1):tp_p3e_cpu1_pe2_rsr_rxn(0)" )
			)
			( signal "TP_P3E_CPU1_PE2_RSR_RXN<1>"
				( objectStatus "@baseboard_fab2_lib.baseboard_fab2(sch_1):tp_p3e_cpu1_pe2_rsr_rxn(1)" )
			)
			( signal "TP_P3E_CPU1_PE2_RSR_RXN<2>"
				( objectStatus "@baseboard_fab2_lib.baseboard_fab2(sch_1):tp_p3e_cpu1_pe2_rsr_rxn(2)" )
			)
			( signal "TP_P3E_CPU1_PE2_RSR_RXN<3>"
				( objectStatus "@baseboard_fab2_lib.baseboard_fab2(sch_1):tp_p3e_cpu1_pe2_rsr_rxn(3)" )
			)
			( signal "TP_P3E_CPU1_PE2_RSR_RXN<4>"
				( objectStatus "@baseboard_fab2_lib.baseboard_fab2(sch_1):tp_p3e_cpu1_pe2_rsr_rxn(4)" )
			)
			( signal "TP_P3E_CPU1_PE2_RSR_RXN<5>"
				( objectStatus "@baseboard_fab2_lib.baseboard_fab2(sch_1):tp_p3e_cpu1_pe2_rsr_rxn(5)" )
			)
			( signal "TP_P3E_CPU1_PE2_RSR_RXN<6>"
				( objectStatus "@baseboard_fab2_lib.baseboard_fab2(sch_1):tp_p3e_cpu1_pe2_rsr_rxn(6)" )
			)
			( signal "TP_P3E_CPU1_PE2_RSR_RXN<7>"
				( objectStatus "@baseboard_fab2_lib.baseboard_fab2(sch_1):tp_p3e_cpu1_pe2_rsr_rxn(7)" )
			)
			( signal "TP_P3E_CPU1_PE2_RSR_RXN<8>"
				( objectStatus "@baseboard_fab2_lib.baseboard_fab2(sch_1):tp_p3e_cpu1_pe2_rsr_rxn(8)" )
			)
			( signal "TP_P3E_CPU1_PE2_RSR_RXN<9>"
				( objectStatus "@baseboard_fab2_lib.baseboard_fab2(sch_1):tp_p3e_cpu1_pe2_rsr_rxn(9)" )
			)
			( signal "TP_P3E_CPU1_PE2_RSR_RXN<10>"
				( objectStatus "@baseboard_fab2_lib.baseboard_fab2(sch_1):tp_p3e_cpu1_pe2_rsr_rxn(10)" )
			)
			( signal "TP_P3E_CPU1_PE2_RSR_RXN<11>"
				( objectStatus "@baseboard_fab2_lib.baseboard_fab2(sch_1):tp_p3e_cpu1_pe2_rsr_rxn(11)" )
			)
			( signal "TP_P3E_CPU1_PE2_RSR_RXN<12>"
				( objectStatus "@baseboard_fab2_lib.baseboard_fab2(sch_1):tp_p3e_cpu1_pe2_rsr_rxn(12)" )
			)
			( signal "TP_P3E_CPU1_PE2_RSR_RXN<13>"
				( objectStatus "@baseboard_fab2_lib.baseboard_fab2(sch_1):tp_p3e_cpu1_pe2_rsr_rxn(13)" )
			)
			( signal "TP_P3E_CPU1_PE2_RSR_RXN<14>"
				( objectStatus "@baseboard_fab2_lib.baseboard_fab2(sch_1):tp_p3e_cpu1_pe2_rsr_rxn(14)" )
			)
			( signal "TP_P3E_CPU1_PE2_RSR_RXN<15>"
				( objectStatus "@baseboard_fab2_lib.baseboard_fab2(sch_1):tp_p3e_cpu1_pe2_rsr_rxn(15)" )
			)
			( signal "TP_P3E_CPU1_PE2_RSR_RXP<0>"
				( objectStatus "@baseboard_fab2_lib.baseboard_fab2(sch_1):tp_p3e_cpu1_pe2_rsr_rxp(0)" )
			)
			( signal "TP_P3E_CPU1_PE2_RSR_RXP<1>"
				( objectStatus "@baseboard_fab2_lib.baseboard_fab2(sch_1):tp_p3e_cpu1_pe2_rsr_rxp(1)" )
			)
			( signal "TP_P3E_CPU1_PE2_RSR_RXP<2>"
				( objectStatus "@baseboard_fab2_lib.baseboard_fab2(sch_1):tp_p3e_cpu1_pe2_rsr_rxp(2)" )
			)
			( signal "TP_P3E_CPU1_PE2_RSR_RXP<3>"
				( objectStatus "@baseboard_fab2_lib.baseboard_fab2(sch_1):tp_p3e_cpu1_pe2_rsr_rxp(3)" )
			)
			( signal "TP_P3E_CPU1_PE2_RSR_RXP<4>"
				( objectStatus "@baseboard_fab2_lib.baseboard_fab2(sch_1):tp_p3e_cpu1_pe2_rsr_rxp(4)" )
			)
			( signal "TP_P3E_CPU1_PE2_RSR_RXP<5>"
				( objectStatus "@baseboard_fab2_lib.baseboard_fab2(sch_1):tp_p3e_cpu1_pe2_rsr_rxp(5)" )
			)
			( signal "TP_P3E_CPU1_PE2_RSR_RXP<6>"
				( objectStatus "@baseboard_fab2_lib.baseboard_fab2(sch_1):tp_p3e_cpu1_pe2_rsr_rxp(6)" )
			)
			( signal "TP_P3E_CPU1_PE2_RSR_RXP<7>"
				( objectStatus "@baseboard_fab2_lib.baseboard_fab2(sch_1):tp_p3e_cpu1_pe2_rsr_rxp(7)" )
			)
			( signal "TP_P3E_CPU1_PE2_RSR_RXP<8>"
				( objectStatus "@baseboard_fab2_lib.baseboard_fab2(sch_1):tp_p3e_cpu1_pe2_rsr_rxp(8)" )
			)
			( signal "TP_P3E_CPU1_PE2_RSR_RXP<9>"
				( objectStatus "@baseboard_fab2_lib.baseboard_fab2(sch_1):tp_p3e_cpu1_pe2_rsr_rxp(9)" )
			)
			( signal "TP_P3E_CPU1_PE2_RSR_RXP<10>"
				( objectStatus "@baseboard_fab2_lib.baseboard_fab2(sch_1):tp_p3e_cpu1_pe2_rsr_rxp(10)" )
			)
			( signal "TP_P3E_CPU1_PE2_RSR_RXP<11>"
				( objectStatus "@baseboard_fab2_lib.baseboard_fab2(sch_1):tp_p3e_cpu1_pe2_rsr_rxp(11)" )
			)
			( signal "TP_P3E_CPU1_PE2_RSR_RXP<12>"
				( objectStatus "@baseboard_fab2_lib.baseboard_fab2(sch_1):tp_p3e_cpu1_pe2_rsr_rxp(12)" )
			)
			( signal "TP_P3E_CPU1_PE2_RSR_RXP<13>"
				( objectStatus "@baseboard_fab2_lib.baseboard_fab2(sch_1):tp_p3e_cpu1_pe2_rsr_rxp(13)" )
			)
			( signal "TP_P3E_CPU1_PE2_RSR_RXP<14>"
				( objectStatus "@baseboard_fab2_lib.baseboard_fab2(sch_1):tp_p3e_cpu1_pe2_rsr_rxp(14)" )
			)
			( signal "TP_P3E_CPU1_PE2_RSR_RXP<15>"
				( objectStatus "@baseboard_fab2_lib.baseboard_fab2(sch_1):tp_p3e_cpu1_pe2_rsr_rxp(15)" )
			)
			( signal "TP_P3E_CPU1_PE2_RSR_TXN<0>"
				( objectStatus "@baseboard_fab2_lib.baseboard_fab2(sch_1):tp_p3e_cpu1_pe2_rsr_txn(0)" )
			)
			( signal "TP_P3E_CPU1_PE2_RSR_TXN<1>"
				( objectStatus "@baseboard_fab2_lib.baseboard_fab2(sch_1):tp_p3e_cpu1_pe2_rsr_txn(1)" )
			)
			( signal "TP_P3E_CPU1_PE2_RSR_TXN<2>"
				( objectStatus "@baseboard_fab2_lib.baseboard_fab2(sch_1):tp_p3e_cpu1_pe2_rsr_txn(2)" )
			)
			( signal "TP_P3E_CPU1_PE2_RSR_TXN<3>"
				( objectStatus "@baseboard_fab2_lib.baseboard_fab2(sch_1):tp_p3e_cpu1_pe2_rsr_txn(3)" )
			)
			( signal "TP_P3E_CPU1_PE2_RSR_TXN<4>"
				( objectStatus "@baseboard_fab2_lib.baseboard_fab2(sch_1):tp_p3e_cpu1_pe2_rsr_txn(4)" )
			)
			( signal "TP_P3E_CPU1_PE2_RSR_TXN<5>"
				( objectStatus "@baseboard_fab2_lib.baseboard_fab2(sch_1):tp_p3e_cpu1_pe2_rsr_txn(5)" )
			)
			( signal "TP_P3E_CPU1_PE2_RSR_TXN<6>"
				( objectStatus "@baseboard_fab2_lib.baseboard_fab2(sch_1):tp_p3e_cpu1_pe2_rsr_txn(6)" )
			)
			( signal "TP_P3E_CPU1_PE2_RSR_TXN<7>"
				( objectStatus "@baseboard_fab2_lib.baseboard_fab2(sch_1):tp_p3e_cpu1_pe2_rsr_txn(7)" )
			)
			( signal "TP_P3E_CPU1_PE2_RSR_TXN<8>"
				( objectStatus "@baseboard_fab2_lib.baseboard_fab2(sch_1):tp_p3e_cpu1_pe2_rsr_txn(8)" )
			)
			( signal "TP_P3E_CPU1_PE2_RSR_TXN<9>"
				( objectStatus "@baseboard_fab2_lib.baseboard_fab2(sch_1):tp_p3e_cpu1_pe2_rsr_txn(9)" )
			)
			( signal "TP_P3E_CPU1_PE2_RSR_TXN<10>"
				( objectStatus "@baseboard_fab2_lib.baseboard_fab2(sch_1):tp_p3e_cpu1_pe2_rsr_txn(10)" )
			)
			( signal "TP_P3E_CPU1_PE2_RSR_TXN<11>"
				( objectStatus "@baseboard_fab2_lib.baseboard_fab2(sch_1):tp_p3e_cpu1_pe2_rsr_txn(11)" )
			)
			( signal "TP_P3E_CPU1_PE2_RSR_TXN<12>"
				( objectStatus "@baseboard_fab2_lib.baseboard_fab2(sch_1):tp_p3e_cpu1_pe2_rsr_txn(12)" )
			)
			( signal "TP_P3E_CPU1_PE2_RSR_TXN<13>"
				( objectStatus "@baseboard_fab2_lib.baseboard_fab2(sch_1):tp_p3e_cpu1_pe2_rsr_txn(13)" )
			)
			( signal "TP_P3E_CPU1_PE2_RSR_TXN<14>"
				( objectStatus "@baseboard_fab2_lib.baseboard_fab2(sch_1):tp_p3e_cpu1_pe2_rsr_txn(14)" )
			)
			( signal "TP_P3E_CPU1_PE2_RSR_TXN<15>"
				( objectStatus "@baseboard_fab2_lib.baseboard_fab2(sch_1):tp_p3e_cpu1_pe2_rsr_txn(15)" )
			)
			( signal "TP_P3E_CPU1_PE2_RSR_TXP<0>"
				( objectStatus "@baseboard_fab2_lib.baseboard_fab2(sch_1):tp_p3e_cpu1_pe2_rsr_txp(0)" )
			)
			( signal "TP_P3E_CPU1_PE2_RSR_TXP<1>"
				( objectStatus "@baseboard_fab2_lib.baseboard_fab2(sch_1):tp_p3e_cpu1_pe2_rsr_txp(1)" )
			)
			( signal "TP_P3E_CPU1_PE2_RSR_TXP<2>"
				( objectStatus "@baseboard_fab2_lib.baseboard_fab2(sch_1):tp_p3e_cpu1_pe2_rsr_txp(2)" )
			)
			( signal "TP_P3E_CPU1_PE2_RSR_TXP<3>"
				( objectStatus "@baseboard_fab2_lib.baseboard_fab2(sch_1):tp_p3e_cpu1_pe2_rsr_txp(3)" )
			)
			( signal "TP_P3E_CPU1_PE2_RSR_TXP<4>"
				( objectStatus "@baseboard_fab2_lib.baseboard_fab2(sch_1):tp_p3e_cpu1_pe2_rsr_txp(4)" )
			)
			( signal "TP_P3E_CPU1_PE2_RSR_TXP<5>"
				( objectStatus "@baseboard_fab2_lib.baseboard_fab2(sch_1):tp_p3e_cpu1_pe2_rsr_txp(5)" )
			)
			( signal "TP_P3E_CPU1_PE2_RSR_TXP<6>"
				( objectStatus "@baseboard_fab2_lib.baseboard_fab2(sch_1):tp_p3e_cpu1_pe2_rsr_txp(6)" )
			)
			( signal "TP_P3E_CPU1_PE2_RSR_TXP<7>"
				( objectStatus "@baseboard_fab2_lib.baseboard_fab2(sch_1):tp_p3e_cpu1_pe2_rsr_txp(7)" )
			)
			( signal "TP_P3E_CPU1_PE2_RSR_TXP<8>"
				( objectStatus "@baseboard_fab2_lib.baseboard_fab2(sch_1):tp_p3e_cpu1_pe2_rsr_txp(8)" )
			)
			( signal "TP_P3E_CPU1_PE2_RSR_TXP<9>"
				( objectStatus "@baseboard_fab2_lib.baseboard_fab2(sch_1):tp_p3e_cpu1_pe2_rsr_txp(9)" )
			)
			( signal "TP_P3E_CPU1_PE2_RSR_TXP<10>"
				( objectStatus "@baseboard_fab2_lib.baseboard_fab2(sch_1):tp_p3e_cpu1_pe2_rsr_txp(10)" )
			)
			( signal "TP_P3E_CPU1_PE2_RSR_TXP<11>"
				( objectStatus "@baseboard_fab2_lib.baseboard_fab2(sch_1):tp_p3e_cpu1_pe2_rsr_txp(11)" )
			)
			( signal "TP_P3E_CPU1_PE2_RSR_TXP<12>"
				( objectStatus "@baseboard_fab2_lib.baseboard_fab2(sch_1):tp_p3e_cpu1_pe2_rsr_txp(12)" )
			)
			( signal "TP_P3E_CPU1_PE2_RSR_TXP<13>"
				( objectStatus "@baseboard_fab2_lib.baseboard_fab2(sch_1):tp_p3e_cpu1_pe2_rsr_txp(13)" )
			)
			( signal "TP_P3E_CPU1_PE2_RSR_TXP<14>"
				( objectStatus "@baseboard_fab2_lib.baseboard_fab2(sch_1):tp_p3e_cpu1_pe2_rsr_txp(14)" )
			)
			( signal "TP_P3E_CPU1_PE2_RSR_TXP<15>"
				( objectStatus "@baseboard_fab2_lib.baseboard_fab2(sch_1):tp_p3e_cpu1_pe2_rsr_txp(15)" )
			)
			( signal "P3E_CPU1_PE3_MP_RXN<0>"
				( objectStatus "@baseboard_fab2_lib.baseboard_fab2(sch_1):p3e_cpu1_pe3_mp_rxn(0)" )
			)
			( signal "P3E_CPU1_PE3_MP_RXN<1>"
				( objectStatus "@baseboard_fab2_lib.baseboard_fab2(sch_1):p3e_cpu1_pe3_mp_rxn(1)" )
			)
			( signal "P3E_CPU1_PE3_MP_RXN<2>"
				( objectStatus "@baseboard_fab2_lib.baseboard_fab2(sch_1):p3e_cpu1_pe3_mp_rxn(2)" )
			)
			( signal "P3E_CPU1_PE3_MP_RXN<3>"
				( objectStatus "@baseboard_fab2_lib.baseboard_fab2(sch_1):p3e_cpu1_pe3_mp_rxn(3)" )
			)
			( signal "P3E_CPU1_PE3_MP_RXN<4>"
				( objectStatus "@baseboard_fab2_lib.baseboard_fab2(sch_1):p3e_cpu1_pe3_mp_rxn(4)" )
			)
			( signal "P3E_CPU1_PE3_MP_RXN<5>"
				( objectStatus "@baseboard_fab2_lib.baseboard_fab2(sch_1):p3e_cpu1_pe3_mp_rxn(5)" )
			)
			( signal "P3E_CPU1_PE3_MP_RXN<6>"
				( objectStatus "@baseboard_fab2_lib.baseboard_fab2(sch_1):p3e_cpu1_pe3_mp_rxn(6)" )
			)
			( signal "P3E_CPU1_PE3_MP_RXN<7>"
				( objectStatus "@baseboard_fab2_lib.baseboard_fab2(sch_1):p3e_cpu1_pe3_mp_rxn(7)" )
			)
			( signal "P3E_CPU1_PE3_MP_RXN<8>"
				( objectStatus "@baseboard_fab2_lib.baseboard_fab2(sch_1):p3e_cpu1_pe3_mp_rxn(8)" )
			)
			( signal "P3E_CPU1_PE3_MP_RXN<9>"
				( objectStatus "@baseboard_fab2_lib.baseboard_fab2(sch_1):p3e_cpu1_pe3_mp_rxn(9)" )
			)
			( signal "P3E_CPU1_PE3_MP_RXN<10>"
				( objectStatus "@baseboard_fab2_lib.baseboard_fab2(sch_1):p3e_cpu1_pe3_mp_rxn(10)" )
			)
			( signal "P3E_CPU1_PE3_MP_RXN<11>"
				( objectStatus "@baseboard_fab2_lib.baseboard_fab2(sch_1):p3e_cpu1_pe3_mp_rxn(11)" )
			)
			( signal "P3E_CPU1_PE3_MP_RXN<12>"
				( objectStatus "@baseboard_fab2_lib.baseboard_fab2(sch_1):p3e_cpu1_pe3_mp_rxn(12)" )
			)
			( signal "P3E_CPU1_PE3_MP_RXN<13>"
				( objectStatus "@baseboard_fab2_lib.baseboard_fab2(sch_1):p3e_cpu1_pe3_mp_rxn(13)" )
			)
			( signal "P3E_CPU1_PE3_MP_RXN<14>"
				( objectStatus "@baseboard_fab2_lib.baseboard_fab2(sch_1):p3e_cpu1_pe3_mp_rxn(14)" )
			)
			( signal "P3E_CPU1_PE3_MP_RXN<15>"
				( objectStatus "@baseboard_fab2_lib.baseboard_fab2(sch_1):p3e_cpu1_pe3_mp_rxn(15)" )
			)
			( signal "P3E_CPU1_PE3_MP_RXP<0>"
				( objectStatus "@baseboard_fab2_lib.baseboard_fab2(sch_1):p3e_cpu1_pe3_mp_rxp(0)" )
			)
			( signal "P3E_CPU1_PE3_MP_RXP<1>"
				( objectStatus "@baseboard_fab2_lib.baseboard_fab2(sch_1):p3e_cpu1_pe3_mp_rxp(1)" )
			)
			( signal "P3E_CPU1_PE3_MP_RXP<2>"
				( objectStatus "@baseboard_fab2_lib.baseboard_fab2(sch_1):p3e_cpu1_pe3_mp_rxp(2)" )
			)
			( signal "P3E_CPU1_PE3_MP_RXP<3>"
				( objectStatus "@baseboard_fab2_lib.baseboard_fab2(sch_1):p3e_cpu1_pe3_mp_rxp(3)" )
			)
			( signal "P3E_CPU1_PE3_MP_RXP<4>"
				( objectStatus "@baseboard_fab2_lib.baseboard_fab2(sch_1):p3e_cpu1_pe3_mp_rxp(4)" )
			)
			( signal "P3E_CPU1_PE3_MP_RXP<5>"
				( objectStatus "@baseboard_fab2_lib.baseboard_fab2(sch_1):p3e_cpu1_pe3_mp_rxp(5)" )
			)
			( signal "P3E_CPU1_PE3_MP_RXP<6>"
				( objectStatus "@baseboard_fab2_lib.baseboard_fab2(sch_1):p3e_cpu1_pe3_mp_rxp(6)" )
			)
			( signal "P3E_CPU1_PE3_MP_RXP<7>"
				( objectStatus "@baseboard_fab2_lib.baseboard_fab2(sch_1):p3e_cpu1_pe3_mp_rxp(7)" )
			)
			( signal "P3E_CPU1_PE3_MP_RXP<8>"
				( objectStatus "@baseboard_fab2_lib.baseboard_fab2(sch_1):p3e_cpu1_pe3_mp_rxp(8)" )
			)
			( signal "P3E_CPU1_PE3_MP_RXP<9>"
				( objectStatus "@baseboard_fab2_lib.baseboard_fab2(sch_1):p3e_cpu1_pe3_mp_rxp(9)" )
			)
			( signal "P3E_CPU1_PE3_MP_RXP<10>"
				( objectStatus "@baseboard_fab2_lib.baseboard_fab2(sch_1):p3e_cpu1_pe3_mp_rxp(10)" )
			)
			( signal "P3E_CPU1_PE3_MP_RXP<11>"
				( objectStatus "@baseboard_fab2_lib.baseboard_fab2(sch_1):p3e_cpu1_pe3_mp_rxp(11)" )
			)
			( signal "P3E_CPU1_PE3_MP_RXP<12>"
				( objectStatus "@baseboard_fab2_lib.baseboard_fab2(sch_1):p3e_cpu1_pe3_mp_rxp(12)" )
			)
			( signal "P3E_CPU1_PE3_MP_RXP<13>"
				( objectStatus "@baseboard_fab2_lib.baseboard_fab2(sch_1):p3e_cpu1_pe3_mp_rxp(13)" )
			)
			( signal "P3E_CPU1_PE3_MP_RXP<14>"
				( objectStatus "@baseboard_fab2_lib.baseboard_fab2(sch_1):p3e_cpu1_pe3_mp_rxp(14)" )
			)
			( signal "P3E_CPU1_PE3_MP_RXP<15>"
				( objectStatus "@baseboard_fab2_lib.baseboard_fab2(sch_1):p3e_cpu1_pe3_mp_rxp(15)" )
			)
			( signal "P3E_CPU1_PE3_MP_TXN<0>"
				( objectStatus "@baseboard_fab2_lib.baseboard_fab2(sch_1):p3e_cpu1_pe3_mp_txn(0)" )
			)
			( signal "P3E_CPU1_PE3_MP_TXN<1>"
				( objectStatus "@baseboard_fab2_lib.baseboard_fab2(sch_1):p3e_cpu1_pe3_mp_txn(1)" )
			)
			( signal "P3E_CPU1_PE3_MP_TXN<2>"
				( objectStatus "@baseboard_fab2_lib.baseboard_fab2(sch_1):p3e_cpu1_pe3_mp_txn(2)" )
			)
			( signal "P3E_CPU1_PE3_MP_TXN<3>"
				( objectStatus "@baseboard_fab2_lib.baseboard_fab2(sch_1):p3e_cpu1_pe3_mp_txn(3)" )
			)
			( signal "P3E_CPU1_PE3_MP_TXN<4>"
				( objectStatus "@baseboard_fab2_lib.baseboard_fab2(sch_1):p3e_cpu1_pe3_mp_txn(4)" )
			)
			( signal "P3E_CPU1_PE3_MP_TXN<5>"
				( objectStatus "@baseboard_fab2_lib.baseboard_fab2(sch_1):p3e_cpu1_pe3_mp_txn(5)" )
			)
			( signal "P3E_CPU1_PE3_MP_TXN<6>"
				( objectStatus "@baseboard_fab2_lib.baseboard_fab2(sch_1):p3e_cpu1_pe3_mp_txn(6)" )
			)
			( signal "P3E_CPU1_PE3_MP_TXN<7>"
				( objectStatus "@baseboard_fab2_lib.baseboard_fab2(sch_1):p3e_cpu1_pe3_mp_txn(7)" )
			)
			( signal "P3E_CPU1_PE3_MP_TXN<8>"
				( objectStatus "@baseboard_fab2_lib.baseboard_fab2(sch_1):p3e_cpu1_pe3_mp_txn(8)" )
			)
			( signal "P3E_CPU1_PE3_MP_TXN<9>"
				( objectStatus "@baseboard_fab2_lib.baseboard_fab2(sch_1):p3e_cpu1_pe3_mp_txn(9)" )
			)
			( signal "P3E_CPU1_PE3_MP_TXN<10>"
				( objectStatus "@baseboard_fab2_lib.baseboard_fab2(sch_1):p3e_cpu1_pe3_mp_txn(10)" )
			)
			( signal "P3E_CPU1_PE3_MP_TXN<11>"
				( objectStatus "@baseboard_fab2_lib.baseboard_fab2(sch_1):p3e_cpu1_pe3_mp_txn(11)" )
			)
			( signal "P3E_CPU1_PE3_MP_TXN<12>"
				( objectStatus "@baseboard_fab2_lib.baseboard_fab2(sch_1):p3e_cpu1_pe3_mp_txn(12)" )
			)
			( signal "P3E_CPU1_PE3_MP_TXN<13>"
				( objectStatus "@baseboard_fab2_lib.baseboard_fab2(sch_1):p3e_cpu1_pe3_mp_txn(13)" )
			)
			( signal "P3E_CPU1_PE3_MP_TXN<14>"
				( objectStatus "@baseboard_fab2_lib.baseboard_fab2(sch_1):p3e_cpu1_pe3_mp_txn(14)" )
			)
			( signal "P3E_CPU1_PE3_MP_TXN<15>"
				( objectStatus "@baseboard_fab2_lib.baseboard_fab2(sch_1):p3e_cpu1_pe3_mp_txn(15)" )
			)
			( signal "P3E_CPU1_PE3_MP_TXP<0>"
				( objectStatus "@baseboard_fab2_lib.baseboard_fab2(sch_1):p3e_cpu1_pe3_mp_txp(0)" )
			)
			( signal "P3E_CPU1_PE3_MP_TXP<1>"
				( objectStatus "@baseboard_fab2_lib.baseboard_fab2(sch_1):p3e_cpu1_pe3_mp_txp(1)" )
			)
			( signal "P3E_CPU1_PE3_MP_TXP<2>"
				( objectStatus "@baseboard_fab2_lib.baseboard_fab2(sch_1):p3e_cpu1_pe3_mp_txp(2)" )
			)
			( signal "P3E_CPU1_PE3_MP_TXP<3>"
				( objectStatus "@baseboard_fab2_lib.baseboard_fab2(sch_1):p3e_cpu1_pe3_mp_txp(3)" )
			)
			( signal "P3E_CPU1_PE3_MP_TXP<4>"
				( objectStatus "@baseboard_fab2_lib.baseboard_fab2(sch_1):p3e_cpu1_pe3_mp_txp(4)" )
			)
			( signal "P3E_CPU1_PE3_MP_TXP<5>"
				( objectStatus "@baseboard_fab2_lib.baseboard_fab2(sch_1):p3e_cpu1_pe3_mp_txp(5)" )
			)
			( signal "P3E_CPU1_PE3_MP_TXP<6>"
				( objectStatus "@baseboard_fab2_lib.baseboard_fab2(sch_1):p3e_cpu1_pe3_mp_txp(6)" )
			)
			( signal "P3E_CPU1_PE3_MP_TXP<7>"
				( objectStatus "@baseboard_fab2_lib.baseboard_fab2(sch_1):p3e_cpu1_pe3_mp_txp(7)" )
			)
			( signal "P3E_CPU1_PE3_MP_TXP<8>"
				( objectStatus "@baseboard_fab2_lib.baseboard_fab2(sch_1):p3e_cpu1_pe3_mp_txp(8)" )
			)
			( signal "P3E_CPU1_PE3_MP_TXP<9>"
				( objectStatus "@baseboard_fab2_lib.baseboard_fab2(sch_1):p3e_cpu1_pe3_mp_txp(9)" )
			)
			( signal "P3E_CPU1_PE3_MP_TXP<10>"
				( objectStatus "@baseboard_fab2_lib.baseboard_fab2(sch_1):p3e_cpu1_pe3_mp_txp(10)" )
			)
			( signal "P3E_CPU1_PE3_MP_TXP<11>"
				( objectStatus "@baseboard_fab2_lib.baseboard_fab2(sch_1):p3e_cpu1_pe3_mp_txp(11)" )
			)
			( signal "P3E_CPU1_PE3_MP_TXP<12>"
				( objectStatus "@baseboard_fab2_lib.baseboard_fab2(sch_1):p3e_cpu1_pe3_mp_txp(12)" )
			)
			( signal "P3E_CPU1_PE3_MP_TXP<13>"
				( objectStatus "@baseboard_fab2_lib.baseboard_fab2(sch_1):p3e_cpu1_pe3_mp_txp(13)" )
			)
			( signal "P3E_CPU1_PE3_MP_TXP<14>"
				( objectStatus "@baseboard_fab2_lib.baseboard_fab2(sch_1):p3e_cpu1_pe3_mp_txp(14)" )
			)
			( signal "P3E_CPU1_PE3_MP_TXP<15>"
				( objectStatus "@baseboard_fab2_lib.baseboard_fab2(sch_1):p3e_cpu1_pe3_mp_txp(15)" )
			)
			( signal "TP_CPU1_UPI2_RSVD_CA12"
				( objectStatus "@baseboard_fab2_lib.baseboard_fab2(sch_1):tp_cpu1_upi2_rsvd_ca12" )
			)
			( signal "TP_CPU1_UPI2_RSVD_CB11"
				( objectStatus "@baseboard_fab2_lib.baseboard_fab2(sch_1):tp_cpu1_upi2_rsvd_cb11" )
			)
			( signal "TP_CPU1_UPI2_RSVD_CC10"
				( objectStatus "@baseboard_fab2_lib.baseboard_fab2(sch_1):tp_cpu1_upi2_rsvd_cc10" )
			)
			( signal "TP_CPU1_UPI2_RSVD_CC12"
				( objectStatus "@baseboard_fab2_lib.baseboard_fab2(sch_1):tp_cpu1_upi2_rsvd_cc12" )
			)
			( signal "TP_CPU1_UPI2_RSVD_CD11"
				( objectStatus "@baseboard_fab2_lib.baseboard_fab2(sch_1):tp_cpu1_upi2_rsvd_cd11" )
			)
			( signal "TP_CPU1_UPI2_RSVD_CE12"
				( objectStatus "@baseboard_fab2_lib.baseboard_fab2(sch_1):tp_cpu1_upi2_rsvd_ce12" )
			)
			( signal "TP_CPU1_UPI2_RSVD_CF11"
				( objectStatus "@baseboard_fab2_lib.baseboard_fab2(sch_1):tp_cpu1_upi2_rsvd_cf11" )
			)
			( signal "TP_CPU1_UPI2_RSVD_CF13"
				( objectStatus "@baseboard_fab2_lib.baseboard_fab2(sch_1):tp_cpu1_upi2_rsvd_cf13" )
			)
			( signal "TP_CPU1_UPI2_RSVD_CG12"
				( objectStatus "@baseboard_fab2_lib.baseboard_fab2(sch_1):tp_cpu1_upi2_rsvd_cg12" )
			)
			( signal "TP_CPU1_UPI2_RSVD_CH11"
				( objectStatus "@baseboard_fab2_lib.baseboard_fab2(sch_1):tp_cpu1_upi2_rsvd_ch11" )
			)
			( signal "TP_CPU1_UPI2_RSVD_CH13"
				( objectStatus "@baseboard_fab2_lib.baseboard_fab2(sch_1):tp_cpu1_upi2_rsvd_ch13" )
			)
			( signal "TP_CPU1_UPI2_RSVD_CJ14"
				( objectStatus "@baseboard_fab2_lib.baseboard_fab2(sch_1):tp_cpu1_upi2_rsvd_cj14" )
			)
			( signal "TP_CPU1_UPI2_RSVD_CK13"
				( objectStatus "@baseboard_fab2_lib.baseboard_fab2(sch_1):tp_cpu1_upi2_rsvd_ck13" )
			)
			( signal "TP_CPU1_UPI2_RSVD_CM13"
				( objectStatus "@baseboard_fab2_lib.baseboard_fab2(sch_1):tp_cpu1_upi2_rsvd_cm13" )
			)
			( signal "TP_CPU1_UPI2_RSVD_CR14"
				( objectStatus "@baseboard_fab2_lib.baseboard_fab2(sch_1):tp_cpu1_upi2_rsvd_cr14" )
			)
			( signal "TP_CPU1_UPI2_RSVD_CU14"
				( objectStatus "@baseboard_fab2_lib.baseboard_fab2(sch_1):tp_cpu1_upi2_rsvd_cu14" )
			)
			( signal "TP_CPU1_UPI2_RSVD_CV13"
				( objectStatus "@baseboard_fab2_lib.baseboard_fab2(sch_1):tp_cpu1_upi2_rsvd_cv13" )
			)
			( signal "TP_CPU1_UPI2_RSVD_CW14"
				( objectStatus "@baseboard_fab2_lib.baseboard_fab2(sch_1):tp_cpu1_upi2_rsvd_cw14" )
			)
			( signal "TP_CPU1_UPI2_RSVD_CW16"
				( objectStatus "@baseboard_fab2_lib.baseboard_fab2(sch_1):tp_cpu1_upi2_rsvd_cw16" )
			)
			( signal "TP_CPU1_UPI2_RSVD_DA16"
				( objectStatus "@baseboard_fab2_lib.baseboard_fab2(sch_1):tp_cpu1_upi2_rsvd_da16" )
			)
			( signal "TP_CPU1_UPI2_RSVD_DB15"
				( objectStatus "@baseboard_fab2_lib.baseboard_fab2(sch_1):tp_cpu1_upi2_rsvd_db15" )
			)
			( signal "TP_CPU1_UPI2_RSVD_DC16"
				( objectStatus "@baseboard_fab2_lib.baseboard_fab2(sch_1):tp_cpu1_upi2_rsvd_dc16" )
			)
			( signal "TP_CPU1_UPI2_RSVD_DD15"
				( objectStatus "@baseboard_fab2_lib.baseboard_fab2(sch_1):tp_cpu1_upi2_rsvd_dd15" )
			)
			( signal "TP_CPU1_UPI2_RSVD_DD17"
				( objectStatus "@baseboard_fab2_lib.baseboard_fab2(sch_1):tp_cpu1_upi2_rsvd_dd17" )
			)
			( signal "TP_CPU1_UPI2_RSVD_DE16"
				( objectStatus "@baseboard_fab2_lib.baseboard_fab2(sch_1):tp_cpu1_upi2_rsvd_de16" )
			)
			( signal "TP_CPU1_UPI2_RSVD_DF15"
				( objectStatus "@baseboard_fab2_lib.baseboard_fab2(sch_1):tp_cpu1_upi2_rsvd_df15" )
			)
			( signal "TP_CPU1_UPI2_RSVD_DF17"
				( objectStatus "@baseboard_fab2_lib.baseboard_fab2(sch_1):tp_cpu1_upi2_rsvd_df17" )
			)
			( signal "TP_CPU1_UPI2_RSVD_DG18"
				( objectStatus "@baseboard_fab2_lib.baseboard_fab2(sch_1):tp_cpu1_upi2_rsvd_dg18" )
			)
			( signal "TP_CPU1_UPI2_RSVD_DG20"
				( objectStatus "@baseboard_fab2_lib.baseboard_fab2(sch_1):tp_cpu1_upi2_rsvd_dg20" )
			)
			( signal "TP_CPU1_UPI2_RSVD_DH17"
				( objectStatus "@baseboard_fab2_lib.baseboard_fab2(sch_1):tp_cpu1_upi2_rsvd_dh17" )
			)
			( signal "TP_CPU1_UPI2_RSVD_DH19"
				( objectStatus "@baseboard_fab2_lib.baseboard_fab2(sch_1):tp_cpu1_upi2_rsvd_dh19" )
			)
			( signal "TP_CPU1_UPI2_RSVD_DJ18"
				( objectStatus "@baseboard_fab2_lib.baseboard_fab2(sch_1):tp_cpu1_upi2_rsvd_dj18" )
			)
			( signal "TP_CPU1_UPI2_RSVD_DJ20"
				( objectStatus "@baseboard_fab2_lib.baseboard_fab2(sch_1):tp_cpu1_upi2_rsvd_dj20" )
			)
			( signal "TP_CPU1_UPI2_RSVD_DK17"
				( objectStatus "@baseboard_fab2_lib.baseboard_fab2(sch_1):tp_cpu1_upi2_rsvd_dk17" )
			)
			( signal "TP_CPU1_UPI2_RSVD_DK19"
				( objectStatus "@baseboard_fab2_lib.baseboard_fab2(sch_1):tp_cpu1_upi2_rsvd_dk19" )
			)
			( signal "TP_CPU1_UPI2_RSVD_DL20"
				( objectStatus "@baseboard_fab2_lib.baseboard_fab2(sch_1):tp_cpu1_upi2_rsvd_dl20" )
			)
			( signal "TP_CPU1_UPI2_RSVD_DM21"
				( objectStatus "@baseboard_fab2_lib.baseboard_fab2(sch_1):tp_cpu1_upi2_rsvd_dm21" )
			)
			( signal "TP_CPU1_UPI2_RSVD_DN20"
				( objectStatus "@baseboard_fab2_lib.baseboard_fab2(sch_1):tp_cpu1_upi2_rsvd_dn20" )
			)
			( signal "TP_CPU1_UPI2_RSVD_DP21"
				( objectStatus "@baseboard_fab2_lib.baseboard_fab2(sch_1):tp_cpu1_upi2_rsvd_dp21" )
			)
			( signal "TP_CPU1_UPI2_RSVD_DT21"
				( objectStatus "@baseboard_fab2_lib.baseboard_fab2(sch_1):tp_cpu1_upi2_rsvd_dt21" )
			)
			( signal "CLK_100M_CPU1_RC_REFCLK1_DN"
				( objectStatus "@baseboard_fab2_lib.baseboard_fab2(sch_1):clk_100m_cpu1_rc_refclk1_dn" )
			)
			( signal "CLK_100M_CPU1_RC_REFCLK1_DP"
				( objectStatus "@baseboard_fab2_lib.baseboard_fab2(sch_1):clk_100m_cpu1_rc_refclk1_dp" )
			)
			( signal "TP_CPU1_RSVD_100"
				( objectStatus "@baseboard_fab2_lib.baseboard_fab2(sch_1):tp_cpu1_rsvd_100" )
			)
			( signal "TP_CPU1_RSVD_101"
				( objectStatus "@baseboard_fab2_lib.baseboard_fab2(sch_1):tp_cpu1_rsvd_101" )
			)
			( signal "TP_CPU1_RSVD_105"
				( objectStatus "@baseboard_fab2_lib.baseboard_fab2(sch_1):tp_cpu1_rsvd_105" )
			)
			( signal "TP_CPU1_RSVD_106"
				( objectStatus "@baseboard_fab2_lib.baseboard_fab2(sch_1):tp_cpu1_rsvd_106" )
			)
			( signal "TP_CPU1_RSVD_108"
				( objectStatus "@baseboard_fab2_lib.baseboard_fab2(sch_1):tp_cpu1_rsvd_108" )
			)
			( signal "TP_CPU1_RSVD_111"
				( objectStatus "@baseboard_fab2_lib.baseboard_fab2(sch_1):tp_cpu1_rsvd_111" )
			)
			( signal "TP_CPU1_RSVD_113"
				( objectStatus "@baseboard_fab2_lib.baseboard_fab2(sch_1):tp_cpu1_rsvd_113" )
			)
			( signal "TP_CPU1_RSVD_114"
				( objectStatus "@baseboard_fab2_lib.baseboard_fab2(sch_1):tp_cpu1_rsvd_114" )
			)
			( signal "TP_CPU1_RSVD_117"
				( objectStatus "@baseboard_fab2_lib.baseboard_fab2(sch_1):tp_cpu1_rsvd_117" )
			)
			( signal "TP_CPU1_RSVD_119"
				( objectStatus "@baseboard_fab2_lib.baseboard_fab2(sch_1):tp_cpu1_rsvd_119" )
			)
			( signal "TP_CPU1_RSVD_121"
				( objectStatus "@baseboard_fab2_lib.baseboard_fab2(sch_1):tp_cpu1_rsvd_121" )
			)
			( signal "TP_CPU1_RSVD_123"
				( objectStatus "@baseboard_fab2_lib.baseboard_fab2(sch_1):tp_cpu1_rsvd_123" )
			)
			( signal "TP_CPU1_RSVD_124"
				( objectStatus "@baseboard_fab2_lib.baseboard_fab2(sch_1):tp_cpu1_rsvd_124" )
			)
			( signal "TP_CPU1_RSVD_144"
				( objectStatus "@baseboard_fab2_lib.baseboard_fab2(sch_1):tp_cpu1_rsvd_144" )
			)
			( signal "TP_CPU1_RSVD_145"
				( objectStatus "@baseboard_fab2_lib.baseboard_fab2(sch_1):tp_cpu1_rsvd_145" )
			)
			( signal "TP_CPU1_RSVD_146"
				( objectStatus "@baseboard_fab2_lib.baseboard_fab2(sch_1):tp_cpu1_rsvd_146" )
			)
			( signal "TP_CPU1_RSVD_147"
				( objectStatus "@baseboard_fab2_lib.baseboard_fab2(sch_1):tp_cpu1_rsvd_147" )
			)
			( signal "TP_CPU1_RSVD_148"
				( objectStatus "@baseboard_fab2_lib.baseboard_fab2(sch_1):tp_cpu1_rsvd_148" )
			)
			( signal "TP_CPU1_RSVD_149"
				( objectStatus "@baseboard_fab2_lib.baseboard_fab2(sch_1):tp_cpu1_rsvd_149" )
			)
			( signal "TP_CPU1_RSVD_150"
				( objectStatus "@baseboard_fab2_lib.baseboard_fab2(sch_1):tp_cpu1_rsvd_150" )
			)
			( signal "TP_CPU1_RSVD_151"
				( objectStatus "@baseboard_fab2_lib.baseboard_fab2(sch_1):tp_cpu1_rsvd_151" )
			)
			( signal "TP_CPU1_RSVD_152"
				( objectStatus "@baseboard_fab2_lib.baseboard_fab2(sch_1):tp_cpu1_rsvd_152" )
			)
			( signal "TP_CPU1_RSVD_154"
				( objectStatus "@baseboard_fab2_lib.baseboard_fab2(sch_1):tp_cpu1_rsvd_154" )
			)
			( signal "TP_CPU1_RSVD_155"
				( objectStatus "@baseboard_fab2_lib.baseboard_fab2(sch_1):tp_cpu1_rsvd_155" )
			)
			( signal "TP_CPU1_RSVD_156"
				( objectStatus "@baseboard_fab2_lib.baseboard_fab2(sch_1):tp_cpu1_rsvd_156" )
			)
			( signal "TP_CPU1_RSVD_157"
				( objectStatus "@baseboard_fab2_lib.baseboard_fab2(sch_1):tp_cpu1_rsvd_157" )
			)
			( signal "TP_CPU1_RSVD_158"
				( objectStatus "@baseboard_fab2_lib.baseboard_fab2(sch_1):tp_cpu1_rsvd_158" )
			)
			( signal "TP_CPU1_RSVD_159"
				( objectStatus "@baseboard_fab2_lib.baseboard_fab2(sch_1):tp_cpu1_rsvd_159" )
			)
			( signal "TP_CPU1_RSVD_160"
				( objectStatus "@baseboard_fab2_lib.baseboard_fab2(sch_1):tp_cpu1_rsvd_160" )
			)
			( signal "TP_CPU1_RSVD_161"
				( objectStatus "@baseboard_fab2_lib.baseboard_fab2(sch_1):tp_cpu1_rsvd_161" )
			)
			( signal "TP_CPU1_RSVD_162"
				( objectStatus "@baseboard_fab2_lib.baseboard_fab2(sch_1):tp_cpu1_rsvd_162" )
			)
			( signal "TP_CPU1_RSVD_163"
				( objectStatus "@baseboard_fab2_lib.baseboard_fab2(sch_1):tp_cpu1_rsvd_163" )
			)
			( signal "TP_CPU1_RSVD_164"
				( objectStatus "@baseboard_fab2_lib.baseboard_fab2(sch_1):tp_cpu1_rsvd_164" )
			)
			( signal "TP_CPU1_RSVD_166"
				( objectStatus "@baseboard_fab2_lib.baseboard_fab2(sch_1):tp_cpu1_rsvd_166" )
			)
			( signal "TP_CPU1_RSVD_167"
				( objectStatus "@baseboard_fab2_lib.baseboard_fab2(sch_1):tp_cpu1_rsvd_167" )
			)
			( signal "TP_CPU1_RSVD_168"
				( objectStatus "@baseboard_fab2_lib.baseboard_fab2(sch_1):tp_cpu1_rsvd_168" )
			)
			( signal "TP_CPU1_RSVD_169"
				( objectStatus "@baseboard_fab2_lib.baseboard_fab2(sch_1):tp_cpu1_rsvd_169" )
			)
			( signal "TP_CPU1_RSVD_170"
				( objectStatus "@baseboard_fab2_lib.baseboard_fab2(sch_1):tp_cpu1_rsvd_170" )
			)
			( signal "TP_CPU1_RSVD_171"
				( objectStatus "@baseboard_fab2_lib.baseboard_fab2(sch_1):tp_cpu1_rsvd_171" )
			)
			( signal "TP_CPU1_RSVD_255"
				( objectStatus "@baseboard_fab2_lib.baseboard_fab2(sch_1):tp_cpu1_rsvd_255" )
			)
			( signal "TP_CPU1_RSVD_82"
				( objectStatus "@baseboard_fab2_lib.baseboard_fab2(sch_1):tp_cpu1_rsvd_82" )
			)
			( signal "TP_CPU1_RSVD_85"
				( objectStatus "@baseboard_fab2_lib.baseboard_fab2(sch_1):tp_cpu1_rsvd_85" )
			)
			( signal "TP_CPU1_RSVD_90"
				( objectStatus "@baseboard_fab2_lib.baseboard_fab2(sch_1):tp_cpu1_rsvd_90" )
			)
			( signal "TP_CPU1_RSVD_91"
				( objectStatus "@baseboard_fab2_lib.baseboard_fab2(sch_1):tp_cpu1_rsvd_91" )
			)
			( signal "TP_CPU1_RSVD_94"
				( objectStatus "@baseboard_fab2_lib.baseboard_fab2(sch_1):tp_cpu1_rsvd_94" )
			)
			( signal "TP_CPU1_RSVD_95"
				( objectStatus "@baseboard_fab2_lib.baseboard_fab2(sch_1):tp_cpu1_rsvd_95" )
			)
			( signal "TP_CPU1_RSVD_97"
				( objectStatus "@baseboard_fab2_lib.baseboard_fab2(sch_1):tp_cpu1_rsvd_97" )
			)
			( signal "TP_CPU1_RSVD_99"
				( objectStatus "@baseboard_fab2_lib.baseboard_fab2(sch_1):tp_cpu1_rsvd_99" )
			)
			( signal "TP_CPU1_TEST_10"
				( objectStatus "@baseboard_fab2_lib.baseboard_fab2(sch_1):tp_cpu1_test_10" )
			)
			( signal "TP_CPU1_TEST_6"
				( objectStatus "@baseboard_fab2_lib.baseboard_fab2(sch_1):tp_cpu1_test_6" )
			)
			( signal "TP_CPU1_TEST_7"
				( objectStatus "@baseboard_fab2_lib.baseboard_fab2(sch_1):tp_cpu1_test_7" )
			)
			( signal "TP_CPU1_TEST_8"
				( objectStatus "@baseboard_fab2_lib.baseboard_fab2(sch_1):tp_cpu1_test_8" )
			)
			( signal "TP_CPU1_TEST_9"
				( objectStatus "@baseboard_fab2_lib.baseboard_fab2(sch_1):tp_cpu1_test_9" )
			)
			( signal "PVCCIN_CPU1"
				( attribute "VOLTAGE" "2.0V"
					( Units "uVoltage" "V" 1.000000)
					( Status sAliasFlattened )
					( Origin gFrontEnd )
				)
				( objectStatus "@baseboard_fab2_lib.baseboard_fab2(sch_1):pvccin_cpu1" )
			)
			( signal "VSENSE_PMAX_CPU1"
				( objectStatus "@baseboard_fab2_lib.baseboard_fab2(sch_1):vsense_pmax_cpu1" )
			)
			( signal "VSENSE_PVCCIN_CPU1_SKT_VRTN"
				( objectStatus "@baseboard_fab2_lib.baseboard_fab2(sch_1):vsense_pvccin_cpu1_skt_vrtn" )
			)
			( signal "VSENSE_PVCCIN_CPU1_SKT_VSEN"
				( objectStatus "@baseboard_fab2_lib.baseboard_fab2(sch_1):vsense_pvccin_cpu1_skt_vsen" )
			)
			( signal "VSENSE_VCCINR2PMAX_CPU1"
				( objectStatus "@baseboard_fab2_lib.baseboard_fab2(sch_1):vsense_vccinr2pmax_cpu1" )
			)
			( signal "PVCCIOMCP_CPU1"
				( attribute "VOLTAGE" "+0.95V"
					( Units "uVoltage" "V" 1.000000)
					( Status sAliasFlattened )
					( Status sAliasConflict )
					( Origin gFrontEnd )
				)
				( objectStatus "@baseboard_fab2_lib.baseboard_fab2(sch_1):pvcciomcp_cpu1" )
			)
			( signal "PVDDQ_GHJ"
				( attribute "VOLTAGE" "1.2V"
					( Units "uVoltage" "V" 1.000000)
					( Status sAliasFlattened )
					( Origin gFrontEnd )
				)
				( objectStatus "@baseboard_fab2_lib.baseboard_fab2(sch_1):pvddq_ghj" )
			)
			( signal "PVDDQ_KLM"
				( attribute "VOLTAGE" "1.2V"
					( Units "uVoltage" "V" 1.000000)
					( Status sAliasFlattened )
					( Origin gFrontEnd )
				)
				( objectStatus "@baseboard_fab2_lib.baseboard_fab2(sch_1):pvddq_klm" )
			)
			( signal "PVPP_GHJ"
				( attribute "VOLTAGE" "2.5V"
					( Units "uVoltage" "V" 1.000000)
					( Status sAliasFlattened )
					( Origin gFrontEnd )
				)
				( objectStatus "@baseboard_fab2_lib.baseboard_fab2(sch_1):pvpp_ghj" )
			)
			( signal "PVSA_CPU1"
				( attribute "VOLTAGE" "1.1V"
					( Units "uVoltage" "V" 1.000000)
					( Status sAliasFlattened )
					( Origin gFrontEnd )
				)
				( objectStatus "@baseboard_fab2_lib.baseboard_fab2(sch_1):pvsa_cpu1" )
			)
			( signal "PD_CPU1_MCP01_DMON"
				( objectStatus "@baseboard_fab2_lib.baseboard_fab2(sch_1):pd_cpu1_mcp01_dmon" )
			)
			( signal "TP_CPU1_KTI2_AMONV"
				( objectStatus "@baseboard_fab2_lib.baseboard_fab2(sch_1):tp_cpu1_kti2_amonv" )
			)
			( signal "TP_CPU1_KTI2_DFX_DN"
				( objectStatus "@baseboard_fab2_lib.baseboard_fab2(sch_1):tp_cpu1_kti2_dfx_dn" )
			)
			( signal "TP_CPU1_RSVD_0"
				( objectStatus "@baseboard_fab2_lib.baseboard_fab2(sch_1):tp_cpu1_rsvd_0" )
			)
			( signal "TP_CPU1_RSVD_1"
				( objectStatus "@baseboard_fab2_lib.baseboard_fab2(sch_1):tp_cpu1_rsvd_1" )
			)
			( signal "TP_CPU1_RSVD_10"
				( objectStatus "@baseboard_fab2_lib.baseboard_fab2(sch_1):tp_cpu1_rsvd_10" )
			)
			( signal "TP_CPU1_RSVD_11"
				( objectStatus "@baseboard_fab2_lib.baseboard_fab2(sch_1):tp_cpu1_rsvd_11" )
			)
			( signal "TP_CPU1_RSVD_12"
				( objectStatus "@baseboard_fab2_lib.baseboard_fab2(sch_1):tp_cpu1_rsvd_12" )
			)
			( signal "TP_CPU1_RSVD_13"
				( objectStatus "@baseboard_fab2_lib.baseboard_fab2(sch_1):tp_cpu1_rsvd_13" )
			)
			( signal "TP_CPU1_RSVD_14"
				( objectStatus "@baseboard_fab2_lib.baseboard_fab2(sch_1):tp_cpu1_rsvd_14" )
			)
			( signal "TP_CPU1_RSVD_15"
				( objectStatus "@baseboard_fab2_lib.baseboard_fab2(sch_1):tp_cpu1_rsvd_15" )
			)
			( signal "TP_CPU1_RSVD_16"
				( objectStatus "@baseboard_fab2_lib.baseboard_fab2(sch_1):tp_cpu1_rsvd_16" )
			)
			( signal "TP_CPU1_RSVD_17"
				( objectStatus "@baseboard_fab2_lib.baseboard_fab2(sch_1):tp_cpu1_rsvd_17" )
			)
			( signal "TP_CPU1_RSVD_18"
				( objectStatus "@baseboard_fab2_lib.baseboard_fab2(sch_1):tp_cpu1_rsvd_18" )
			)
			( signal "TP_CPU1_RSVD_19"
				( objectStatus "@baseboard_fab2_lib.baseboard_fab2(sch_1):tp_cpu1_rsvd_19" )
			)
			( signal "TP_CPU1_RSVD_2"
				( objectStatus "@baseboard_fab2_lib.baseboard_fab2(sch_1):tp_cpu1_rsvd_2" )
			)
			( signal "TP_CPU1_RSVD_20"
				( objectStatus "@baseboard_fab2_lib.baseboard_fab2(sch_1):tp_cpu1_rsvd_20" )
			)
			( signal "TP_CPU1_RSVD_21"
				( objectStatus "@baseboard_fab2_lib.baseboard_fab2(sch_1):tp_cpu1_rsvd_21" )
			)
			( signal "TP_CPU1_RSVD_22"
				( objectStatus "@baseboard_fab2_lib.baseboard_fab2(sch_1):tp_cpu1_rsvd_22" )
			)
			( signal "TP_CPU1_RSVD_23"
				( objectStatus "@baseboard_fab2_lib.baseboard_fab2(sch_1):tp_cpu1_rsvd_23" )
			)
			( signal "TP_CPU1_RSVD_24"
				( objectStatus "@baseboard_fab2_lib.baseboard_fab2(sch_1):tp_cpu1_rsvd_24" )
			)
			( signal "TP_CPU1_RSVD_25"
				( objectStatus "@baseboard_fab2_lib.baseboard_fab2(sch_1):tp_cpu1_rsvd_25" )
			)
			( signal "TP_CPU1_RSVD_26"
				( objectStatus "@baseboard_fab2_lib.baseboard_fab2(sch_1):tp_cpu1_rsvd_26" )
			)
			( signal "TP_CPU1_RSVD_27"
				( objectStatus "@baseboard_fab2_lib.baseboard_fab2(sch_1):tp_cpu1_rsvd_27" )
			)
			( signal "TP_CPU1_RSVD_28"
				( objectStatus "@baseboard_fab2_lib.baseboard_fab2(sch_1):tp_cpu1_rsvd_28" )
			)
			( signal "TP_CPU1_RSVD_29"
				( objectStatus "@baseboard_fab2_lib.baseboard_fab2(sch_1):tp_cpu1_rsvd_29" )
			)
			( signal "TP_CPU1_RSVD_3"
				( objectStatus "@baseboard_fab2_lib.baseboard_fab2(sch_1):tp_cpu1_rsvd_3" )
			)
			( signal "TP_CPU1_RSVD_30"
				( objectStatus "@baseboard_fab2_lib.baseboard_fab2(sch_1):tp_cpu1_rsvd_30" )
			)
			( signal "TP_CPU1_RSVD_31"
				( objectStatus "@baseboard_fab2_lib.baseboard_fab2(sch_1):tp_cpu1_rsvd_31" )
			)
			( signal "TP_CPU1_RSVD_32"
				( objectStatus "@baseboard_fab2_lib.baseboard_fab2(sch_1):tp_cpu1_rsvd_32" )
			)
			( signal "TP_CPU1_RSVD_33"
				( objectStatus "@baseboard_fab2_lib.baseboard_fab2(sch_1):tp_cpu1_rsvd_33" )
			)
			( signal "TP_CPU1_RSVD_34"
				( objectStatus "@baseboard_fab2_lib.baseboard_fab2(sch_1):tp_cpu1_rsvd_34" )
			)
			( signal "TP_CPU1_RSVD_35"
				( objectStatus "@baseboard_fab2_lib.baseboard_fab2(sch_1):tp_cpu1_rsvd_35" )
			)
			( signal "TP_CPU1_RSVD_36"
				( objectStatus "@baseboard_fab2_lib.baseboard_fab2(sch_1):tp_cpu1_rsvd_36" )
			)
			( signal "TP_CPU1_RSVD_37"
				( objectStatus "@baseboard_fab2_lib.baseboard_fab2(sch_1):tp_cpu1_rsvd_37" )
			)
			( signal "TP_CPU1_RSVD_38"
				( objectStatus "@baseboard_fab2_lib.baseboard_fab2(sch_1):tp_cpu1_rsvd_38" )
			)
			( signal "TP_CPU1_RSVD_39"
				( objectStatus "@baseboard_fab2_lib.baseboard_fab2(sch_1):tp_cpu1_rsvd_39" )
			)
			( signal "TP_CPU1_RSVD_4"
				( objectStatus "@baseboard_fab2_lib.baseboard_fab2(sch_1):tp_cpu1_rsvd_4" )
			)
			( signal "TP_CPU1_RSVD_40"
				( objectStatus "@baseboard_fab2_lib.baseboard_fab2(sch_1):tp_cpu1_rsvd_40" )
			)
			( signal "TP_CPU1_RSVD_41"
				( objectStatus "@baseboard_fab2_lib.baseboard_fab2(sch_1):tp_cpu1_rsvd_41" )
			)
			( signal "TP_CPU1_RSVD_42"
				( objectStatus "@baseboard_fab2_lib.baseboard_fab2(sch_1):tp_cpu1_rsvd_42" )
			)
			( signal "TP_CPU1_RSVD_43"
				( objectStatus "@baseboard_fab2_lib.baseboard_fab2(sch_1):tp_cpu1_rsvd_43" )
			)
			( signal "TP_CPU1_RSVD_44"
				( objectStatus "@baseboard_fab2_lib.baseboard_fab2(sch_1):tp_cpu1_rsvd_44" )
			)
			( signal "TP_CPU1_RSVD_45"
				( objectStatus "@baseboard_fab2_lib.baseboard_fab2(sch_1):tp_cpu1_rsvd_45" )
			)
			( signal "TP_CPU1_RSVD_46"
				( objectStatus "@baseboard_fab2_lib.baseboard_fab2(sch_1):tp_cpu1_rsvd_46" )
			)
			( signal "TP_CPU1_RSVD_47"
				( objectStatus "@baseboard_fab2_lib.baseboard_fab2(sch_1):tp_cpu1_rsvd_47" )
			)
			( signal "TP_CPU1_RSVD_48"
				( objectStatus "@baseboard_fab2_lib.baseboard_fab2(sch_1):tp_cpu1_rsvd_48" )
			)
			( signal "TP_CPU1_RSVD_49"
				( objectStatus "@baseboard_fab2_lib.baseboard_fab2(sch_1):tp_cpu1_rsvd_49" )
			)
			( signal "TP_CPU1_RSVD_5"
				( objectStatus "@baseboard_fab2_lib.baseboard_fab2(sch_1):tp_cpu1_rsvd_5" )
			)
			( signal "TP_CPU1_RSVD_50"
				( objectStatus "@baseboard_fab2_lib.baseboard_fab2(sch_1):tp_cpu1_rsvd_50" )
			)
			( signal "TP_CPU1_RSVD_51"
				( objectStatus "@baseboard_fab2_lib.baseboard_fab2(sch_1):tp_cpu1_rsvd_51" )
			)
			( signal "TP_CPU1_RSVD_53"
				( objectStatus "@baseboard_fab2_lib.baseboard_fab2(sch_1):tp_cpu1_rsvd_53" )
			)
			( signal "TP_CPU1_RSVD_54"
				( objectStatus "@baseboard_fab2_lib.baseboard_fab2(sch_1):tp_cpu1_rsvd_54" )
			)
			( signal "TP_CPU1_RSVD_55"
				( objectStatus "@baseboard_fab2_lib.baseboard_fab2(sch_1):tp_cpu1_rsvd_55" )
			)
			( signal "TP_CPU1_RSVD_56"
				( objectStatus "@baseboard_fab2_lib.baseboard_fab2(sch_1):tp_cpu1_rsvd_56" )
			)
			( signal "TP_CPU1_RSVD_57"
				( objectStatus "@baseboard_fab2_lib.baseboard_fab2(sch_1):tp_cpu1_rsvd_57" )
			)
			( signal "TP_CPU1_RSVD_59"
				( objectStatus "@baseboard_fab2_lib.baseboard_fab2(sch_1):tp_cpu1_rsvd_59" )
			)
			( signal "TP_CPU1_RSVD_6"
				( objectStatus "@baseboard_fab2_lib.baseboard_fab2(sch_1):tp_cpu1_rsvd_6" )
			)
			( signal "TP_CPU1_RSVD_60"
				( objectStatus "@baseboard_fab2_lib.baseboard_fab2(sch_1):tp_cpu1_rsvd_60" )
			)
			( signal "TP_CPU1_RSVD_61"
				( objectStatus "@baseboard_fab2_lib.baseboard_fab2(sch_1):tp_cpu1_rsvd_61" )
			)
			( signal "TP_CPU1_RSVD_64"
				( objectStatus "@baseboard_fab2_lib.baseboard_fab2(sch_1):tp_cpu1_rsvd_64" )
			)
			( signal "TP_CPU1_RSVD_66"
				( objectStatus "@baseboard_fab2_lib.baseboard_fab2(sch_1):tp_cpu1_rsvd_66" )
			)
			( signal "TP_CPU1_RSVD_67"
				( objectStatus "@baseboard_fab2_lib.baseboard_fab2(sch_1):tp_cpu1_rsvd_67" )
			)
			( signal "TP_CPU1_RSVD_69"
				( objectStatus "@baseboard_fab2_lib.baseboard_fab2(sch_1):tp_cpu1_rsvd_69" )
			)
			( signal "TP_CPU1_RSVD_7"
				( objectStatus "@baseboard_fab2_lib.baseboard_fab2(sch_1):tp_cpu1_rsvd_7" )
			)
			( signal "TP_CPU1_RSVD_70"
				( objectStatus "@baseboard_fab2_lib.baseboard_fab2(sch_1):tp_cpu1_rsvd_70" )
			)
			( signal "TP_CPU1_RSVD_72"
				( objectStatus "@baseboard_fab2_lib.baseboard_fab2(sch_1):tp_cpu1_rsvd_72" )
			)
			( signal "TP_CPU1_RSVD_73"
				( objectStatus "@baseboard_fab2_lib.baseboard_fab2(sch_1):tp_cpu1_rsvd_73" )
			)
			( signal "TP_CPU1_RSVD_8"
				( objectStatus "@baseboard_fab2_lib.baseboard_fab2(sch_1):tp_cpu1_rsvd_8" )
			)
			( signal "TP_CPU1_RSVD_9"
				( objectStatus "@baseboard_fab2_lib.baseboard_fab2(sch_1):tp_cpu1_rsvd_9" )
			)
			( signal "VSENSE_PVCCIO_CPU1_SKT_VRTN"
				( objectStatus "@baseboard_fab2_lib.baseboard_fab2(sch_1):vsense_pvccio_cpu1_skt_vrtn" )
			)
			( signal "VSENSE_PVCCIO_CPU1_SKT_VSEN"
				( objectStatus "@baseboard_fab2_lib.baseboard_fab2(sch_1):vsense_pvccio_cpu1_skt_vsen" )
			)
			( signal "VSENSE_PVCCIOMCP_CPU1_SKT_VRTN"
				( objectStatus "@baseboard_fab2_lib.baseboard_fab2(sch_1):vsense_pvcciomcp_cpu1_skt_vrtn" )
			)
			( signal "VSENSE_PVCCIOMCP_CPU1_SKT_VSEN"
				( objectStatus "@baseboard_fab2_lib.baseboard_fab2(sch_1):vsense_pvcciomcp_cpu1_skt_vsen" )
			)
			( signal "VSENSE_PVCCMCP_CPU1_SKT_VRTN"
				( objectStatus "@baseboard_fab2_lib.baseboard_fab2(sch_1):vsense_pvccmcp_cpu1_skt_vrtn" )
			)
			( signal "VSENSE_PVCCMCP_CPU1_SKT_VSEN"
				( objectStatus "@baseboard_fab2_lib.baseboard_fab2(sch_1):vsense_pvccmcp_cpu1_skt_vsen" )
			)
			( signal "VSENSE_PVSA_CPU1_SKT_VRTN"
				( objectStatus "@baseboard_fab2_lib.baseboard_fab2(sch_1):vsense_pvsa_cpu1_skt_vrtn" )
			)
			( signal "VSENSE_PVSA_CPU1_SKT_VSEN"
				( objectStatus "@baseboard_fab2_lib.baseboard_fab2(sch_1):vsense_pvsa_cpu1_skt_vsen" )
			)
			( signal "FM_ADR_COMPLETE_GHJ_N"
				( objectStatus "@baseboard_fab2_lib.baseboard_fab2(sch_1):fm_adr_complete_ghj_n" )
			)
			( signal "M_G_VREF"
				( objectStatus "@baseboard_fab2_lib.baseboard_fab2(sch_1):m_g_vref" )
			)
			( signal "P12V_NVDIMM_GHJ"
				( attribute "VOLTAGE" "12.0"
					( Units "uVoltage" "V" 1.000000)
					( Status sAliasFlattened )
					( Origin gFrontEnd )
				)
				( objectStatus "@baseboard_fab2_lib.baseboard_fab2(sch_1):p12v_nvdimm_ghj" )
			)
			( signal "PVTT_GHJ"
				( attribute "VOLTAGE" "0.6V"
					( Units "uVoltage" "V" 1.000000)
					( Status sAliasFlattened )
					( Origin gFrontEnd )
				)
				( objectStatus "@baseboard_fab2_lib.baseboard_fab2(sch_1):pvtt_ghj" )
			)
			( signal "SMB_DDR_GHJ_VPP_SCL"
				( objectStatus "@baseboard_fab2_lib.baseboard_fab2(sch_1):smb_ddr_ghj_vpp_scl" )
			)
			( signal "SMB_DDR_GHJ_VPP_SDA"
				( objectStatus "@baseboard_fab2_lib.baseboard_fab2(sch_1):smb_ddr_ghj_vpp_sda" )
			)
			( signal "TP_CH_G_DIMM_G0_RFU_0"
				( objectStatus "@baseboard_fab2_lib.baseboard_fab2(sch_1):tp_ch_g_dimm_g0_rfu_0" )
			)
			( signal "TP_CH_G_DIMM_G0_RFU_1"
				( objectStatus "@baseboard_fab2_lib.baseboard_fab2(sch_1):tp_ch_g_dimm_g0_rfu_1" )
			)
			( signal "TP_CH_G_DIMM_G0_RFU_2"
				( objectStatus "@baseboard_fab2_lib.baseboard_fab2(sch_1):tp_ch_g_dimm_g0_rfu_2" )
			)
			( signal "TP_CH_G_DIMM0_RFU_0"
				( objectStatus "@baseboard_fab2_lib.baseboard_fab2(sch_1):tp_ch_g_dimm0_rfu_0" )
			)
			( signal "TP_CH_G_DIMM0_RFU_1"
				( objectStatus "@baseboard_fab2_lib.baseboard_fab2(sch_1):tp_ch_g_dimm0_rfu_1" )
			)
			( signal "TP_CH_G_DIMM0_RFU_2"
				( objectStatus "@baseboard_fab2_lib.baseboard_fab2(sch_1):tp_ch_g_dimm0_rfu_2" )
			)
			( signal "M_H_VREF"
				( objectStatus "@baseboard_fab2_lib.baseboard_fab2(sch_1):m_h_vref" )
			)
			( signal "TP_CH_H_DIMM_H0_RFU_0"
				( objectStatus "@baseboard_fab2_lib.baseboard_fab2(sch_1):tp_ch_h_dimm_h0_rfu_0" )
			)
			( signal "TP_CH_H_DIMM_H0_RFU_1"
				( objectStatus "@baseboard_fab2_lib.baseboard_fab2(sch_1):tp_ch_h_dimm_h0_rfu_1" )
			)
			( signal "TP_CH_H_DIMM_H0_RFU_2"
				( objectStatus "@baseboard_fab2_lib.baseboard_fab2(sch_1):tp_ch_h_dimm_h0_rfu_2" )
			)
			( signal "TP_CH_H_DIMM0_RFU_0"
				( objectStatus "@baseboard_fab2_lib.baseboard_fab2(sch_1):tp_ch_h_dimm0_rfu_0" )
			)
			( signal "TP_CH_H_DIMM0_RFU_1"
				( objectStatus "@baseboard_fab2_lib.baseboard_fab2(sch_1):tp_ch_h_dimm0_rfu_1" )
			)
			( signal "TP_CH_H_DIMM0_RFU_2"
				( objectStatus "@baseboard_fab2_lib.baseboard_fab2(sch_1):tp_ch_h_dimm0_rfu_2" )
			)
			( signal "M_J_VREF"
				( objectStatus "@baseboard_fab2_lib.baseboard_fab2(sch_1):m_j_vref" )
			)
			( signal "TP_CH_J_DIMM_J0_RFU_0"
				( objectStatus "@baseboard_fab2_lib.baseboard_fab2(sch_1):tp_ch_j_dimm_j0_rfu_0" )
			)
			( signal "TP_CH_J_DIMM_J0_RFU_1"
				( objectStatus "@baseboard_fab2_lib.baseboard_fab2(sch_1):tp_ch_j_dimm_j0_rfu_1" )
			)
			( signal "TP_CH_J_DIMM_J0_RFU_2"
				( objectStatus "@baseboard_fab2_lib.baseboard_fab2(sch_1):tp_ch_j_dimm_j0_rfu_2" )
			)
			( signal "TP_CH_J_DIMM_J1_RFU_0"
				( objectStatus "@baseboard_fab2_lib.baseboard_fab2(sch_1):tp_ch_j_dimm_j1_rfu_0" )
			)
			( signal "TP_CH_J_DIMM_J1_RFU_1"
				( objectStatus "@baseboard_fab2_lib.baseboard_fab2(sch_1):tp_ch_j_dimm_j1_rfu_1" )
			)
			( signal "TP_CH_J_DIMM_J1_RFU_2"
				( objectStatus "@baseboard_fab2_lib.baseboard_fab2(sch_1):tp_ch_j_dimm_j1_rfu_2" )
			)
			( signal "FM_ADR_COMPLETE_KLM_N"
				( objectStatus "@baseboard_fab2_lib.baseboard_fab2(sch_1):fm_adr_complete_klm_n" )
			)
			( signal "M_K_VREF"
				( objectStatus "@baseboard_fab2_lib.baseboard_fab2(sch_1):m_k_vref" )
			)
			( signal "P12V_NVDIMM_KLM"
				( attribute "VOLTAGE" "12.0"
					( Units "uVoltage" "V" 1.000000)
					( Status sAliasFlattened )
					( Origin gFrontEnd )
				)
				( objectStatus "@baseboard_fab2_lib.baseboard_fab2(sch_1):p12v_nvdimm_klm" )
			)
			( signal "PVPP_KLM"
				( attribute "VOLTAGE" "2.5V"
					( Units "uVoltage" "V" 1.000000)
					( Status sAliasFlattened )
					( Origin gFrontEnd )
				)
				( objectStatus "@baseboard_fab2_lib.baseboard_fab2(sch_1):pvpp_klm" )
			)
			( signal "PVTT_KLM"
				( attribute "VOLTAGE" "0.6V"
					( Units "uVoltage" "V" 1.000000)
					( Status sAliasFlattened )
					( Origin gFrontEnd )
				)
				( objectStatus "@baseboard_fab2_lib.baseboard_fab2(sch_1):pvtt_klm" )
			)
			( signal "SMB_DDR_KLM_VPP_SCL"
				( objectStatus "@baseboard_fab2_lib.baseboard_fab2(sch_1):smb_ddr_klm_vpp_scl" )
			)
			( signal "SMB_DDR_KLM_VPP_SDA"
				( objectStatus "@baseboard_fab2_lib.baseboard_fab2(sch_1):smb_ddr_klm_vpp_sda" )
			)
			( signal "TP_CH_K_DIMM_K0_RFU_0"
				( objectStatus "@baseboard_fab2_lib.baseboard_fab2(sch_1):tp_ch_k_dimm_k0_rfu_0" )
			)
			( signal "TP_CH_K_DIMM_K0_RFU_1"
				( objectStatus "@baseboard_fab2_lib.baseboard_fab2(sch_1):tp_ch_k_dimm_k0_rfu_1" )
			)
			( signal "TP_CH_K_DIMM_K0_RFU_2"
				( objectStatus "@baseboard_fab2_lib.baseboard_fab2(sch_1):tp_ch_k_dimm_k0_rfu_2" )
			)
			( signal "TP_CH_K_DIMM0_RFU_0"
				( objectStatus "@baseboard_fab2_lib.baseboard_fab2(sch_1):tp_ch_k_dimm0_rfu_0" )
			)
			( signal "TP_CH_K_DIMM0_RFU_1"
				( objectStatus "@baseboard_fab2_lib.baseboard_fab2(sch_1):tp_ch_k_dimm0_rfu_1" )
			)
			( signal "TP_CH_K_DIMM0_RFU_2"
				( objectStatus "@baseboard_fab2_lib.baseboard_fab2(sch_1):tp_ch_k_dimm0_rfu_2" )
			)
			( signal "M_L_VREF"
				( objectStatus "@baseboard_fab2_lib.baseboard_fab2(sch_1):m_l_vref" )
			)
			( signal "TP_CH_L_DIMM_L0_RFU_0"
				( objectStatus "@baseboard_fab2_lib.baseboard_fab2(sch_1):tp_ch_l_dimm_l0_rfu_0" )
			)
			( signal "TP_CH_L_DIMM_L0_RFU_1"
				( objectStatus "@baseboard_fab2_lib.baseboard_fab2(sch_1):tp_ch_l_dimm_l0_rfu_1" )
			)
			( signal "TP_CH_L_DIMM_L0_RFU_2"
				( objectStatus "@baseboard_fab2_lib.baseboard_fab2(sch_1):tp_ch_l_dimm_l0_rfu_2" )
			)
			( signal "TP_CH_L_DIMM0_RFU_0"
				( objectStatus "@baseboard_fab2_lib.baseboard_fab2(sch_1):tp_ch_l_dimm0_rfu_0" )
			)
			( signal "TP_CH_L_DIMM0_RFU_1"
				( objectStatus "@baseboard_fab2_lib.baseboard_fab2(sch_1):tp_ch_l_dimm0_rfu_1" )
			)
			( signal "TP_CH_L_DIMM0_RFU_2"
				( objectStatus "@baseboard_fab2_lib.baseboard_fab2(sch_1):tp_ch_l_dimm0_rfu_2" )
			)
			( signal "M_M_VREF"
				( objectStatus "@baseboard_fab2_lib.baseboard_fab2(sch_1):m_m_vref" )
			)
			( signal "TP_CH_M_DIMM_M0_RFU_0"
				( objectStatus "@baseboard_fab2_lib.baseboard_fab2(sch_1):tp_ch_m_dimm_m0_rfu_0" )
			)
			( signal "TP_CH_M_DIMM_M0_RFU_1"
				( objectStatus "@baseboard_fab2_lib.baseboard_fab2(sch_1):tp_ch_m_dimm_m0_rfu_1" )
			)
			( signal "TP_CH_M_DIMM_M0_RFU_2"
				( objectStatus "@baseboard_fab2_lib.baseboard_fab2(sch_1):tp_ch_m_dimm_m0_rfu_2" )
			)
			( signal "TP_CH_M_DIMM_M1_RFU_0"
				( objectStatus "@baseboard_fab2_lib.baseboard_fab2(sch_1):tp_ch_m_dimm_m1_rfu_0" )
			)
			( signal "TP_CH_M_DIMM_M1_RFU_1"
				( objectStatus "@baseboard_fab2_lib.baseboard_fab2(sch_1):tp_ch_m_dimm_m1_rfu_1" )
			)
			( signal "TP_CH_M_DIMM_M1_RFU_2"
				( objectStatus "@baseboard_fab2_lib.baseboard_fab2(sch_1):tp_ch_m_dimm_m1_rfu_2" )
			)
			( signal "FM_ADR_COMPLETE"
				( objectStatus "@baseboard_fab2_lib.baseboard_fab2(sch_1):fm_adr_complete" )
			)
			( signal "FM_ADR_COMPLETE_DLY"
				( objectStatus "@baseboard_fab2_lib.baseboard_fab2(sch_1):fm_adr_complete_dly" )
			)
			( signal "FM_ADR_COMPLETE_R"
				( objectStatus "@baseboard_fab2_lib.baseboard_fab2(sch_1):fm_adr_complete_r" )
			)
			( signal "FM_ADR_SMI_GPIO_N"
				( objectStatus "@baseboard_fab2_lib.baseboard_fab2(sch_1):fm_adr_smi_gpio_n" )
			)
			( signal "IRQ_DIMM_SAVE_LVT3"
				( objectStatus "@baseboard_fab2_lib.baseboard_fab2(sch_1):irq_dimm_save_lvt3" )
			)
			( signal "IRQ_DIMM_SAVE_LVT3_N"
				( objectStatus "@baseboard_fab2_lib.baseboard_fab2(sch_1):irq_dimm_save_lvt3_n" )
			)
			( signal "FM_BMC_SYS_THROTTLE_R_N"
				( objectStatus "@baseboard_fab2_lib.baseboard_fab2(sch_1):fm_bmc_sys_throttle_r_n" )
			)
			( signal "SPI_BMC_BT_CS1_N"
				( objectStatus "@baseboard_fab2_lib.baseboard_fab2(sch_1):spi_bmc_bt_cs1_n" )
			)
			( signal "IRQ_DIMM_SAVE_N"
				( objectStatus "@baseboard_fab2_lib.baseboard_fab2(sch_1):irq_dimm_save_n" )
			)
			( signal "IRQ_DIMM_SAVE_R_N"
				( objectStatus "@baseboard_fab2_lib.baseboard_fab2(sch_1):irq_dimm_save_r_n" )
			)
			( signal "P3V3"
				( attribute "VOLTAGE" "3.3V"
					( Units "uVoltage" "V" 1.000000)
					( Status sAliasFlattened )
					( Status sAliasConflict )
					( Origin gFrontEnd )
				)
				( objectStatus "@baseboard_fab2_lib.baseboard_fab2(sch_1):p3v3" )
			)
			( signal "PWRGD_PVPP_ABC"
				( objectStatus "@baseboard_fab2_lib.baseboard_fab2(sch_1):pwrgd_pvpp_abc" )
			)
			( signal "SMB_OCP_FRU_STBY_LVC3_SCL"
				( objectStatus "@baseboard_fab2_lib.baseboard_fab2(sch_1):smb_ocp_fru_stby_lvc3_scl" )
			)
			( signal "SMB_OCP_FRU_STBY_LVC3_SDA"
				( objectStatus "@baseboard_fab2_lib.baseboard_fab2(sch_1):smb_ocp_fru_stby_lvc3_sda" )
			)
			( signal "TP_HFI_IO_CONN0_RSVD_17"
				( objectStatus "@baseboard_fab2_lib.baseboard_fab2(sch_1):tp_hfi_io_conn0_rsvd_17" )
			)
			( signal "FM_CPU0_FIVR_FAULT_LVT3"
				( objectStatus "@baseboard_fab2_lib.baseboard_fab2(sch_1):fm_cpu0_fivr_fault_lvt3" )
			)
			( signal "FM_CPU0_FIVR_FAULT_R_LVT3"
				( objectStatus "@baseboard_fab2_lib.baseboard_fab2(sch_1):fm_cpu0_fivr_fault_r_lvt3" )
			)
			( signal "FM_CPU0_THERMTRIP_LVT3_N"
				( objectStatus "@baseboard_fab2_lib.baseboard_fab2(sch_1):fm_cpu0_thermtrip_lvt3_n" )
			)
			( signal "FM_CPU0_THERMTRIP_LVT3_R_N"
				( objectStatus "@baseboard_fab2_lib.baseboard_fab2(sch_1):fm_cpu0_thermtrip_lvt3_r_n" )
			)
			( signal "FM_CPU1_FIVR_FAULT_LVT3"
				( objectStatus "@baseboard_fab2_lib.baseboard_fab2(sch_1):fm_cpu1_fivr_fault_lvt3" )
			)
			( signal "FM_CPU1_FIVR_FAULT_R_LVT3"
				( objectStatus "@baseboard_fab2_lib.baseboard_fab2(sch_1):fm_cpu1_fivr_fault_r_lvt3" )
			)
			( signal "FM_CPU1_THERMTRIP_LVT3_N"
				( objectStatus "@baseboard_fab2_lib.baseboard_fab2(sch_1):fm_cpu1_thermtrip_lvt3_n" )
			)
			( signal "FM_CPU1_THERMTRIP_LVT3_R_N"
				( objectStatus "@baseboard_fab2_lib.baseboard_fab2(sch_1):fm_cpu1_thermtrip_lvt3_r_n" )
			)
			( signal "FM_CPU_CATERR_LVT3_N"
				( objectStatus "@baseboard_fab2_lib.baseboard_fab2(sch_1):fm_cpu_caterr_lvt3_n" )
			)
			( signal "FM_CPU_CATERR_LVT3_R2_N"
				( objectStatus "@baseboard_fab2_lib.baseboard_fab2(sch_1):fm_cpu_caterr_lvt3_r2_n" )
			)
			( signal "FM_CPU_ERR2_LVT3_N"
				( objectStatus "@baseboard_fab2_lib.baseboard_fab2(sch_1):fm_cpu_err2_lvt3_n" )
			)
			( signal "FM_CPU_ERR2_LVT3_R_N"
				( objectStatus "@baseboard_fab2_lib.baseboard_fab2(sch_1):fm_cpu_err2_lvt3_r_n" )
			)
			( signal "FM_CPU_MSMI_LVT3_N"
				( objectStatus "@baseboard_fab2_lib.baseboard_fab2(sch_1):fm_cpu_msmi_lvt3_n" )
			)
			( signal "FM_CPU_MSMI_LVT3_R_N"
				( objectStatus "@baseboard_fab2_lib.baseboard_fab2(sch_1):fm_cpu_msmi_lvt3_r_n" )
			)
			( signal "H_CPU_CATERR_G_N"
				( objectStatus "@baseboard_fab2_lib.baseboard_fab2(sch_1):h_cpu_caterr_g_n" )
			)
			( signal "H_CPU_ERR2_G_R_N"
				( objectStatus "@baseboard_fab2_lib.baseboard_fab2(sch_1):h_cpu_err2_g_r_n" )
			)
			( signal "H_CPU_ERR2_GTL_N"
				( objectStatus "@baseboard_fab2_lib.baseboard_fab2(sch_1):h_cpu_err2_gtl_n" )
			)
			( signal "H_CPU_MSMI_G_N"
				( objectStatus "@baseboard_fab2_lib.baseboard_fab2(sch_1):h_cpu_msmi_g_n" )
			)
			( signal "P0V7_GTL2104_VREF_0"
				( attribute "VOLTAGE" "+0.7 V"
					( Units "uVoltage" "V" 1.000000)
					( Status sAliasFlattened )
					( Origin gFrontEnd )
				)
				( objectStatus "@baseboard_fab2_lib.baseboard_fab2(sch_1):p0v7_gtl2104_vref_0" )
			)
			( signal "P0V7_GTL2104_VREF_1"
				( attribute "VOLTAGE" "+0.7 V"
					( Units "uVoltage" "V" 1.000000)
					( Status sAliasFlattened )
					( Origin gFrontEnd )
				)
				( objectStatus "@baseboard_fab2_lib.baseboard_fab2(sch_1):p0v7_gtl2104_vref_1" )
			)
			( signal "PD_GTL2104_DIR_0"
				( objectStatus "@baseboard_fab2_lib.baseboard_fab2(sch_1):pd_gtl2104_dir_0" )
			)
			( signal "PD_GTL2104_DIR_1"
				( objectStatus "@baseboard_fab2_lib.baseboard_fab2(sch_1):pd_gtl2104_dir_1" )
			)
			( signal "PWRGD_CPUPWRGD"
				( objectStatus "@baseboard_fab2_lib.baseboard_fab2(sch_1):pwrgd_cpupwrgd" )
			)
			( signal "PWRGD_CPUPWRGD_GTL"
				( objectStatus "@baseboard_fab2_lib.baseboard_fab2(sch_1):pwrgd_cpupwrgd_gtl" )
			)
			( signal "PWRGD_CPUPWRGD_R1"
				( objectStatus "@baseboard_fab2_lib.baseboard_fab2(sch_1):pwrgd_cpupwrgd_r1" )
			)
			( signal "FM_CPU0_PROCHOT_LVT3_BMC_N"
				( objectStatus "@baseboard_fab2_lib.baseboard_fab2(sch_1):fm_cpu0_prochot_lvt3_bmc_n" )
			)
			( signal "FM_CPU0_PROCHOT_LVT3_K_N"
				( objectStatus "@baseboard_fab2_lib.baseboard_fab2(sch_1):fm_cpu0_prochot_lvt3_k_n" )
			)
			( signal "FM_CPU0_PROCHOT_LVT3_N"
				( objectStatus "@baseboard_fab2_lib.baseboard_fab2(sch_1):fm_cpu0_prochot_lvt3_n" )
			)
			( signal "FM_CPU0_PROCHOT_LVT3_R_N"
				( objectStatus "@baseboard_fab2_lib.baseboard_fab2(sch_1):fm_cpu0_prochot_lvt3_r_n" )
			)
			( signal "FM_CPU0_PROCHOT_PCH_N"
				( objectStatus "@baseboard_fab2_lib.baseboard_fab2(sch_1):fm_cpu0_prochot_pch_n" )
			)
			( signal "FM_CPU1_PROCHOT_LVT3_BMC_N"
				( objectStatus "@baseboard_fab2_lib.baseboard_fab2(sch_1):fm_cpu1_prochot_lvt3_bmc_n" )
			)
			( signal "FM_CPU1_PROCHOT_LVT3_K_N"
				( objectStatus "@baseboard_fab2_lib.baseboard_fab2(sch_1):fm_cpu1_prochot_lvt3_k_n" )
			)
			( signal "FM_CPU1_PROCHOT_LVT3_N"
				( objectStatus "@baseboard_fab2_lib.baseboard_fab2(sch_1):fm_cpu1_prochot_lvt3_n" )
			)
			( signal "FM_CPU1_PROCHOT_LVT3_R_N"
				( objectStatus "@baseboard_fab2_lib.baseboard_fab2(sch_1):fm_cpu1_prochot_lvt3_r_n" )
			)
			( signal "FM_CPU1_PROCHOT_PCH_N"
				( objectStatus "@baseboard_fab2_lib.baseboard_fab2(sch_1):fm_cpu1_prochot_pch_n" )
			)
			( signal "FM_CPU_ERR0_LVT3_BMC_N"
				( objectStatus "@baseboard_fab2_lib.baseboard_fab2(sch_1):fm_cpu_err0_lvt3_bmc_n" )
			)
			( signal "FM_CPU_ERR0_LVT3_K_N"
				( objectStatus "@baseboard_fab2_lib.baseboard_fab2(sch_1):fm_cpu_err0_lvt3_k_n" )
			)
			( signal "FM_CPU_ERR0_LVT3_N"
				( objectStatus "@baseboard_fab2_lib.baseboard_fab2(sch_1):fm_cpu_err0_lvt3_n" )
			)
			( signal "FM_CPU_ERR0_LVT3_R_N"
				( objectStatus "@baseboard_fab2_lib.baseboard_fab2(sch_1):fm_cpu_err0_lvt3_r_n" )
			)
			( signal "FM_CPU_ERR0_PCH_N"
				( objectStatus "@baseboard_fab2_lib.baseboard_fab2(sch_1):fm_cpu_err0_pch_n" )
			)
			( signal "FM_CPU_ERR1_LVT3_BMC_N"
				( objectStatus "@baseboard_fab2_lib.baseboard_fab2(sch_1):fm_cpu_err1_lvt3_bmc_n" )
			)
			( signal "FM_CPU_ERR1_LVT3_K_N"
				( objectStatus "@baseboard_fab2_lib.baseboard_fab2(sch_1):fm_cpu_err1_lvt3_k_n" )
			)
			( signal "FM_CPU_ERR1_LVT3_N"
				( objectStatus "@baseboard_fab2_lib.baseboard_fab2(sch_1):fm_cpu_err1_lvt3_n" )
			)
			( signal "FM_CPU_ERR1_LVT3_R_N"
				( objectStatus "@baseboard_fab2_lib.baseboard_fab2(sch_1):fm_cpu_err1_lvt3_r_n" )
			)
			( signal "FM_CPU_ERR1_PCH_N"
				( objectStatus "@baseboard_fab2_lib.baseboard_fab2(sch_1):fm_cpu_err1_pch_n" )
			)
			( signal "H_CPU0_PROCHOT_G_PCH_N"
				( objectStatus "@baseboard_fab2_lib.baseboard_fab2(sch_1):h_cpu0_prochot_g_pch_n" )
			)
			( signal "H_CPU0_PROCHOT_G_R_N"
				( objectStatus "@baseboard_fab2_lib.baseboard_fab2(sch_1):h_cpu0_prochot_g_r_n" )
			)
			( signal "H_CPU1_PROCHOT_G_PCH_N"
				( objectStatus "@baseboard_fab2_lib.baseboard_fab2(sch_1):h_cpu1_prochot_g_pch_n" )
			)
			( signal "H_CPU1_PROCHOT_G_R_N"
				( objectStatus "@baseboard_fab2_lib.baseboard_fab2(sch_1):h_cpu1_prochot_g_r_n" )
			)
			( signal "H_CPU_ERR0_GTL_N"
				( objectStatus "@baseboard_fab2_lib.baseboard_fab2(sch_1):h_cpu_err0_gtl_n" )
			)
			( signal "H_CPU_ERR0_GTL_R_N"
				( objectStatus "@baseboard_fab2_lib.baseboard_fab2(sch_1):h_cpu_err0_gtl_r_n" )
			)
			( signal "H_CPU_ERR0_PCH_N"
				( objectStatus "@baseboard_fab2_lib.baseboard_fab2(sch_1):h_cpu_err0_pch_n" )
			)
			( signal "H_CPU_ERR1_GTL_N"
				( objectStatus "@baseboard_fab2_lib.baseboard_fab2(sch_1):h_cpu_err1_gtl_n" )
			)
			( signal "H_CPU_ERR1_GTL_R_N"
				( objectStatus "@baseboard_fab2_lib.baseboard_fab2(sch_1):h_cpu_err1_gtl_r_n" )
			)
			( signal "H_CPU_ERR1_PCH_N"
				( objectStatus "@baseboard_fab2_lib.baseboard_fab2(sch_1):h_cpu_err1_pch_n" )
			)
			( signal "P0V7_GTL2104_5_VREF"
				( attribute "VOLTAGE" "0.734"
					( Units "uVoltage" "V" 1.000000)
					( Status sAliasFlattened )
					( Origin gFrontEnd )
				)
				( objectStatus "@baseboard_fab2_lib.baseboard_fab2(sch_1):p0v7_gtl2104_5_vref" )
			)
			( signal "PD_GTL2104_4_DIR"
				( objectStatus "@baseboard_fab2_lib.baseboard_fab2(sch_1):pd_gtl2104_4_dir" )
			)
			( signal "FM_DIMM_EVENT_FET"
				( objectStatus "@baseboard_fab2_lib.baseboard_fab2(sch_1):fm_dimm_event_fet" )
			)
			( signal "FM_MEM_THERM_EVENT_LVT3_N"
				( objectStatus "@baseboard_fab2_lib.baseboard_fab2(sch_1):fm_mem_therm_event_lvt3_n" )
			)
			( signal "H_CPU0_MEMABC_MEMHOT"
				( objectStatus "@baseboard_fab2_lib.baseboard_fab2(sch_1):h_cpu0_memabc_memhot" )
			)
			( signal "H_CPU0_MEMDEF_MEMHOT"
				( objectStatus "@baseboard_fab2_lib.baseboard_fab2(sch_1):h_cpu0_memdef_memhot" )
			)
			( signal "H_CPU1_MEMGHJ_MEMHOT"
				( objectStatus "@baseboard_fab2_lib.baseboard_fab2(sch_1):h_cpu1_memghj_memhot" )
			)
			( signal "H_CPU1_MEMKLM_MEMHOT"
				( objectStatus "@baseboard_fab2_lib.baseboard_fab2(sch_1):h_cpu1_memklm_memhot" )
			)
			( signal "IRQ_PVDDQ_ABC_VRHOT_LVT3_N"
				( objectStatus "@baseboard_fab2_lib.baseboard_fab2(sch_1):irq_pvddq_abc_vrhot_lvt3_n" )
			)
			( signal "IRQ_PVDDQ_DEF_VRHOT_LVT3_N"
				( objectStatus "@baseboard_fab2_lib.baseboard_fab2(sch_1):irq_pvddq_def_vrhot_lvt3_n" )
			)
			( signal "FM_BMC_NMI_N_R"
				( objectStatus "@baseboard_fab2_lib.baseboard_fab2(sch_1):fm_bmc_nmi_n_r" )
			)
			( signal "IRQ_PVDDQ_GHJ_VRHOT_LVT3_N"
				( objectStatus "@baseboard_fab2_lib.baseboard_fab2(sch_1):irq_pvddq_ghj_vrhot_lvt3_n" )
			)
			( signal "IRQ_PVDDQ_KLM_VRHOT_LVT3_N"
				( objectStatus "@baseboard_fab2_lib.baseboard_fab2(sch_1):irq_pvddq_klm_vrhot_lvt3_n" )
			)
			( signal "FM_PVCCIN_CPU0_PWR_IN_ALERT_N"
				( objectStatus "@baseboard_fab2_lib.baseboard_fab2(sch_1):fm_pvccin_cpu0_pwr_in_alert_n" )
			)
			( signal "FM_PVCCIN_CPU1_PWR_IN_ALERT_N"
				( objectStatus "@baseboard_fab2_lib.baseboard_fab2(sch_1):fm_pvccin_cpu1_pwr_in_alert_n" )
			)
			( signal "FM_PWRBRK_N"
				( objectStatus "@baseboard_fab2_lib.baseboard_fab2(sch_1):fm_pwrbrk_n" )
			)
			( signal "FM_SYS_THROTTLE_LVC3"
				( objectStatus "@baseboard_fab2_lib.baseboard_fab2(sch_1):fm_sys_throttle_lvc3" )
			)
			( signal "FM_THROTTLE_N"
				( objectStatus "@baseboard_fab2_lib.baseboard_fab2(sch_1):fm_throttle_n" )
			)
			( signal "FM_THROTTLE_R_N"
				( objectStatus "@baseboard_fab2_lib.baseboard_fab2(sch_1):fm_throttle_r_n" )
			)
			( signal "IRQ_CPU0_PROCHOT_G_N"
				( objectStatus "@baseboard_fab2_lib.baseboard_fab2(sch_1):irq_cpu0_prochot_g_n" )
			)
			( signal "IRQ_CPU0_VRHOT"
				( objectStatus "@baseboard_fab2_lib.baseboard_fab2(sch_1):irq_cpu0_vrhot" )
			)
			( signal "IRQ_CPU1_PROCHOT_G_N"
				( objectStatus "@baseboard_fab2_lib.baseboard_fab2(sch_1):irq_cpu1_prochot_g_n" )
			)
			( signal "IRQ_CPU1_VRHOT"
				( objectStatus "@baseboard_fab2_lib.baseboard_fab2(sch_1):irq_cpu1_vrhot" )
			)
			( signal "IRQ_PVCCIN_CPU0_VRHOT_LVC3_N"
				( objectStatus "@baseboard_fab2_lib.baseboard_fab2(sch_1):irq_pvccin_cpu0_vrhot_lvc3_n" )
			)
			( signal "IRQ_PVCCIN_CPU1_VRHOT_LVC3_N"
				( objectStatus "@baseboard_fab2_lib.baseboard_fab2(sch_1):irq_pvccin_cpu1_vrhot_lvc3_n" )
			)
			( signal "PD_GTL2014_1_VREF"
				( objectStatus "@baseboard_fab2_lib.baseboard_fab2(sch_1):pd_gtl2014_1_vref" )
			)
			( signal "PD_GTL2014_2_VREF"
				( objectStatus "@baseboard_fab2_lib.baseboard_fab2(sch_1):pd_gtl2014_2_vref" )
			)
			( signal "PU_GTL2014_1_DIR"
				( objectStatus "@baseboard_fab2_lib.baseboard_fab2(sch_1):pu_gtl2014_1_dir" )
			)
			( signal "PU_GTL2014_2_DIR"
				( objectStatus "@baseboard_fab2_lib.baseboard_fab2(sch_1):pu_gtl2014_2_dir" )
			)
			( signal "PWRGD_CPU0_LVC3"
				( objectStatus "@baseboard_fab2_lib.baseboard_fab2(sch_1):pwrgd_cpu0_lvc3" )
			)
			( signal "PWRGD_CPU1_LVC3"
				( objectStatus "@baseboard_fab2_lib.baseboard_fab2(sch_1):pwrgd_cpu1_lvc3" )
			)
			( signal "PWRGD_DRAMPWRGD"
				( objectStatus "@baseboard_fab2_lib.baseboard_fab2(sch_1):pwrgd_drampwrgd" )
			)
			( signal "RST_CPU0_LVC3_N"
				( objectStatus "@baseboard_fab2_lib.baseboard_fab2(sch_1):rst_cpu0_lvc3_n" )
			)
			( signal "RST_CPU1_LVC3_N"
				( objectStatus "@baseboard_fab2_lib.baseboard_fab2(sch_1):rst_cpu1_lvc3_n" )
			)
			( signal "SMB_DDR_ABC_SCL_G"
				( objectStatus "@baseboard_fab2_lib.baseboard_fab2(sch_1):smb_ddr_abc_scl_g" )
			)
			( signal "SMB_DDR_ABC_SDA_G"
				( objectStatus "@baseboard_fab2_lib.baseboard_fab2(sch_1):smb_ddr_abc_sda_g" )
			)
			( signal "SMB_DDR_ABC_VPP_SCL_R"
				( objectStatus "@baseboard_fab2_lib.baseboard_fab2(sch_1):smb_ddr_abc_vpp_scl_r" )
			)
			( signal "SMB_DDR_ABC_VPP_SDA_R"
				( objectStatus "@baseboard_fab2_lib.baseboard_fab2(sch_1):smb_ddr_abc_vpp_sda_r" )
			)
			( signal "SMB_DDR_DEF_SCL_G"
				( objectStatus "@baseboard_fab2_lib.baseboard_fab2(sch_1):smb_ddr_def_scl_g" )
			)
			( signal "SMB_DDR_DEF_SDA_G"
				( objectStatus "@baseboard_fab2_lib.baseboard_fab2(sch_1):smb_ddr_def_sda_g" )
			)
			( signal "SMB_DDR_DEF_VPP_SCL_R"
				( objectStatus "@baseboard_fab2_lib.baseboard_fab2(sch_1):smb_ddr_def_vpp_scl_r" )
			)
			( signal "SMB_DDR_DEF_VPP_SDA_R"
				( objectStatus "@baseboard_fab2_lib.baseboard_fab2(sch_1):smb_ddr_def_vpp_sda_r" )
			)
			( signal "SMB_DDR_GHJ_SCL_G"
				( objectStatus "@baseboard_fab2_lib.baseboard_fab2(sch_1):smb_ddr_ghj_scl_g" )
			)
			( signal "SMB_DDR_GHJ_SDA_G"
				( objectStatus "@baseboard_fab2_lib.baseboard_fab2(sch_1):smb_ddr_ghj_sda_g" )
			)
			( signal "SMB_DDR_GHJ_VPP_SCL_R"
				( objectStatus "@baseboard_fab2_lib.baseboard_fab2(sch_1):smb_ddr_ghj_vpp_scl_r" )
			)
			( signal "SMB_DDR_GHJ_VPP_SDA_R"
				( objectStatus "@baseboard_fab2_lib.baseboard_fab2(sch_1):smb_ddr_ghj_vpp_sda_r" )
			)
			( signal "SMB_DDR_KLM_SCL_G"
				( objectStatus "@baseboard_fab2_lib.baseboard_fab2(sch_1):smb_ddr_klm_scl_g" )
			)
			( signal "SMB_DDR_KLM_SDA_G"
				( objectStatus "@baseboard_fab2_lib.baseboard_fab2(sch_1):smb_ddr_klm_sda_g" )
			)
			( signal "SMB_DDR_KLM_VPP_SCL_R"
				( objectStatus "@baseboard_fab2_lib.baseboard_fab2(sch_1):smb_ddr_klm_vpp_scl_r" )
			)
			( signal "SMB_DDR_KLM_VPP_SDA_R"
				( objectStatus "@baseboard_fab2_lib.baseboard_fab2(sch_1):smb_ddr_klm_vpp_sda_r" )
			)
			( signal "TP_SMB_DDR_ABC_EN"
				( objectStatus "@baseboard_fab2_lib.baseboard_fab2(sch_1):tp_smb_ddr_abc_en" )
			)
			( signal "TP_SMB_DDR_DEF_EN"
				( objectStatus "@baseboard_fab2_lib.baseboard_fab2(sch_1):tp_smb_ddr_def_en" )
			)
			( signal "TP_SMB_DDR_GHJ_EN"
				( objectStatus "@baseboard_fab2_lib.baseboard_fab2(sch_1):tp_smb_ddr_ghj_en" )
			)
			( signal "TP_SMB_DDR_KLM_EN"
				( objectStatus "@baseboard_fab2_lib.baseboard_fab2(sch_1):tp_smb_ddr_klm_en" )
			)
			( signal "A_COMP_CKMNG"
				( objectStatus "@baseboard_fab2_lib.baseboard_fab2(sch_1):a_comp_ckmng" )
			)
			( signal "CLK_25M_BMC"
				( objectStatus "@baseboard_fab2_lib.baseboard_fab2(sch_1):clk_25m_bmc" )
			)
			( signal "CLK_25M_BMC_R"
				( objectStatus "@baseboard_fab2_lib.baseboard_fab2(sch_1):clk_25m_bmc_r" )
			)
			( signal "CLK_25M_CPLD"
				( objectStatus "@baseboard_fab2_lib.baseboard_fab2(sch_1):clk_25m_cpld" )
			)
			( signal "CLK_25M_CPLD_R"
				( objectStatus "@baseboard_fab2_lib.baseboard_fab2(sch_1):clk_25m_cpld_r" )
			)
			( signal "CLK_32K_SUSCLK_PLD"
				( objectStatus "@baseboard_fab2_lib.baseboard_fab2(sch_1):clk_32k_susclk_pld" )
			)
			( signal "CLK_32K_SUSCLK_PLD_R"
				( objectStatus "@baseboard_fab2_lib.baseboard_fab2(sch_1):clk_32k_susclk_pld_r" )
			)
			( signal "CLK_50M_CKMNG_BMC_1"
				( objectStatus "@baseboard_fab2_lib.baseboard_fab2(sch_1):clk_50m_ckmng_bmc_1" )
			)
			( signal "CLK_50M_CKMNG_BMC_1_R"
				( objectStatus "@baseboard_fab2_lib.baseboard_fab2(sch_1):clk_50m_ckmng_bmc_1_r" )
			)
			( signal "CLK_50M_CKMNG_BMC_2"
				( objectStatus "@baseboard_fab2_lib.baseboard_fab2(sch_1):clk_50m_ckmng_bmc_2" )
			)
			( signal "CLK_50M_CKMNG_BMC_2_R"
				( objectStatus "@baseboard_fab2_lib.baseboard_fab2(sch_1):clk_50m_ckmng_bmc_2_r" )
			)
			( signal "CLK_50M_CKMNG_OCP"
				( objectStatus "@baseboard_fab2_lib.baseboard_fab2(sch_1):clk_50m_ckmng_ocp" )
			)
			( signal "CLK_50M_CKMNG_OCP_R"
				( objectStatus "@baseboard_fab2_lib.baseboard_fab2(sch_1):clk_50m_ckmng_ocp_r" )
			)
			( signal "CLK_50M_CKMNG_PCH_10GBE"
				( objectStatus "@baseboard_fab2_lib.baseboard_fab2(sch_1):clk_50m_ckmng_pch_10gbe" )
			)
			( signal "CLK_50M_CKMNG_PCH_10GBE_R"
				( objectStatus "@baseboard_fab2_lib.baseboard_fab2(sch_1):clk_50m_ckmng_pch_10gbe_r" )
			)
			( signal "CLK_50M_CKMNG_SPRVLLE"
				( objectStatus "@baseboard_fab2_lib.baseboard_fab2(sch_1):clk_50m_ckmng_sprvlle" )
			)
			( signal "CLK_50M_CKMNG_SPRVLLE_R"
				( objectStatus "@baseboard_fab2_lib.baseboard_fab2(sch_1):clk_50m_ckmng_sprvlle_r" )
			)
			( signal "P3V3_STBY_MNG"
				( attribute "VOLTAGE" "5"
					( Units "uVoltage" "V" 1.000000)
					( Status sAliasFlattened )
					( Origin gFrontEnd )
				)
				( objectStatus "@baseboard_fab2_lib.baseboard_fab2(sch_1):p3v3_stby_mng" )
			)
			( signal "P3V3_STBY_MNG_CPU"
				( attribute "VOLTAGE" "3.3"
					( Units "uVoltage" "V" 1.000000)
					( Status sAliasFlattened )
					( Origin gFrontEnd )
				)
				( objectStatus "@baseboard_fab2_lib.baseboard_fab2(sch_1):p3v3_stby_mng_cpu" )
			)
			( signal "P3V3_STBY_MNG_RGMII"
				( attribute "VOLTAGE" "3.3"
					( Units "uVoltage" "V" 1.000000)
					( Status sAliasFlattened )
					( Origin gFrontEnd )
				)
				( objectStatus "@baseboard_fab2_lib.baseboard_fab2(sch_1):p3v3_stby_mng_rgmii" )
			)
			( signal "P3V3_STBY_MNG_RMII"
				( attribute "VOLTAGE" "3.3"
					( Units "uVoltage" "V" 1.000000)
					( Status sAliasFlattened )
					( Origin gFrontEnd )
				)
				( objectStatus "@baseboard_fab2_lib.baseboard_fab2(sch_1):p3v3_stby_mng_rmii" )
			)
			( signal "PD_CKMNG_OE"
				( objectStatus "@baseboard_fab2_lib.baseboard_fab2(sch_1):pd_ckmng_oe" )
			)
			( signal "PWRGD_P3V3_STBY"
				( objectStatus "@baseboard_fab2_lib.baseboard_fab2(sch_1):pwrgd_p3v3_stby" )
			)
			( signal "SMB_HOST_STBY_LVC3_SCL"
				( objectStatus "@baseboard_fab2_lib.baseboard_fab2(sch_1):smb_host_stby_lvc3_scl" )
			)
			( signal "SMB_HOST_STBY_LVC3_SDA"
				( objectStatus "@baseboard_fab2_lib.baseboard_fab2(sch_1):smb_host_stby_lvc3_sda" )
			)
			( signal "TP_33P_33M_SMBADR"
				( objectStatus "@baseboard_fab2_lib.baseboard_fab2(sch_1):tp_33p_33m_smbadr" )
			)
			( signal "TP_CLK5_50M_CKMNG"
				( objectStatus "@baseboard_fab2_lib.baseboard_fab2(sch_1):tp_clk5_50m_ckmng" )
			)
			( signal "TP_CLK_100M_R_DN"
				( objectStatus "@baseboard_fab2_lib.baseboard_fab2(sch_1):tp_clk_100m_r_dn" )
			)
			( signal "TP_CLK_100M_R_DP"
				( objectStatus "@baseboard_fab2_lib.baseboard_fab2(sch_1):tp_clk_100m_r_dp" )
			)
			( signal "TP_CLK_125M"
				( objectStatus "@baseboard_fab2_lib.baseboard_fab2(sch_1):tp_clk_125m" )
			)
			( signal "TP_CLK_125M_BMCA"
				( objectStatus "@baseboard_fab2_lib.baseboard_fab2(sch_1):tp_clk_125m_bmca" )
			)
			( signal "TP_CLK_96M_CKMNG_N"
				( objectStatus "@baseboard_fab2_lib.baseboard_fab2(sch_1):tp_clk_96m_ckmng_n" )
			)
			( signal "TP_CLK_96M_CKMNG_P"
				( objectStatus "@baseboard_fab2_lib.baseboard_fab2(sch_1):tp_clk_96m_ckmng_p" )
			)
			( signal "XTAL_CK_MNG_IN"
				( objectStatus "@baseboard_fab2_lib.baseboard_fab2(sch_1):xtal_ck_mng_in" )
			)
			( signal "XTAL_CK_MNG_OUT"
				( objectStatus "@baseboard_fab2_lib.baseboard_fab2(sch_1):xtal_ck_mng_out" )
			)
			( signal "CLK_100M_CPU0_BCLK0_R_DN"
				( objectStatus "@baseboard_fab2_lib.baseboard_fab2(sch_1):clk_100m_cpu0_bclk0_r_dn" )
			)
			( signal "CLK_100M_CPU0_BCLK0_R_DP"
				( objectStatus "@baseboard_fab2_lib.baseboard_fab2(sch_1):clk_100m_cpu0_bclk0_r_dp" )
			)
			( signal "CLK_100M_CPU0_BCLK1_R_DN"
				( objectStatus "@baseboard_fab2_lib.baseboard_fab2(sch_1):clk_100m_cpu0_bclk1_r_dn" )
			)
			( signal "CLK_100M_CPU0_BCLK1_R_DP"
				( objectStatus "@baseboard_fab2_lib.baseboard_fab2(sch_1):clk_100m_cpu0_bclk1_r_dp" )
			)
			( signal "CLK_100M_CPU0_BCLK2_R_DN"
				( objectStatus "@baseboard_fab2_lib.baseboard_fab2(sch_1):clk_100m_cpu0_bclk2_r_dn" )
			)
			( signal "CLK_100M_CPU0_BCLK2_R_DP"
				( objectStatus "@baseboard_fab2_lib.baseboard_fab2(sch_1):clk_100m_cpu0_bclk2_r_dp" )
			)
			( signal "CLK_100M_CPU0_PE_REFCLK_R_DN"
				( objectStatus "@baseboard_fab2_lib.baseboard_fab2(sch_1):clk_100m_cpu0_pe_refclk_r_dn" )
			)
			( signal "CLK_100M_CPU0_PE_REFCLK_R_DP"
				( objectStatus "@baseboard_fab2_lib.baseboard_fab2(sch_1):clk_100m_cpu0_pe_refclk_r_dp" )
			)
			( signal "CLK_100M_CPU0_RC_REFCLK0_R_DN"
				( objectStatus "@baseboard_fab2_lib.baseboard_fab2(sch_1):clk_100m_cpu0_rc_refclk0_r_dn" )
			)
			( signal "CLK_100M_CPU0_RC_REFCLK0_R_DP"
				( objectStatus "@baseboard_fab2_lib.baseboard_fab2(sch_1):clk_100m_cpu0_rc_refclk0_r_dp" )
			)
			( signal "CLK_100M_CPU0_RC_REFCLK1_R_DN"
				( objectStatus "@baseboard_fab2_lib.baseboard_fab2(sch_1):clk_100m_cpu0_rc_refclk1_r_dn" )
			)
			( signal "CLK_100M_CPU0_RC_REFCLK1_R_DP"
				( objectStatus "@baseboard_fab2_lib.baseboard_fab2(sch_1):clk_100m_cpu0_rc_refclk1_r_dp" )
			)
			( signal "CLK_100M_CPU1_BCLK0_R_DN"
				( objectStatus "@baseboard_fab2_lib.baseboard_fab2(sch_1):clk_100m_cpu1_bclk0_r_dn" )
			)
			( signal "CLK_100M_CPU1_BCLK0_R_DP"
				( objectStatus "@baseboard_fab2_lib.baseboard_fab2(sch_1):clk_100m_cpu1_bclk0_r_dp" )
			)
			( signal "CLK_100M_CPU1_BCLK1_R_DN"
				( objectStatus "@baseboard_fab2_lib.baseboard_fab2(sch_1):clk_100m_cpu1_bclk1_r_dn" )
			)
			( signal "CLK_100M_CPU1_BCLK1_R_DP"
				( objectStatus "@baseboard_fab2_lib.baseboard_fab2(sch_1):clk_100m_cpu1_bclk1_r_dp" )
			)
			( signal "CLK_100M_CPU1_BCLK2_R_DN"
				( objectStatus "@baseboard_fab2_lib.baseboard_fab2(sch_1):clk_100m_cpu1_bclk2_r_dn" )
			)
			( signal "CLK_100M_CPU1_BCLK2_R_DP"
				( objectStatus "@baseboard_fab2_lib.baseboard_fab2(sch_1):clk_100m_cpu1_bclk2_r_dp" )
			)
			( signal "CLK_100M_CPU1_PE_REFCLK_R_DN"
				( objectStatus "@baseboard_fab2_lib.baseboard_fab2(sch_1):clk_100m_cpu1_pe_refclk_r_dn" )
			)
			( signal "CLK_100M_CPU1_PE_REFCLK_R_DP"
				( objectStatus "@baseboard_fab2_lib.baseboard_fab2(sch_1):clk_100m_cpu1_pe_refclk_r_dp" )
			)
			( signal "CLK_100M_CPU1_RC_REFCLK0_R_DN"
				( objectStatus "@baseboard_fab2_lib.baseboard_fab2(sch_1):clk_100m_cpu1_rc_refclk0_r_dn" )
			)
			( signal "CLK_100M_CPU1_RC_REFCLK0_R_DP"
				( objectStatus "@baseboard_fab2_lib.baseboard_fab2(sch_1):clk_100m_cpu1_rc_refclk0_r_dp" )
			)
			( signal "CLK_100M_CPU1_RC_REFCLK1_R_DN"
				( objectStatus "@baseboard_fab2_lib.baseboard_fab2(sch_1):clk_100m_cpu1_rc_refclk1_r_dn" )
			)
			( signal "CLK_100M_CPU1_RC_REFCLK1_R_DP"
				( objectStatus "@baseboard_fab2_lib.baseboard_fab2(sch_1):clk_100m_cpu1_rc_refclk1_r_dp" )
			)
			( signal "CLK_100M_DB1200_DN"
				( objectStatus "@baseboard_fab2_lib.baseboard_fab2(sch_1):clk_100m_db1200_dn" )
			)
			( signal "CLK_100M_DB1200_DP"
				( objectStatus "@baseboard_fab2_lib.baseboard_fab2(sch_1):clk_100m_db1200_dp" )
			)
			( signal "FM_100M_N"
				( objectStatus "@baseboard_fab2_lib.baseboard_fab2(sch_1):fm_100m_n" )
			)
			( signal "FM_CPU0_MCP_CLK_EN_N"
				( objectStatus "@baseboard_fab2_lib.baseboard_fab2(sch_1):fm_cpu0_mcp_clk_en_n" )
			)
			( signal "FM_CPU1_MCP_CLK_EN_N"
				( objectStatus "@baseboard_fab2_lib.baseboard_fab2(sch_1):fm_cpu1_mcp_clk_en_n" )
			)
			( signal "FM_DB1200_PWRGD"
				( objectStatus "@baseboard_fab2_lib.baseboard_fab2(sch_1):fm_db1200_pwrgd" )
			)
			( signal "FM_DB1200_SMB_SA0"
				( objectStatus "@baseboard_fab2_lib.baseboard_fab2(sch_1):fm_db1200_smb_sa0" )
			)
			( signal "FM_DB1200_SMB_SA1"
				( objectStatus "@baseboard_fab2_lib.baseboard_fab2(sch_1):fm_db1200_smb_sa1" )
			)
			( signal "FM_DB1200ZL_BCLKS_EN_N"
				( objectStatus "@baseboard_fab2_lib.baseboard_fab2(sch_1):fm_db1200zl_bclks_en_n" )
			)
			( signal "FM_HBW_BYPASS_LOWBW_N"
				( objectStatus "@baseboard_fab2_lib.baseboard_fab2(sch_1):fm_hbw_bypass_lowbw_n" )
			)
			( signal "NC_DB1200ZL<0>"
				( objectStatus "@baseboard_fab2_lib.baseboard_fab2(sch_1):nc_db1200zl(0)" )
			)
			( signal "NC_DB1200ZL<1>"
				( objectStatus "@baseboard_fab2_lib.baseboard_fab2(sch_1):nc_db1200zl(1)" )
			)
			( signal "NC_DB1200ZL<2>"
				( objectStatus "@baseboard_fab2_lib.baseboard_fab2(sch_1):nc_db1200zl(2)" )
			)
			( signal "P3V3_DB1200"
				( attribute "VOLTAGE" "5"
					( Units "uVoltage" "V" 1.000000)
					( Status sAliasFlattened )
					( Origin gFrontEnd )
				)
				( objectStatus "@baseboard_fab2_lib.baseboard_fab2(sch_1):p3v3_db1200" )
			)
			( signal "P3V3_DB1200_A"
				( attribute "VOLTAGE" "+3.3V"
					( Units "uVoltage" "V" 1.000000)
					( Status sAliasFlattened )
					( Origin gFrontEnd )
				)
				( objectStatus "@baseboard_fab2_lib.baseboard_fab2(sch_1):p3v3_db1200_a" )
			)
			( signal "P3V3_DB1200_R"
				( attribute "VOLTAGE" "+3.3V"
					( Units "uVoltage" "V" 1.000000)
					( Status sAliasFlattened )
					( Origin gFrontEnd )
				)
				( objectStatus "@baseboard_fab2_lib.baseboard_fab2(sch_1):p3v3_db1200_r" )
			)
			( signal "SMB_HOST_STBY_LVC3_SCL_R2"
				( objectStatus "@baseboard_fab2_lib.baseboard_fab2(sch_1):smb_host_stby_lvc3_scl_r2" )
			)
			( signal "SMB_HOST_STBY_LVC3_SDA_R2"
				( objectStatus "@baseboard_fab2_lib.baseboard_fab2(sch_1):smb_host_stby_lvc3_sda_r2" )
			)
			( signal "CLK_156M_OSC_BRD_CPU0_DN"
				( objectStatus "@baseboard_fab2_lib.baseboard_fab2(sch_1):clk_156m_osc_brd_cpu0_dn" )
			)
			( signal "CLK_156M_OSC_BRD_CPU0_DP"
				( objectStatus "@baseboard_fab2_lib.baseboard_fab2(sch_1):clk_156m_osc_brd_cpu0_dp" )
			)
			( signal "CLK_156M_OSC_BRD_CPU1_DN"
				( objectStatus "@baseboard_fab2_lib.baseboard_fab2(sch_1):clk_156m_osc_brd_cpu1_dn" )
			)
			( signal "CLK_156M_OSC_BRD_CPU1_DP"
				( objectStatus "@baseboard_fab2_lib.baseboard_fab2(sch_1):clk_156m_osc_brd_cpu1_dp" )
			)
			( signal "CLK_322M_156M_CPU0_OSC_VRM_DN"
				( objectStatus "@baseboard_fab2_lib.baseboard_fab2(sch_1):clk_322m_156m_cpu0_osc_vrm_dn" )
			)
			( signal "CLK_322M_156M_CPU0_OSC_VRM_DP"
				( objectStatus "@baseboard_fab2_lib.baseboard_fab2(sch_1):clk_322m_156m_cpu0_osc_vrm_dp" )
			)
			( signal "CLK_322M_156M_CPU1_OSC_VRM_DN"
				( objectStatus "@baseboard_fab2_lib.baseboard_fab2(sch_1):clk_322m_156m_cpu1_osc_vrm_dn" )
			)
			( signal "CLK_322M_156M_CPU1_OSC_VRM_DP"
				( objectStatus "@baseboard_fab2_lib.baseboard_fab2(sch_1):clk_322m_156m_cpu1_osc_vrm_dp" )
			)
			( signal "FM_156M_CPU0_BRD_OSC_EN"
				( objectStatus "@baseboard_fab2_lib.baseboard_fab2(sch_1):fm_156m_cpu0_brd_osc_en" )
			)
			( signal "FM_156M_CPU1_BRD_OSC_EN"
				( objectStatus "@baseboard_fab2_lib.baseboard_fab2(sch_1):fm_156m_cpu1_brd_osc_en" )
			)
			( signal "FM_CPU0_STL_BRD_OSC_EN"
				( objectStatus "@baseboard_fab2_lib.baseboard_fab2(sch_1):fm_cpu0_stl_brd_osc_en" )
			)
			( signal "FM_CPU0_VRM_322M_156M_OSC_EN"
				( objectStatus "@baseboard_fab2_lib.baseboard_fab2(sch_1):fm_cpu0_vrm_322m_156m_osc_en" )
			)
			( signal "FM_CPU0_VRM_OSC_EN"
				( objectStatus "@baseboard_fab2_lib.baseboard_fab2(sch_1):fm_cpu0_vrm_osc_en" )
			)
			( signal "FM_CPU1_STL_BRD_OSC_EN"
				( objectStatus "@baseboard_fab2_lib.baseboard_fab2(sch_1):fm_cpu1_stl_brd_osc_en" )
			)
			( signal "FM_CPU1_VRM_322M_156M_OSC_EN"
				( objectStatus "@baseboard_fab2_lib.baseboard_fab2(sch_1):fm_cpu1_vrm_322m_156m_osc_en" )
			)
			( signal "FM_CPU1_VRM_OSC_EN"
				( objectStatus "@baseboard_fab2_lib.baseboard_fab2(sch_1):fm_cpu1_vrm_osc_en" )
			)
			( signal "NC_CLK_156M_CPU0_OSC"
				( objectStatus "@baseboard_fab2_lib.baseboard_fab2(sch_1):nc_clk_156m_cpu0_osc" )
			)
			( signal "NC_CLK_156M_CPU1_OSC"
				( objectStatus "@baseboard_fab2_lib.baseboard_fab2(sch_1):nc_clk_156m_cpu1_osc" )
			)
			( signal "P3E_CPU0_PE1_PCH_C_TXN<8>"
				( objectStatus "@baseboard_fab2_lib.baseboard_fab2(sch_1):p3e_cpu0_pe1_pch_c_txn(8)" )
			)
			( signal "P3E_CPU0_PE1_PCH_C_TXN<9>"
				( objectStatus "@baseboard_fab2_lib.baseboard_fab2(sch_1):p3e_cpu0_pe1_pch_c_txn(9)" )
			)
			( signal "P3E_CPU0_PE1_PCH_C_TXN<10>"
				( objectStatus "@baseboard_fab2_lib.baseboard_fab2(sch_1):p3e_cpu0_pe1_pch_c_txn(10)" )
			)
			( signal "P3E_CPU0_PE1_PCH_C_TXN<11>"
				( objectStatus "@baseboard_fab2_lib.baseboard_fab2(sch_1):p3e_cpu0_pe1_pch_c_txn(11)" )
			)
			( signal "P3E_CPU0_PE1_PCH_C_TXN<12>"
				( objectStatus "@baseboard_fab2_lib.baseboard_fab2(sch_1):p3e_cpu0_pe1_pch_c_txn(12)" )
			)
			( signal "P3E_CPU0_PE1_PCH_C_TXN<13>"
				( objectStatus "@baseboard_fab2_lib.baseboard_fab2(sch_1):p3e_cpu0_pe1_pch_c_txn(13)" )
			)
			( signal "P3E_CPU0_PE1_PCH_C_TXN<14>"
				( objectStatus "@baseboard_fab2_lib.baseboard_fab2(sch_1):p3e_cpu0_pe1_pch_c_txn(14)" )
			)
			( signal "P3E_CPU0_PE1_PCH_C_TXN<15>"
				( objectStatus "@baseboard_fab2_lib.baseboard_fab2(sch_1):p3e_cpu0_pe1_pch_c_txn(15)" )
			)
			( signal "P3E_CPU0_PE1_PCH_C_TXP<8>"
				( objectStatus "@baseboard_fab2_lib.baseboard_fab2(sch_1):p3e_cpu0_pe1_pch_c_txp(8)" )
			)
			( signal "P3E_CPU0_PE1_PCH_C_TXP<9>"
				( objectStatus "@baseboard_fab2_lib.baseboard_fab2(sch_1):p3e_cpu0_pe1_pch_c_txp(9)" )
			)
			( signal "P3E_CPU0_PE1_PCH_C_TXP<10>"
				( objectStatus "@baseboard_fab2_lib.baseboard_fab2(sch_1):p3e_cpu0_pe1_pch_c_txp(10)" )
			)
			( signal "P3E_CPU0_PE1_PCH_C_TXP<11>"
				( objectStatus "@baseboard_fab2_lib.baseboard_fab2(sch_1):p3e_cpu0_pe1_pch_c_txp(11)" )
			)
			( signal "P3E_CPU0_PE1_PCH_C_TXP<12>"
				( objectStatus "@baseboard_fab2_lib.baseboard_fab2(sch_1):p3e_cpu0_pe1_pch_c_txp(12)" )
			)
			( signal "P3E_CPU0_PE1_PCH_C_TXP<13>"
				( objectStatus "@baseboard_fab2_lib.baseboard_fab2(sch_1):p3e_cpu0_pe1_pch_c_txp(13)" )
			)
			( signal "P3E_CPU0_PE1_PCH_C_TXP<14>"
				( objectStatus "@baseboard_fab2_lib.baseboard_fab2(sch_1):p3e_cpu0_pe1_pch_c_txp(14)" )
			)
			( signal "P3E_CPU0_PE1_PCH_C_TXP<15>"
				( objectStatus "@baseboard_fab2_lib.baseboard_fab2(sch_1):p3e_cpu0_pe1_pch_c_txp(15)" )
			)
			( signal "P3E_CPU0_PE1_PCH_R_RXN<8>"
				( objectStatus "@baseboard_fab2_lib.baseboard_fab2(sch_1):p3e_cpu0_pe1_pch_r_rxn(8)" )
			)
			( signal "P3E_CPU0_PE1_PCH_R_RXN<9>"
				( objectStatus "@baseboard_fab2_lib.baseboard_fab2(sch_1):p3e_cpu0_pe1_pch_r_rxn(9)" )
			)
			( signal "P3E_CPU0_PE1_PCH_R_RXN<10>"
				( objectStatus "@baseboard_fab2_lib.baseboard_fab2(sch_1):p3e_cpu0_pe1_pch_r_rxn(10)" )
			)
			( signal "P3E_CPU0_PE1_PCH_R_RXN<11>"
				( objectStatus "@baseboard_fab2_lib.baseboard_fab2(sch_1):p3e_cpu0_pe1_pch_r_rxn(11)" )
			)
			( signal "P3E_CPU0_PE1_PCH_R_RXN<12>"
				( objectStatus "@baseboard_fab2_lib.baseboard_fab2(sch_1):p3e_cpu0_pe1_pch_r_rxn(12)" )
			)
			( signal "P3E_CPU0_PE1_PCH_R_RXN<13>"
				( objectStatus "@baseboard_fab2_lib.baseboard_fab2(sch_1):p3e_cpu0_pe1_pch_r_rxn(13)" )
			)
			( signal "P3E_CPU0_PE1_PCH_R_RXN<14>"
				( objectStatus "@baseboard_fab2_lib.baseboard_fab2(sch_1):p3e_cpu0_pe1_pch_r_rxn(14)" )
			)
			( signal "P3E_CPU0_PE1_PCH_R_RXN<15>"
				( objectStatus "@baseboard_fab2_lib.baseboard_fab2(sch_1):p3e_cpu0_pe1_pch_r_rxn(15)" )
			)
			( signal "P3E_CPU0_PE1_PCH_R_RXP<8>"
				( objectStatus "@baseboard_fab2_lib.baseboard_fab2(sch_1):p3e_cpu0_pe1_pch_r_rxp(8)" )
			)
			( signal "P3E_CPU0_PE1_PCH_R_RXP<9>"
				( objectStatus "@baseboard_fab2_lib.baseboard_fab2(sch_1):p3e_cpu0_pe1_pch_r_rxp(9)" )
			)
			( signal "P3E_CPU0_PE1_PCH_R_RXP<10>"
				( objectStatus "@baseboard_fab2_lib.baseboard_fab2(sch_1):p3e_cpu0_pe1_pch_r_rxp(10)" )
			)
			( signal "P3E_CPU0_PE1_PCH_R_RXP<11>"
				( objectStatus "@baseboard_fab2_lib.baseboard_fab2(sch_1):p3e_cpu0_pe1_pch_r_rxp(11)" )
			)
			( signal "P3E_CPU0_PE1_PCH_R_RXP<12>"
				( objectStatus "@baseboard_fab2_lib.baseboard_fab2(sch_1):p3e_cpu0_pe1_pch_r_rxp(12)" )
			)
			( signal "P3E_CPU0_PE1_PCH_R_RXP<13>"
				( objectStatus "@baseboard_fab2_lib.baseboard_fab2(sch_1):p3e_cpu0_pe1_pch_r_rxp(13)" )
			)
			( signal "P3E_CPU0_PE1_PCH_R_RXP<14>"
				( objectStatus "@baseboard_fab2_lib.baseboard_fab2(sch_1):p3e_cpu0_pe1_pch_r_rxp(14)" )
			)
			( signal "P3E_CPU0_PE1_PCH_R_RXP<15>"
				( objectStatus "@baseboard_fab2_lib.baseboard_fab2(sch_1):p3e_cpu0_pe1_pch_r_rxp(15)" )
			)
			( signal "P3E_CPU0_PE2_SS_C_TXN<0>"
				( objectStatus "@baseboard_fab2_lib.baseboard_fab2(sch_1):p3e_cpu0_pe2_ss_c_txn(0)" )
			)
			( signal "P3E_CPU0_PE2_SS_C_TXN<1>"
				( objectStatus "@baseboard_fab2_lib.baseboard_fab2(sch_1):p3e_cpu0_pe2_ss_c_txn(1)" )
			)
			( signal "P3E_CPU0_PE2_SS_C_TXN<2>"
				( objectStatus "@baseboard_fab2_lib.baseboard_fab2(sch_1):p3e_cpu0_pe2_ss_c_txn(2)" )
			)
			( signal "P3E_CPU0_PE2_SS_C_TXN<3>"
				( objectStatus "@baseboard_fab2_lib.baseboard_fab2(sch_1):p3e_cpu0_pe2_ss_c_txn(3)" )
			)
			( signal "P3E_CPU0_PE2_SS_C_TXN<4>"
				( objectStatus "@baseboard_fab2_lib.baseboard_fab2(sch_1):p3e_cpu0_pe2_ss_c_txn(4)" )
			)
			( signal "P3E_CPU0_PE2_SS_C_TXN<5>"
				( objectStatus "@baseboard_fab2_lib.baseboard_fab2(sch_1):p3e_cpu0_pe2_ss_c_txn(5)" )
			)
			( signal "P3E_CPU0_PE2_SS_C_TXN<6>"
				( objectStatus "@baseboard_fab2_lib.baseboard_fab2(sch_1):p3e_cpu0_pe2_ss_c_txn(6)" )
			)
			( signal "P3E_CPU0_PE2_SS_C_TXN<7>"
				( objectStatus "@baseboard_fab2_lib.baseboard_fab2(sch_1):p3e_cpu0_pe2_ss_c_txn(7)" )
			)
			( signal "P3E_CPU0_PE2_SS_C_TXN<8>"
				( objectStatus "@baseboard_fab2_lib.baseboard_fab2(sch_1):p3e_cpu0_pe2_ss_c_txn(8)" )
			)
			( signal "P3E_CPU0_PE2_SS_C_TXN<9>"
				( objectStatus "@baseboard_fab2_lib.baseboard_fab2(sch_1):p3e_cpu0_pe2_ss_c_txn(9)" )
			)
			( signal "P3E_CPU0_PE2_SS_C_TXN<10>"
				( objectStatus "@baseboard_fab2_lib.baseboard_fab2(sch_1):p3e_cpu0_pe2_ss_c_txn(10)" )
			)
			( signal "P3E_CPU0_PE2_SS_C_TXN<11>"
				( objectStatus "@baseboard_fab2_lib.baseboard_fab2(sch_1):p3e_cpu0_pe2_ss_c_txn(11)" )
			)
			( signal "P3E_CPU0_PE2_SS_C_TXN<12>"
				( objectStatus "@baseboard_fab2_lib.baseboard_fab2(sch_1):p3e_cpu0_pe2_ss_c_txn(12)" )
			)
			( signal "P3E_CPU0_PE2_SS_C_TXN<13>"
				( objectStatus "@baseboard_fab2_lib.baseboard_fab2(sch_1):p3e_cpu0_pe2_ss_c_txn(13)" )
			)
			( signal "P3E_CPU0_PE2_SS_C_TXN<14>"
				( objectStatus "@baseboard_fab2_lib.baseboard_fab2(sch_1):p3e_cpu0_pe2_ss_c_txn(14)" )
			)
			( signal "P3E_CPU0_PE2_SS_C_TXN<15>"
				( objectStatus "@baseboard_fab2_lib.baseboard_fab2(sch_1):p3e_cpu0_pe2_ss_c_txn(15)" )
			)
			( signal "P3E_CPU0_PE2_SS_C_TXP<0>"
				( objectStatus "@baseboard_fab2_lib.baseboard_fab2(sch_1):p3e_cpu0_pe2_ss_c_txp(0)" )
			)
			( signal "P3E_CPU0_PE2_SS_C_TXP<1>"
				( objectStatus "@baseboard_fab2_lib.baseboard_fab2(sch_1):p3e_cpu0_pe2_ss_c_txp(1)" )
			)
			( signal "P3E_CPU0_PE2_SS_C_TXP<2>"
				( objectStatus "@baseboard_fab2_lib.baseboard_fab2(sch_1):p3e_cpu0_pe2_ss_c_txp(2)" )
			)
			( signal "P3E_CPU0_PE2_SS_C_TXP<3>"
				( objectStatus "@baseboard_fab2_lib.baseboard_fab2(sch_1):p3e_cpu0_pe2_ss_c_txp(3)" )
			)
			( signal "P3E_CPU0_PE2_SS_C_TXP<4>"
				( objectStatus "@baseboard_fab2_lib.baseboard_fab2(sch_1):p3e_cpu0_pe2_ss_c_txp(4)" )
			)
			( signal "P3E_CPU0_PE2_SS_C_TXP<5>"
				( objectStatus "@baseboard_fab2_lib.baseboard_fab2(sch_1):p3e_cpu0_pe2_ss_c_txp(5)" )
			)
			( signal "P3E_CPU0_PE2_SS_C_TXP<6>"
				( objectStatus "@baseboard_fab2_lib.baseboard_fab2(sch_1):p3e_cpu0_pe2_ss_c_txp(6)" )
			)
			( signal "P3E_CPU0_PE2_SS_C_TXP<7>"
				( objectStatus "@baseboard_fab2_lib.baseboard_fab2(sch_1):p3e_cpu0_pe2_ss_c_txp(7)" )
			)
			( signal "P3E_CPU0_PE2_SS_C_TXP<8>"
				( objectStatus "@baseboard_fab2_lib.baseboard_fab2(sch_1):p3e_cpu0_pe2_ss_c_txp(8)" )
			)
			( signal "P3E_CPU0_PE2_SS_C_TXP<9>"
				( objectStatus "@baseboard_fab2_lib.baseboard_fab2(sch_1):p3e_cpu0_pe2_ss_c_txp(9)" )
			)
			( signal "P3E_CPU0_PE2_SS_C_TXP<10>"
				( objectStatus "@baseboard_fab2_lib.baseboard_fab2(sch_1):p3e_cpu0_pe2_ss_c_txp(10)" )
			)
			( signal "P3E_CPU0_PE2_SS_C_TXP<11>"
				( objectStatus "@baseboard_fab2_lib.baseboard_fab2(sch_1):p3e_cpu0_pe2_ss_c_txp(11)" )
			)
			( signal "P3E_CPU0_PE2_SS_C_TXP<12>"
				( objectStatus "@baseboard_fab2_lib.baseboard_fab2(sch_1):p3e_cpu0_pe2_ss_c_txp(12)" )
			)
			( signal "P3E_CPU0_PE2_SS_C_TXP<13>"
				( objectStatus "@baseboard_fab2_lib.baseboard_fab2(sch_1):p3e_cpu0_pe2_ss_c_txp(13)" )
			)
			( signal "P3E_CPU0_PE2_SS_C_TXP<14>"
				( objectStatus "@baseboard_fab2_lib.baseboard_fab2(sch_1):p3e_cpu0_pe2_ss_c_txp(14)" )
			)
			( signal "P3E_CPU0_PE2_SS_C_TXP<15>"
				( objectStatus "@baseboard_fab2_lib.baseboard_fab2(sch_1):p3e_cpu0_pe2_ss_c_txp(15)" )
			)
			( signal "P3E_OCP_CPU0_PE3_C_TXN<0>"
				( objectStatus "@baseboard_fab2_lib.baseboard_fab2(sch_1):p3e_ocp_cpu0_pe3_c_txn(0)" )
			)
			( signal "P3E_OCP_CPU0_PE3_C_TXN<1>"
				( objectStatus "@baseboard_fab2_lib.baseboard_fab2(sch_1):p3e_ocp_cpu0_pe3_c_txn(1)" )
			)
			( signal "P3E_OCP_CPU0_PE3_C_TXN<2>"
				( objectStatus "@baseboard_fab2_lib.baseboard_fab2(sch_1):p3e_ocp_cpu0_pe3_c_txn(2)" )
			)
			( signal "P3E_OCP_CPU0_PE3_C_TXN<3>"
				( objectStatus "@baseboard_fab2_lib.baseboard_fab2(sch_1):p3e_ocp_cpu0_pe3_c_txn(3)" )
			)
			( signal "P3E_OCP_CPU0_PE3_C_TXN<4>"
				( objectStatus "@baseboard_fab2_lib.baseboard_fab2(sch_1):p3e_ocp_cpu0_pe3_c_txn(4)" )
			)
			( signal "P3E_OCP_CPU0_PE3_C_TXN<5>"
				( objectStatus "@baseboard_fab2_lib.baseboard_fab2(sch_1):p3e_ocp_cpu0_pe3_c_txn(5)" )
			)
			( signal "P3E_OCP_CPU0_PE3_C_TXN<6>"
				( objectStatus "@baseboard_fab2_lib.baseboard_fab2(sch_1):p3e_ocp_cpu0_pe3_c_txn(6)" )
			)
			( signal "P3E_OCP_CPU0_PE3_C_TXN<7>"
				( objectStatus "@baseboard_fab2_lib.baseboard_fab2(sch_1):p3e_ocp_cpu0_pe3_c_txn(7)" )
			)
			( signal "P3E_OCP_CPU0_PE3_C_TXN<8>"
				( objectStatus "@baseboard_fab2_lib.baseboard_fab2(sch_1):p3e_ocp_cpu0_pe3_c_txn(8)" )
			)
			( signal "P3E_OCP_CPU0_PE3_C_TXN<9>"
				( objectStatus "@baseboard_fab2_lib.baseboard_fab2(sch_1):p3e_ocp_cpu0_pe3_c_txn(9)" )
			)
			( signal "P3E_OCP_CPU0_PE3_C_TXN<10>"
				( objectStatus "@baseboard_fab2_lib.baseboard_fab2(sch_1):p3e_ocp_cpu0_pe3_c_txn(10)" )
			)
			( signal "P3E_OCP_CPU0_PE3_C_TXN<11>"
				( objectStatus "@baseboard_fab2_lib.baseboard_fab2(sch_1):p3e_ocp_cpu0_pe3_c_txn(11)" )
			)
			( signal "P3E_OCP_CPU0_PE3_C_TXN<12>"
				( objectStatus "@baseboard_fab2_lib.baseboard_fab2(sch_1):p3e_ocp_cpu0_pe3_c_txn(12)" )
			)
			( signal "P3E_OCP_CPU0_PE3_C_TXN<13>"
				( objectStatus "@baseboard_fab2_lib.baseboard_fab2(sch_1):p3e_ocp_cpu0_pe3_c_txn(13)" )
			)
			( signal "P3E_OCP_CPU0_PE3_C_TXN<14>"
				( objectStatus "@baseboard_fab2_lib.baseboard_fab2(sch_1):p3e_ocp_cpu0_pe3_c_txn(14)" )
			)
			( signal "P3E_OCP_CPU0_PE3_C_TXN<15>"
				( objectStatus "@baseboard_fab2_lib.baseboard_fab2(sch_1):p3e_ocp_cpu0_pe3_c_txn(15)" )
			)
			( signal "P3E_OCP_CPU0_PE3_C_TXP<0>"
				( objectStatus "@baseboard_fab2_lib.baseboard_fab2(sch_1):p3e_ocp_cpu0_pe3_c_txp(0)" )
			)
			( signal "P3E_OCP_CPU0_PE3_C_TXP<1>"
				( objectStatus "@baseboard_fab2_lib.baseboard_fab2(sch_1):p3e_ocp_cpu0_pe3_c_txp(1)" )
			)
			( signal "P3E_OCP_CPU0_PE3_C_TXP<2>"
				( objectStatus "@baseboard_fab2_lib.baseboard_fab2(sch_1):p3e_ocp_cpu0_pe3_c_txp(2)" )
			)
			( signal "P3E_OCP_CPU0_PE3_C_TXP<3>"
				( objectStatus "@baseboard_fab2_lib.baseboard_fab2(sch_1):p3e_ocp_cpu0_pe3_c_txp(3)" )
			)
			( signal "P3E_OCP_CPU0_PE3_C_TXP<4>"
				( objectStatus "@baseboard_fab2_lib.baseboard_fab2(sch_1):p3e_ocp_cpu0_pe3_c_txp(4)" )
			)
			( signal "P3E_OCP_CPU0_PE3_C_TXP<5>"
				( objectStatus "@baseboard_fab2_lib.baseboard_fab2(sch_1):p3e_ocp_cpu0_pe3_c_txp(5)" )
			)
			( signal "P3E_OCP_CPU0_PE3_C_TXP<6>"
				( objectStatus "@baseboard_fab2_lib.baseboard_fab2(sch_1):p3e_ocp_cpu0_pe3_c_txp(6)" )
			)
			( signal "P3E_OCP_CPU0_PE3_C_TXP<7>"
				( objectStatus "@baseboard_fab2_lib.baseboard_fab2(sch_1):p3e_ocp_cpu0_pe3_c_txp(7)" )
			)
			( signal "P3E_OCP_CPU0_PE3_C_TXP<8>"
				( objectStatus "@baseboard_fab2_lib.baseboard_fab2(sch_1):p3e_ocp_cpu0_pe3_c_txp(8)" )
			)
			( signal "P3E_OCP_CPU0_PE3_C_TXP<9>"
				( objectStatus "@baseboard_fab2_lib.baseboard_fab2(sch_1):p3e_ocp_cpu0_pe3_c_txp(9)" )
			)
			( signal "P3E_OCP_CPU0_PE3_C_TXP<10>"
				( objectStatus "@baseboard_fab2_lib.baseboard_fab2(sch_1):p3e_ocp_cpu0_pe3_c_txp(10)" )
			)
			( signal "P3E_OCP_CPU0_PE3_C_TXP<11>"
				( objectStatus "@baseboard_fab2_lib.baseboard_fab2(sch_1):p3e_ocp_cpu0_pe3_c_txp(11)" )
			)
			( signal "P3E_OCP_CPU0_PE3_C_TXP<12>"
				( objectStatus "@baseboard_fab2_lib.baseboard_fab2(sch_1):p3e_ocp_cpu0_pe3_c_txp(12)" )
			)
			( signal "P3E_OCP_CPU0_PE3_C_TXP<13>"
				( objectStatus "@baseboard_fab2_lib.baseboard_fab2(sch_1):p3e_ocp_cpu0_pe3_c_txp(13)" )
			)
			( signal "P3E_OCP_CPU0_PE3_C_TXP<14>"
				( objectStatus "@baseboard_fab2_lib.baseboard_fab2(sch_1):p3e_ocp_cpu0_pe3_c_txp(14)" )
			)
			( signal "P3E_OCP_CPU0_PE3_C_TXP<15>"
				( objectStatus "@baseboard_fab2_lib.baseboard_fab2(sch_1):p3e_ocp_cpu0_pe3_c_txp(15)" )
			)
			( signal "P3E_CPU0_PE1_PCH_RXN<0>"
				( objectStatus "@baseboard_fab2_lib.baseboard_fab2(sch_1):p3e_cpu0_pe1_pch_rxn(0)" )
			)
			( signal "P3E_CPU0_PE1_PCH_RXN<1>"
				( objectStatus "@baseboard_fab2_lib.baseboard_fab2(sch_1):p3e_cpu0_pe1_pch_rxn(1)" )
			)
			( signal "P3E_CPU0_PE1_PCH_RXN<2>"
				( objectStatus "@baseboard_fab2_lib.baseboard_fab2(sch_1):p3e_cpu0_pe1_pch_rxn(2)" )
			)
			( signal "P3E_CPU0_PE1_PCH_RXN<3>"
				( objectStatus "@baseboard_fab2_lib.baseboard_fab2(sch_1):p3e_cpu0_pe1_pch_rxn(3)" )
			)
			( signal "P3E_CPU0_PE1_PCH_RXN<4>"
				( objectStatus "@baseboard_fab2_lib.baseboard_fab2(sch_1):p3e_cpu0_pe1_pch_rxn(4)" )
			)
			( signal "P3E_CPU0_PE1_PCH_RXN<5>"
				( objectStatus "@baseboard_fab2_lib.baseboard_fab2(sch_1):p3e_cpu0_pe1_pch_rxn(5)" )
			)
			( signal "P3E_CPU0_PE1_PCH_RXN<6>"
				( objectStatus "@baseboard_fab2_lib.baseboard_fab2(sch_1):p3e_cpu0_pe1_pch_rxn(6)" )
			)
			( signal "P3E_CPU0_PE1_PCH_RXN<7>"
				( objectStatus "@baseboard_fab2_lib.baseboard_fab2(sch_1):p3e_cpu0_pe1_pch_rxn(7)" )
			)
			( signal "P3E_CPU0_PE1_PCH_RXP<0>"
				( objectStatus "@baseboard_fab2_lib.baseboard_fab2(sch_1):p3e_cpu0_pe1_pch_rxp(0)" )
			)
			( signal "P3E_CPU0_PE1_PCH_RXP<1>"
				( objectStatus "@baseboard_fab2_lib.baseboard_fab2(sch_1):p3e_cpu0_pe1_pch_rxp(1)" )
			)
			( signal "P3E_CPU0_PE1_PCH_RXP<2>"
				( objectStatus "@baseboard_fab2_lib.baseboard_fab2(sch_1):p3e_cpu0_pe1_pch_rxp(2)" )
			)
			( signal "P3E_CPU0_PE1_PCH_RXP<3>"
				( objectStatus "@baseboard_fab2_lib.baseboard_fab2(sch_1):p3e_cpu0_pe1_pch_rxp(3)" )
			)
			( signal "P3E_CPU0_PE1_PCH_RXP<4>"
				( objectStatus "@baseboard_fab2_lib.baseboard_fab2(sch_1):p3e_cpu0_pe1_pch_rxp(4)" )
			)
			( signal "P3E_CPU0_PE1_PCH_RXP<5>"
				( objectStatus "@baseboard_fab2_lib.baseboard_fab2(sch_1):p3e_cpu0_pe1_pch_rxp(5)" )
			)
			( signal "P3E_CPU0_PE1_PCH_RXP<6>"
				( objectStatus "@baseboard_fab2_lib.baseboard_fab2(sch_1):p3e_cpu0_pe1_pch_rxp(6)" )
			)
			( signal "P3E_CPU0_PE1_PCH_RXP<7>"
				( objectStatus "@baseboard_fab2_lib.baseboard_fab2(sch_1):p3e_cpu0_pe1_pch_rxp(7)" )
			)
			( signal "P3E_CPU0_PE1_PCH_TXN<0>"
				( objectStatus "@baseboard_fab2_lib.baseboard_fab2(sch_1):p3e_cpu0_pe1_pch_txn(0)" )
			)
			( signal "P3E_CPU0_PE1_PCH_TXN<1>"
				( objectStatus "@baseboard_fab2_lib.baseboard_fab2(sch_1):p3e_cpu0_pe1_pch_txn(1)" )
			)
			( signal "P3E_CPU0_PE1_PCH_TXN<2>"
				( objectStatus "@baseboard_fab2_lib.baseboard_fab2(sch_1):p3e_cpu0_pe1_pch_txn(2)" )
			)
			( signal "P3E_CPU0_PE1_PCH_TXN<3>"
				( objectStatus "@baseboard_fab2_lib.baseboard_fab2(sch_1):p3e_cpu0_pe1_pch_txn(3)" )
			)
			( signal "P3E_CPU0_PE1_PCH_TXN<4>"
				( objectStatus "@baseboard_fab2_lib.baseboard_fab2(sch_1):p3e_cpu0_pe1_pch_txn(4)" )
			)
			( signal "P3E_CPU0_PE1_PCH_TXN<5>"
				( objectStatus "@baseboard_fab2_lib.baseboard_fab2(sch_1):p3e_cpu0_pe1_pch_txn(5)" )
			)
			( signal "P3E_CPU0_PE1_PCH_TXN<6>"
				( objectStatus "@baseboard_fab2_lib.baseboard_fab2(sch_1):p3e_cpu0_pe1_pch_txn(6)" )
			)
			( signal "P3E_CPU0_PE1_PCH_TXN<7>"
				( objectStatus "@baseboard_fab2_lib.baseboard_fab2(sch_1):p3e_cpu0_pe1_pch_txn(7)" )
			)
			( signal "P3E_CPU0_PE1_PCH_TXP<0>"
				( objectStatus "@baseboard_fab2_lib.baseboard_fab2(sch_1):p3e_cpu0_pe1_pch_txp(0)" )
			)
			( signal "P3E_CPU0_PE1_PCH_TXP<1>"
				( objectStatus "@baseboard_fab2_lib.baseboard_fab2(sch_1):p3e_cpu0_pe1_pch_txp(1)" )
			)
			( signal "P3E_CPU0_PE1_PCH_TXP<2>"
				( objectStatus "@baseboard_fab2_lib.baseboard_fab2(sch_1):p3e_cpu0_pe1_pch_txp(2)" )
			)
			( signal "P3E_CPU0_PE1_PCH_TXP<3>"
				( objectStatus "@baseboard_fab2_lib.baseboard_fab2(sch_1):p3e_cpu0_pe1_pch_txp(3)" )
			)
			( signal "P3E_CPU0_PE1_PCH_TXP<4>"
				( objectStatus "@baseboard_fab2_lib.baseboard_fab2(sch_1):p3e_cpu0_pe1_pch_txp(4)" )
			)
			( signal "P3E_CPU0_PE1_PCH_TXP<5>"
				( objectStatus "@baseboard_fab2_lib.baseboard_fab2(sch_1):p3e_cpu0_pe1_pch_txp(5)" )
			)
			( signal "P3E_CPU0_PE1_PCH_TXP<6>"
				( objectStatus "@baseboard_fab2_lib.baseboard_fab2(sch_1):p3e_cpu0_pe1_pch_txp(6)" )
			)
			( signal "P3E_CPU0_PE1_PCH_TXP<7>"
				( objectStatus "@baseboard_fab2_lib.baseboard_fab2(sch_1):p3e_cpu0_pe1_pch_txp(7)" )
			)
			( signal "P3E_CPU0_PE1_SS_C_TXN<0>"
				( objectStatus "@baseboard_fab2_lib.baseboard_fab2(sch_1):p3e_cpu0_pe1_ss_c_txn(0)" )
			)
			( signal "P3E_CPU0_PE1_SS_C_TXN<1>"
				( objectStatus "@baseboard_fab2_lib.baseboard_fab2(sch_1):p3e_cpu0_pe1_ss_c_txn(1)" )
			)
			( signal "P3E_CPU0_PE1_SS_C_TXN<2>"
				( objectStatus "@baseboard_fab2_lib.baseboard_fab2(sch_1):p3e_cpu0_pe1_ss_c_txn(2)" )
			)
			( signal "P3E_CPU0_PE1_SS_C_TXN<3>"
				( objectStatus "@baseboard_fab2_lib.baseboard_fab2(sch_1):p3e_cpu0_pe1_ss_c_txn(3)" )
			)
			( signal "P3E_CPU0_PE1_SS_C_TXN<4>"
				( objectStatus "@baseboard_fab2_lib.baseboard_fab2(sch_1):p3e_cpu0_pe1_ss_c_txn(4)" )
			)
			( signal "P3E_CPU0_PE1_SS_C_TXN<5>"
				( objectStatus "@baseboard_fab2_lib.baseboard_fab2(sch_1):p3e_cpu0_pe1_ss_c_txn(5)" )
			)
			( signal "P3E_CPU0_PE1_SS_C_TXN<6>"
				( objectStatus "@baseboard_fab2_lib.baseboard_fab2(sch_1):p3e_cpu0_pe1_ss_c_txn(6)" )
			)
			( signal "P3E_CPU0_PE1_SS_C_TXN<7>"
				( objectStatus "@baseboard_fab2_lib.baseboard_fab2(sch_1):p3e_cpu0_pe1_ss_c_txn(7)" )
			)
			( signal "P3E_CPU0_PE1_SS_C_TXP<0>"
				( objectStatus "@baseboard_fab2_lib.baseboard_fab2(sch_1):p3e_cpu0_pe1_ss_c_txp(0)" )
			)
			( signal "P3E_CPU0_PE1_SS_C_TXP<1>"
				( objectStatus "@baseboard_fab2_lib.baseboard_fab2(sch_1):p3e_cpu0_pe1_ss_c_txp(1)" )
			)
			( signal "P3E_CPU0_PE1_SS_C_TXP<2>"
				( objectStatus "@baseboard_fab2_lib.baseboard_fab2(sch_1):p3e_cpu0_pe1_ss_c_txp(2)" )
			)
			( signal "P3E_CPU0_PE1_SS_C_TXP<3>"
				( objectStatus "@baseboard_fab2_lib.baseboard_fab2(sch_1):p3e_cpu0_pe1_ss_c_txp(3)" )
			)
			( signal "P3E_CPU0_PE1_SS_C_TXP<4>"
				( objectStatus "@baseboard_fab2_lib.baseboard_fab2(sch_1):p3e_cpu0_pe1_ss_c_txp(4)" )
			)
			( signal "P3E_CPU0_PE1_SS_C_TXP<5>"
				( objectStatus "@baseboard_fab2_lib.baseboard_fab2(sch_1):p3e_cpu0_pe1_ss_c_txp(5)" )
			)
			( signal "P3E_CPU0_PE1_SS_C_TXP<6>"
				( objectStatus "@baseboard_fab2_lib.baseboard_fab2(sch_1):p3e_cpu0_pe1_ss_c_txp(6)" )
			)
			( signal "P3E_CPU0_PE1_SS_C_TXP<7>"
				( objectStatus "@baseboard_fab2_lib.baseboard_fab2(sch_1):p3e_cpu0_pe1_ss_c_txp(7)" )
			)
			( signal "P3E_CPU0_PE1_SS_R_RXN<0>"
				( objectStatus "@baseboard_fab2_lib.baseboard_fab2(sch_1):p3e_cpu0_pe1_ss_r_rxn(0)" )
			)
			( signal "P3E_CPU0_PE1_SS_R_RXN<1>"
				( objectStatus "@baseboard_fab2_lib.baseboard_fab2(sch_1):p3e_cpu0_pe1_ss_r_rxn(1)" )
			)
			( signal "P3E_CPU0_PE1_SS_R_RXN<2>"
				( objectStatus "@baseboard_fab2_lib.baseboard_fab2(sch_1):p3e_cpu0_pe1_ss_r_rxn(2)" )
			)
			( signal "P3E_CPU0_PE1_SS_R_RXN<3>"
				( objectStatus "@baseboard_fab2_lib.baseboard_fab2(sch_1):p3e_cpu0_pe1_ss_r_rxn(3)" )
			)
			( signal "P3E_CPU0_PE1_SS_R_RXN<4>"
				( objectStatus "@baseboard_fab2_lib.baseboard_fab2(sch_1):p3e_cpu0_pe1_ss_r_rxn(4)" )
			)
			( signal "P3E_CPU0_PE1_SS_R_RXN<5>"
				( objectStatus "@baseboard_fab2_lib.baseboard_fab2(sch_1):p3e_cpu0_pe1_ss_r_rxn(5)" )
			)
			( signal "P3E_CPU0_PE1_SS_R_RXN<6>"
				( objectStatus "@baseboard_fab2_lib.baseboard_fab2(sch_1):p3e_cpu0_pe1_ss_r_rxn(6)" )
			)
			( signal "P3E_CPU0_PE1_SS_R_RXN<7>"
				( objectStatus "@baseboard_fab2_lib.baseboard_fab2(sch_1):p3e_cpu0_pe1_ss_r_rxn(7)" )
			)
			( signal "P3E_CPU0_PE1_SS_R_RXP<0>"
				( objectStatus "@baseboard_fab2_lib.baseboard_fab2(sch_1):p3e_cpu0_pe1_ss_r_rxp(0)" )
			)
			( signal "P3E_CPU0_PE1_SS_R_RXP<1>"
				( objectStatus "@baseboard_fab2_lib.baseboard_fab2(sch_1):p3e_cpu0_pe1_ss_r_rxp(1)" )
			)
			( signal "P3E_CPU0_PE1_SS_R_RXP<2>"
				( objectStatus "@baseboard_fab2_lib.baseboard_fab2(sch_1):p3e_cpu0_pe1_ss_r_rxp(2)" )
			)
			( signal "P3E_CPU0_PE1_SS_R_RXP<3>"
				( objectStatus "@baseboard_fab2_lib.baseboard_fab2(sch_1):p3e_cpu0_pe1_ss_r_rxp(3)" )
			)
			( signal "P3E_CPU0_PE1_SS_R_RXP<4>"
				( objectStatus "@baseboard_fab2_lib.baseboard_fab2(sch_1):p3e_cpu0_pe1_ss_r_rxp(4)" )
			)
			( signal "P3E_CPU0_PE1_SS_R_RXP<5>"
				( objectStatus "@baseboard_fab2_lib.baseboard_fab2(sch_1):p3e_cpu0_pe1_ss_r_rxp(5)" )
			)
			( signal "P3E_CPU0_PE1_SS_R_RXP<6>"
				( objectStatus "@baseboard_fab2_lib.baseboard_fab2(sch_1):p3e_cpu0_pe1_ss_r_rxp(6)" )
			)
			( signal "P3E_CPU0_PE1_SS_R_RXP<7>"
				( objectStatus "@baseboard_fab2_lib.baseboard_fab2(sch_1):p3e_cpu0_pe1_ss_r_rxp(7)" )
			)
			( signal "CLK_100M_PCH_SLOTX24_S0_DN"
				( objectStatus "@baseboard_fab2_lib.baseboard_fab2(sch_1):clk_100m_pch_slotx24_s0_dn" )
			)
			( signal "CLK_100M_PCH_SLOTX24_S0_DP"
				( objectStatus "@baseboard_fab2_lib.baseboard_fab2(sch_1):clk_100m_pch_slotx24_s0_dp" )
			)
			( signal "CLK_100M_PCH_SLOTX24_S1_DN"
				( objectStatus "@baseboard_fab2_lib.baseboard_fab2(sch_1):clk_100m_pch_slotx24_s1_dn" )
			)
			( signal "CLK_100M_PCH_SLOTX24_S1_DP"
				( objectStatus "@baseboard_fab2_lib.baseboard_fab2(sch_1):clk_100m_pch_slotx24_s1_dp" )
			)
			( signal "CLK_100M_PCH_SLOTX24_S2_DN"
				( objectStatus "@baseboard_fab2_lib.baseboard_fab2(sch_1):clk_100m_pch_slotx24_s2_dn" )
			)
			( signal "CLK_100M_PCH_SLOTX24_S2_DP"
				( objectStatus "@baseboard_fab2_lib.baseboard_fab2(sch_1):clk_100m_pch_slotx24_s2_dp" )
			)
			( signal "CLK_100M_PCH_SLOTX24_S3_DN"
				( objectStatus "@baseboard_fab2_lib.baseboard_fab2(sch_1):clk_100m_pch_slotx24_s3_dn" )
			)
			( signal "CLK_100M_PCH_SLOTX24_S3_DP"
				( objectStatus "@baseboard_fab2_lib.baseboard_fab2(sch_1):clk_100m_pch_slotx24_s3_dp" )
			)
			( signal "CLK_100M_PCH_SLOTX24_S4_DN"
				( objectStatus "@baseboard_fab2_lib.baseboard_fab2(sch_1):clk_100m_pch_slotx24_s4_dn" )
			)
			( signal "CLK_100M_PCH_SLOTX24_S4_DP"
				( objectStatus "@baseboard_fab2_lib.baseboard_fab2(sch_1):clk_100m_pch_slotx24_s4_dp" )
			)
			( signal "CLK_100M_PCH_SLOTX24_S5_DN"
				( objectStatus "@baseboard_fab2_lib.baseboard_fab2(sch_1):clk_100m_pch_slotx24_s5_dn" )
			)
			( signal "CLK_100M_PCH_SLOTX24_S5_DP"
				( objectStatus "@baseboard_fab2_lib.baseboard_fab2(sch_1):clk_100m_pch_slotx24_s5_dp" )
			)
			( signal "FM_PE_SLOTX24_WAKE_N"
				( objectStatus "@baseboard_fab2_lib.baseboard_fab2(sch_1):fm_pe_slotx24_wake_n" )
			)
			( signal "FM_PRSNT_2_1_N"
				( objectStatus "@baseboard_fab2_lib.baseboard_fab2(sch_1):fm_prsnt_2_1_n" )
			)
			( signal "FM_PRSNT_2_2_N"
				( objectStatus "@baseboard_fab2_lib.baseboard_fab2(sch_1):fm_prsnt_2_2_n" )
			)
			( signal "FM_PRSNT_2_3_N"
				( objectStatus "@baseboard_fab2_lib.baseboard_fab2(sch_1):fm_prsnt_2_3_n" )
			)
			( signal "FM_PRSNT_2_4_N"
				( objectStatus "@baseboard_fab2_lib.baseboard_fab2(sch_1):fm_prsnt_2_4_n" )
			)
			( signal "FM_PRSNT_2_5_N"
				( objectStatus "@baseboard_fab2_lib.baseboard_fab2(sch_1):fm_prsnt_2_5_n" )
			)
			( signal "FM_PWRBRK_SLOT_N"
				( objectStatus "@baseboard_fab2_lib.baseboard_fab2(sch_1):fm_pwrbrk_slot_n" )
			)
			( signal "FM_SLT_CFG0"
				( objectStatus "@baseboard_fab2_lib.baseboard_fab2(sch_1):fm_slt_cfg0" )
			)
			( signal "FM_SLT_CFG1"
				( objectStatus "@baseboard_fab2_lib.baseboard_fab2(sch_1):fm_slt_cfg1" )
			)
			( signal "IRQ_OOB_MGMT_RISER_ALERT_N"
				( objectStatus "@baseboard_fab2_lib.baseboard_fab2(sch_1):irq_oob_mgmt_riser_alert_n" )
			)
			( signal "P12V"
				( attribute "VOLTAGE" "+12."
					( Units "uVoltage" "V" 1.000000)
					( Status sAliasFlattened )
					( Status sAliasConflict )
					( Origin gFrontEnd )
				)
				( objectStatus "@baseboard_fab2_lib.baseboard_fab2(sch_1):p12v" )
			)
			( signal "RST_PCIE_RISER1_PERST_N"
				( objectStatus "@baseboard_fab2_lib.baseboard_fab2(sch_1):rst_pcie_riser1_perst_n" )
			)
			( signal "RST_PCIE_RISER1_PERST_R_N"
				( objectStatus "@baseboard_fab2_lib.baseboard_fab2(sch_1):rst_pcie_riser1_perst_r_n" )
			)
			( signal "SMB_SLOTX24_BMC_STBY_LVC3_SCL"
				( objectStatus "@baseboard_fab2_lib.baseboard_fab2(sch_1):smb_slotx24_bmc_stby_lvc3_scl" )
			)
			( signal "SMB_SLOTX24_BMC_STBY_LVC3_SDA"
				( objectStatus "@baseboard_fab2_lib.baseboard_fab2(sch_1):smb_slotx24_bmc_stby_lvc3_sda" )
			)
			( signal "SMB_SLOTX24_PCH_STBY_LVC3_SCL"
				( objectStatus "@baseboard_fab2_lib.baseboard_fab2(sch_1):smb_slotx24_pch_stby_lvc3_scl" )
			)
			( signal "SMB_SLOTX24_PCH_STBY_LVC3_SDA"
				( objectStatus "@baseboard_fab2_lib.baseboard_fab2(sch_1):smb_slotx24_pch_stby_lvc3_sda" )
			)
			( signal "SMB_SLOTX24_STBY_LVC3_SCL_R2"
				( objectStatus "@baseboard_fab2_lib.baseboard_fab2(sch_1):smb_slotx24_stby_lvc3_scl_r2" )
			)
			( signal "SMB_SLOTX24_STBY_LVC3_SDA_R2"
				( objectStatus "@baseboard_fab2_lib.baseboard_fab2(sch_1):smb_slotx24_stby_lvc3_sda_r2" )
			)
			( signal "FM_PRSNT_2_6_N"
				( objectStatus "@baseboard_fab2_lib.baseboard_fab2(sch_1):fm_prsnt_2_6_n" )
			)
			( signal "RCC_DFX_1940_1"
				( objectStatus "@baseboard_fab2_lib.baseboard_fab2(sch_1):rcc_dfx_1940_1" )
			)
			( signal "RCC_DFX_1940_2"
				( objectStatus "@baseboard_fab2_lib.baseboard_fab2(sch_1):rcc_dfx_1940_2" )
			)
			( signal "RCC_DFX_1940_3"
				( objectStatus "@baseboard_fab2_lib.baseboard_fab2(sch_1):rcc_dfx_1940_3" )
			)
			( signal "RCC_DFX_1940_4"
				( objectStatus "@baseboard_fab2_lib.baseboard_fab2(sch_1):rcc_dfx_1940_4" )
			)
			( signal "CLK_100M_PCH_XDP_DN"
				( objectStatus "@baseboard_fab2_lib.baseboard_fab2(sch_1):clk_100m_pch_xdp_dn" )
			)
			( signal "CLK_100M_PCH_XDP_DP"
				( objectStatus "@baseboard_fab2_lib.baseboard_fab2(sch_1):clk_100m_pch_xdp_dp" )
			)
			( signal "FM_DEBUG_RST_BTN_N"
				( objectStatus "@baseboard_fab2_lib.baseboard_fab2(sch_1):fm_debug_rst_btn_n" )
			)
			( signal "FM_DEBUG_RST_BTN_R1_N"
				( objectStatus "@baseboard_fab2_lib.baseboard_fab2(sch_1):fm_debug_rst_btn_r1_n" )
			)
			( signal "P1V05_PCH_STBY"
				( attribute "VOLTAGE" "1.05V"
					( Units "uVoltage" "V" 1.000000)
					( Status sAliasFlattened )
					( Origin gFrontEnd )
				)
				( objectStatus "@baseboard_fab2_lib.baseboard_fab2(sch_1):p1v05_pch_stby" )
			)
			( signal "RST_RSMRST_N"
				( objectStatus "@baseboard_fab2_lib.baseboard_fab2(sch_1):rst_rsmrst_n" )
			)
			( signal "SPI_PCH_IO2"
				( objectStatus "@baseboard_fab2_lib.baseboard_fab2(sch_1):spi_pch_io2" )
			)
			( signal "SPI_PCH_MOSI"
				( objectStatus "@baseboard_fab2_lib.baseboard_fab2(sch_1):spi_pch_mosi" )
			)
			( signal "TP_XDP_CPU_OBSDATA_C0"
				( objectStatus "@baseboard_fab2_lib.baseboard_fab2(sch_1):tp_xdp_cpu_obsdata_c0" )
			)
			( signal "TP_XDP_CPU_OBSDATA_C1"
				( objectStatus "@baseboard_fab2_lib.baseboard_fab2(sch_1):tp_xdp_cpu_obsdata_c1" )
			)
			( signal "TP_XDP_CPU_OBSDATA_C2"
				( objectStatus "@baseboard_fab2_lib.baseboard_fab2(sch_1):tp_xdp_cpu_obsdata_c2" )
			)
			( signal "TP_XDP_CPU_OBSDATA_C3"
				( objectStatus "@baseboard_fab2_lib.baseboard_fab2(sch_1):tp_xdp_cpu_obsdata_c3" )
			)
			( signal "TP_XDP_CPU_OBSDATA_D0"
				( objectStatus "@baseboard_fab2_lib.baseboard_fab2(sch_1):tp_xdp_cpu_obsdata_d0" )
			)
			( signal "TP_XDP_CPU_OBSDATA_D1"
				( objectStatus "@baseboard_fab2_lib.baseboard_fab2(sch_1):tp_xdp_cpu_obsdata_d1" )
			)
			( signal "TP_XDP_CPU_OBSDATA_D2"
				( objectStatus "@baseboard_fab2_lib.baseboard_fab2(sch_1):tp_xdp_cpu_obsdata_d2" )
			)
			( signal "TP_XDP_CPU_OBSDATA_D3"
				( objectStatus "@baseboard_fab2_lib.baseboard_fab2(sch_1):tp_xdp_cpu_obsdata_d3" )
			)
			( signal "TP_XDP_CPU_OBSFN_C0"
				( objectStatus "@baseboard_fab2_lib.baseboard_fab2(sch_1):tp_xdp_cpu_obsfn_c0" )
			)
			( signal "TP_XDP_OBSDATA_A0"
				( objectStatus "@baseboard_fab2_lib.baseboard_fab2(sch_1):tp_xdp_obsdata_a0" )
			)
			( signal "TP_XDP_OBSDATA_A1"
				( objectStatus "@baseboard_fab2_lib.baseboard_fab2(sch_1):tp_xdp_obsdata_a1" )
			)
			( signal "TP_XDP_OBSDATA_A2"
				( objectStatus "@baseboard_fab2_lib.baseboard_fab2(sch_1):tp_xdp_obsdata_a2" )
			)
			( signal "TP_XDP_OBSDATA_A3"
				( objectStatus "@baseboard_fab2_lib.baseboard_fab2(sch_1):tp_xdp_obsdata_a3" )
			)
			( signal "TP_XDP_OBSDATA_B0"
				( objectStatus "@baseboard_fab2_lib.baseboard_fab2(sch_1):tp_xdp_obsdata_b0" )
			)
			( signal "TP_XDP_OBSDATA_B1"
				( objectStatus "@baseboard_fab2_lib.baseboard_fab2(sch_1):tp_xdp_obsdata_b1" )
			)
			( signal "TP_XDP_OBSDATA_B2"
				( objectStatus "@baseboard_fab2_lib.baseboard_fab2(sch_1):tp_xdp_obsdata_b2" )
			)
			( signal "TP_XDP_OBSDATA_B3"
				( objectStatus "@baseboard_fab2_lib.baseboard_fab2(sch_1):tp_xdp_obsdata_b3" )
			)
			( signal "TP_XDP_OBSFN_B0"
				( objectStatus "@baseboard_fab2_lib.baseboard_fab2(sch_1):tp_xdp_obsfn_b0" )
			)
			( signal "TP_XDP_OBSFN_B1"
				( objectStatus "@baseboard_fab2_lib.baseboard_fab2(sch_1):tp_xdp_obsfn_b1" )
			)
			( signal "XDP_CPU_GTL_TCK_R2"
				( objectStatus "@baseboard_fab2_lib.baseboard_fab2(sch_1):xdp_cpu_gtl_tck_r2" )
			)
			( signal "XDP_CPU_TCK_BUF"
				( objectStatus "@baseboard_fab2_lib.baseboard_fab2(sch_1):xdp_cpu_tck_buf" )
			)
			( signal "XDP_DEBUG_CONSENT_N"
				( objectStatus "@baseboard_fab2_lib.baseboard_fab2(sch_1):xdp_debug_consent_n" )
			)
			( signal "XDP_ITP_PMODE"
				( objectStatus "@baseboard_fab2_lib.baseboard_fab2(sch_1):xdp_itp_pmode" )
			)
			( signal "XDP_OBSFN_B0_MBP6_N"
				( objectStatus "@baseboard_fab2_lib.baseboard_fab2(sch_1):xdp_obsfn_b0_mbp6_n" )
			)
			( signal "XDP_OBSFN_B1_MBP7_N"
				( objectStatus "@baseboard_fab2_lib.baseboard_fab2(sch_1):xdp_obsfn_b1_mbp7_n" )
			)
			( signal "XDP_PCH_CPU_TCK0"
				( objectStatus "@baseboard_fab2_lib.baseboard_fab2(sch_1):xdp_pch_cpu_tck0" )
			)
			( signal "XDP_PCH_TCK1"
				( objectStatus "@baseboard_fab2_lib.baseboard_fab2(sch_1):xdp_pch_tck1" )
			)
			( signal "XDP_PRDY_N"
				( objectStatus "@baseboard_fab2_lib.baseboard_fab2(sch_1):xdp_prdy_n" )
			)
			( signal "XDP_PREQ_N"
				( objectStatus "@baseboard_fab2_lib.baseboard_fab2(sch_1):xdp_preq_n" )
			)
			( signal "XDP_PWRGD_RST_N"
				( objectStatus "@baseboard_fab2_lib.baseboard_fab2(sch_1):xdp_pwrgd_rst_n" )
			)
			( signal "XDP_RSMRST_N"
				( objectStatus "@baseboard_fab2_lib.baseboard_fab2(sch_1):xdp_rsmrst_n" )
			)
			( signal "XDP_RST_CO_N"
				( objectStatus "@baseboard_fab2_lib.baseboard_fab2(sch_1):xdp_rst_co_n" )
			)
			( signal "XDP_SPI_PCH_MOSI_BOOT_HALT_N"
				( objectStatus "@baseboard_fab2_lib.baseboard_fab2(sch_1):xdp_spi_pch_mosi_boot_halt_n" )
			)
			( signal "XDP_SYSPWROK"
				( objectStatus "@baseboard_fab2_lib.baseboard_fab2(sch_1):xdp_syspwrok" )
			)
			( signal "XDP_TDI"
				( objectStatus "@baseboard_fab2_lib.baseboard_fab2(sch_1):xdp_tdi" )
			)
			( signal "XDP_TDO"
				( objectStatus "@baseboard_fab2_lib.baseboard_fab2(sch_1):xdp_tdo" )
			)
			( signal "XDP_TMS"
				( objectStatus "@baseboard_fab2_lib.baseboard_fab2(sch_1):xdp_tms" )
			)
			( signal "XDP_TRST_N"
				( objectStatus "@baseboard_fab2_lib.baseboard_fab2(sch_1):xdp_trst_n" )
			)
			( signal "PWRGD_PVCCIN_CPU0"
				( objectStatus "@baseboard_fab2_lib.baseboard_fab2(sch_1):pwrgd_pvccin_cpu0" )
			)
			( signal "XDP_CPU_TDO"
				( objectStatus "@baseboard_fab2_lib.baseboard_fab2(sch_1):xdp_cpu_tdo" )
			)
			( signal "FM_CPU0_AND_CPU1_MCP_PRES"
				( objectStatus "@baseboard_fab2_lib.baseboard_fab2(sch_1):fm_cpu0_and_cpu1_mcp_pres" )
			)
			( signal "FM_CPU0_CD_PRES"
				( objectStatus "@baseboard_fab2_lib.baseboard_fab2(sch_1):fm_cpu0_cd_pres" )
			)
			( signal "FM_CPU0_OR_CPU1_MCP_PRES"
				( objectStatus "@baseboard_fab2_lib.baseboard_fab2(sch_1):fm_cpu0_or_cpu1_mcp_pres" )
			)
			( signal "FM_CPU1_CD_PRES"
				( objectStatus "@baseboard_fab2_lib.baseboard_fab2(sch_1):fm_cpu1_cd_pres" )
			)
			( signal "JTAG_MCP_CPU0_TDI_R"
				( objectStatus "@baseboard_fab2_lib.baseboard_fab2(sch_1):jtag_mcp_cpu0_tdi_r" )
			)
			( signal "JTAG_MCP_CPU1_TDI_R"
				( objectStatus "@baseboard_fab2_lib.baseboard_fab2(sch_1):jtag_mcp_cpu1_tdi_r" )
			)
			( signal "JTAG_MCP_MUX_TDI"
				( objectStatus "@baseboard_fab2_lib.baseboard_fab2(sch_1):jtag_mcp_mux_tdi" )
			)
			( signal "JTAG_MCP_MUX_TDO"
				( objectStatus "@baseboard_fab2_lib.baseboard_fab2(sch_1):jtag_mcp_mux_tdo" )
			)
			( signal "JTAG_MCP_TCK_R"
				( objectStatus "@baseboard_fab2_lib.baseboard_fab2(sch_1):jtag_mcp_tck_r" )
			)
			( signal "JTAG_MCP_TMS_R"
				( objectStatus "@baseboard_fab2_lib.baseboard_fab2(sch_1):jtag_mcp_tms_r" )
			)
			( signal "JTAG_MCP_TMS_R1"
				( objectStatus "@baseboard_fab2_lib.baseboard_fab2(sch_1):jtag_mcp_tms_r1" )
			)
			( signal "PWRGD_CPU0_G_R"
				( objectStatus "@baseboard_fab2_lib.baseboard_fab2(sch_1):pwrgd_cpu0_g_r" )
			)
			( signal "TP_JTAG_MCP_IO8_RSVD"
				( objectStatus "@baseboard_fab2_lib.baseboard_fab2(sch_1):tp_jtag_mcp_io8_rsvd" )
			)
			( signal "A_PCH_XCLK_BIASREF"
				( objectStatus "@baseboard_fab2_lib.baseboard_fab2(sch_1):a_pch_xclk_biasref" )
			)
			( signal "CLK_100M_AIRMAX8_PE1_DN"
				( objectStatus "@baseboard_fab2_lib.baseboard_fab2(sch_1):clk_100m_airmax8_pe1_dn" )
			)
			( signal "CLK_100M_AIRMAX8_PE1_DP"
				( objectStatus "@baseboard_fab2_lib.baseboard_fab2(sch_1):clk_100m_airmax8_pe1_dp" )
			)
			( signal "CLK_100M_BMC_PE_DN"
				( objectStatus "@baseboard_fab2_lib.baseboard_fab2(sch_1):clk_100m_bmc_pe_dn" )
			)
			( signal "CLK_100M_BMC_PE_DP"
				( objectStatus "@baseboard_fab2_lib.baseboard_fab2(sch_1):clk_100m_bmc_pe_dp" )
			)
			( signal "CLK_100M_BMC_PE_R_DN"
				( objectStatus "@baseboard_fab2_lib.baseboard_fab2(sch_1):clk_100m_bmc_pe_r_dn" )
			)
			( signal "CLK_100M_BMC_PE_R_DP"
				( objectStatus "@baseboard_fab2_lib.baseboard_fab2(sch_1):clk_100m_bmc_pe_r_dp" )
			)
			( signal "CLK_100M_M2_DN"
				( objectStatus "@baseboard_fab2_lib.baseboard_fab2(sch_1):clk_100m_m2_dn" )
			)
			( signal "CLK_100M_M2_DP"
				( objectStatus "@baseboard_fab2_lib.baseboard_fab2(sch_1):clk_100m_m2_dp" )
			)
			( signal "CLK_100M_MEZZ1_DN"
				( objectStatus "@baseboard_fab2_lib.baseboard_fab2(sch_1):clk_100m_mezz1_dn" )
			)
			( signal "CLK_100M_MEZZ1_DP"
				( objectStatus "@baseboard_fab2_lib.baseboard_fab2(sch_1):clk_100m_mezz1_dp" )
			)
			( signal "CLK_100M_MEZZ2_DN"
				( objectStatus "@baseboard_fab2_lib.baseboard_fab2(sch_1):clk_100m_mezz2_dn" )
			)
			( signal "CLK_100M_MEZZ2_DP"
				( objectStatus "@baseboard_fab2_lib.baseboard_fab2(sch_1):clk_100m_mezz2_dp" )
			)
			( signal "CLK_100M_MEZZ3_DN"
				( objectStatus "@baseboard_fab2_lib.baseboard_fab2(sch_1):clk_100m_mezz3_dn" )
			)
			( signal "CLK_100M_MEZZ3_DP"
				( objectStatus "@baseboard_fab2_lib.baseboard_fab2(sch_1):clk_100m_mezz3_dp" )
			)
			( signal "CLK_100M_MEZZ4_DN"
				( objectStatus "@baseboard_fab2_lib.baseboard_fab2(sch_1):clk_100m_mezz4_dn" )
			)
			( signal "CLK_100M_MEZZ4_DP"
				( objectStatus "@baseboard_fab2_lib.baseboard_fab2(sch_1):clk_100m_mezz4_dp" )
			)
			( signal "CLK_100M_SPRV_DN"
				( objectStatus "@baseboard_fab2_lib.baseboard_fab2(sch_1):clk_100m_sprv_dn" )
			)
			( signal "CLK_100M_SPRV_DP"
				( objectStatus "@baseboard_fab2_lib.baseboard_fab2(sch_1):clk_100m_sprv_dp" )
			)
			( signal "CLK_48M_USB_BMC"
				( objectStatus "@baseboard_fab2_lib.baseboard_fab2(sch_1):clk_48m_usb_bmc" )
			)
			( signal "H_PMSYNC_CLK_24M_R"
				( objectStatus "@baseboard_fab2_lib.baseboard_fab2(sch_1):h_pmsync_clk_24m_r" )
			)
			( signal "TP_CLK_100M_NSSCC0_DN"
				( objectStatus "@baseboard_fab2_lib.baseboard_fab2(sch_1):tp_clk_100m_nsscc0_dn" )
			)
			( signal "TP_CLK_100M_NSSCC0_DP"
				( objectStatus "@baseboard_fab2_lib.baseboard_fab2(sch_1):tp_clk_100m_nsscc0_dp" )
			)
			( signal "TP_CLK_100M_NSSCC1_DN"
				( objectStatus "@baseboard_fab2_lib.baseboard_fab2(sch_1):tp_clk_100m_nsscc1_dn" )
			)
			( signal "TP_CLK_100M_NSSCC1_DP"
				( objectStatus "@baseboard_fab2_lib.baseboard_fab2(sch_1):tp_clk_100m_nsscc1_dp" )
			)
			( signal "TP_CLK_100M_PLAT1_DN"
				( objectStatus "@baseboard_fab2_lib.baseboard_fab2(sch_1):tp_clk_100m_plat1_dn" )
			)
			( signal "TP_CLK_100M_PLAT1_DP"
				( objectStatus "@baseboard_fab2_lib.baseboard_fab2(sch_1):tp_clk_100m_plat1_dp" )
			)
			( signal "TP_CLK_24M_PMSYNC2"
				( objectStatus "@baseboard_fab2_lib.baseboard_fab2(sch_1):tp_clk_24m_pmsync2" )
			)
			( signal "TP_PCH_RSVD64"
				( objectStatus "@baseboard_fab2_lib.baseboard_fab2(sch_1):tp_pch_rsvd64" )
			)
			( signal "TP_PCH_RSVD65"
				( objectStatus "@baseboard_fab2_lib.baseboard_fab2(sch_1):tp_pch_rsvd65" )
			)
			( signal "XTAL_33K_RTC1"
				( objectStatus "@baseboard_fab2_lib.baseboard_fab2(sch_1):xtal_33k_rtc1" )
			)
			( signal "XTAL_33K_RTC2"
				( objectStatus "@baseboard_fab2_lib.baseboard_fab2(sch_1):xtal_33k_rtc2" )
			)
			( signal "XTAL_PCH_48M_IN"
				( objectStatus "@baseboard_fab2_lib.baseboard_fab2(sch_1):xtal_pch_48m_in" )
			)
			( signal "XTAL_PCH_48M_OUT"
				( objectStatus "@baseboard_fab2_lib.baseboard_fab2(sch_1):xtal_pch_48m_out" )
			)
			( signal "A_USB2_COMP"
				( objectStatus "@baseboard_fab2_lib.baseboard_fab2(sch_1):a_usb2_comp" )
			)
			( signal "A_USB2_VBUS"
				( objectStatus "@baseboard_fab2_lib.baseboard_fab2(sch_1):a_usb2_vbus" )
			)
			( signal "TP_PCH_RSVD55"
				( objectStatus "@baseboard_fab2_lib.baseboard_fab2(sch_1):tp_pch_rsvd55" )
			)
			( signal "CLK_100M_SRC12_DP"
				( objectStatus "@baseboard_fab2_lib.baseboard_fab2(sch_1):clk_100m_src12_dp" )
			)
			( signal "CLK_100M_SRC12_DN"
				( objectStatus "@baseboard_fab2_lib.baseboard_fab2(sch_1):clk_100m_src12_dn" )
			)
			( signal "TP_USB2_P03_DN"
				( objectStatus "@baseboard_fab2_lib.baseboard_fab2(sch_1):tp_usb2_p03_dn" )
			)
			( signal "TP_USB2_P03_DP"
				( objectStatus "@baseboard_fab2_lib.baseboard_fab2(sch_1):tp_usb2_p03_dp" )
			)
			( signal "TP_USB2_P06_DN"
				( objectStatus "@baseboard_fab2_lib.baseboard_fab2(sch_1):tp_usb2_p06_dn" )
			)
			( signal "TP_USB2_P06_DP"
				( objectStatus "@baseboard_fab2_lib.baseboard_fab2(sch_1):tp_usb2_p06_dp" )
			)
			( signal "TP_USB2_P07_DN"
				( objectStatus "@baseboard_fab2_lib.baseboard_fab2(sch_1):tp_usb2_p07_dn" )
			)
			( signal "TP_USB2_P07_DP"
				( objectStatus "@baseboard_fab2_lib.baseboard_fab2(sch_1):tp_usb2_p07_dp" )
			)
			( signal "TP_USB2_P10_DN"
				( objectStatus "@baseboard_fab2_lib.baseboard_fab2(sch_1):tp_usb2_p10_dn" )
			)
			( signal "TP_USB2_P10_DP"
				( objectStatus "@baseboard_fab2_lib.baseboard_fab2(sch_1):tp_usb2_p10_dp" )
			)
			( signal "TP_USB2_P11_DN"
				( objectStatus "@baseboard_fab2_lib.baseboard_fab2(sch_1):tp_usb2_p11_dn" )
			)
			( signal "TP_USB2_P11_DP"
				( objectStatus "@baseboard_fab2_lib.baseboard_fab2(sch_1):tp_usb2_p11_dp" )
			)
			( signal "TP_USB2_P12_DN"
				( objectStatus "@baseboard_fab2_lib.baseboard_fab2(sch_1):tp_usb2_p12_dn" )
			)
			( signal "TP_USB2_P12_DP"
				( objectStatus "@baseboard_fab2_lib.baseboard_fab2(sch_1):tp_usb2_p12_dp" )
			)
			( signal "TP_USB2_P13_DN"
				( objectStatus "@baseboard_fab2_lib.baseboard_fab2(sch_1):tp_usb2_p13_dn" )
			)
			( signal "TP_USB2_P13_DP"
				( objectStatus "@baseboard_fab2_lib.baseboard_fab2(sch_1):tp_usb2_p13_dp" )
			)
			( signal "TP_USB2_P14_DN"
				( objectStatus "@baseboard_fab2_lib.baseboard_fab2(sch_1):tp_usb2_p14_dn" )
			)
			( signal "TP_USB2_P14_DP"
				( objectStatus "@baseboard_fab2_lib.baseboard_fab2(sch_1):tp_usb2_p14_dp" )
			)
			( signal "TP_USB2_P8_DN"
				( objectStatus "@baseboard_fab2_lib.baseboard_fab2(sch_1):tp_usb2_p8_dn" )
			)
			( signal "TP_USB2_P8_DP"
				( objectStatus "@baseboard_fab2_lib.baseboard_fab2(sch_1):tp_usb2_p8_dp" )
			)
			( signal "TP_USB2_P9_DN"
				( objectStatus "@baseboard_fab2_lib.baseboard_fab2(sch_1):tp_usb2_p9_dn" )
			)
			( signal "TP_USB2_P9_DP"
				( objectStatus "@baseboard_fab2_lib.baseboard_fab2(sch_1):tp_usb2_p9_dp" )
			)
			( signal "TP_USB3_P02_RXN"
				( objectStatus "@baseboard_fab2_lib.baseboard_fab2(sch_1):tp_usb3_p02_rxn" )
			)
			( signal "TP_USB3_P02_RXP"
				( objectStatus "@baseboard_fab2_lib.baseboard_fab2(sch_1):tp_usb3_p02_rxp" )
			)
			( signal "TP_USB3_P02_TXN"
				( objectStatus "@baseboard_fab2_lib.baseboard_fab2(sch_1):tp_usb3_p02_txn" )
			)
			( signal "TP_USB3_P02_TXP"
				( objectStatus "@baseboard_fab2_lib.baseboard_fab2(sch_1):tp_usb3_p02_txp" )
			)
			( signal "TP_USB3_P03_RXN"
				( objectStatus "@baseboard_fab2_lib.baseboard_fab2(sch_1):tp_usb3_p03_rxn" )
			)
			( signal "TP_USB3_P03_RXP"
				( objectStatus "@baseboard_fab2_lib.baseboard_fab2(sch_1):tp_usb3_p03_rxp" )
			)
			( signal "TP_USB3_P03_TXN"
				( objectStatus "@baseboard_fab2_lib.baseboard_fab2(sch_1):tp_usb3_p03_txn" )
			)
			( signal "TP_USB3_P03_TXP"
				( objectStatus "@baseboard_fab2_lib.baseboard_fab2(sch_1):tp_usb3_p03_txp" )
			)
			( signal "TP_USB3_P04_RXN"
				( objectStatus "@baseboard_fab2_lib.baseboard_fab2(sch_1):tp_usb3_p04_rxn" )
			)
			( signal "TP_USB3_P04_RXP"
				( objectStatus "@baseboard_fab2_lib.baseboard_fab2(sch_1):tp_usb3_p04_rxp" )
			)
			( signal "TP_USB3_P04_TXN"
				( objectStatus "@baseboard_fab2_lib.baseboard_fab2(sch_1):tp_usb3_p04_txn" )
			)
			( signal "TP_USB3_P04_TXP"
				( objectStatus "@baseboard_fab2_lib.baseboard_fab2(sch_1):tp_usb3_p04_txp" )
			)
			( signal "TP_USB3_P05_RXN"
				( objectStatus "@baseboard_fab2_lib.baseboard_fab2(sch_1):tp_usb3_p05_rxn" )
			)
			( signal "TP_USB3_P05_RXP"
				( objectStatus "@baseboard_fab2_lib.baseboard_fab2(sch_1):tp_usb3_p05_rxp" )
			)
			( signal "TP_USB3_P05_TXN"
				( objectStatus "@baseboard_fab2_lib.baseboard_fab2(sch_1):tp_usb3_p05_txn" )
			)
			( signal "TP_USB3_P05_TXP"
				( objectStatus "@baseboard_fab2_lib.baseboard_fab2(sch_1):tp_usb3_p05_txp" )
			)
			( signal "TP_USB3_P06_RXN"
				( objectStatus "@baseboard_fab2_lib.baseboard_fab2(sch_1):tp_usb3_p06_rxn" )
			)
			( signal "TP_USB3_P06_RXP"
				( objectStatus "@baseboard_fab2_lib.baseboard_fab2(sch_1):tp_usb3_p06_rxp" )
			)
			( signal "TP_USB3_P06_TXN"
				( objectStatus "@baseboard_fab2_lib.baseboard_fab2(sch_1):tp_usb3_p06_txn" )
			)
			( signal "TP_USB3_P06_TXP"
				( objectStatus "@baseboard_fab2_lib.baseboard_fab2(sch_1):tp_usb3_p06_txp" )
			)
			( signal "USB2_P01_DN"
				( objectStatus "@baseboard_fab2_lib.baseboard_fab2(sch_1):usb2_p01_dn" )
			)
			( signal "USB2_P01_DP"
				( objectStatus "@baseboard_fab2_lib.baseboard_fab2(sch_1):usb2_p01_dp" )
			)
			( signal "USB2_PCH_BMC_P5_DN"
				( objectStatus "@baseboard_fab2_lib.baseboard_fab2(sch_1):usb2_pch_bmc_p5_dn" )
			)
			( signal "USB2_PCH_BMC_P5_DP"
				( objectStatus "@baseboard_fab2_lib.baseboard_fab2(sch_1):usb2_pch_bmc_p5_dp" )
			)
			( signal "VCC_VA_3V3"
				( objectStatus "@baseboard_fab2_lib.baseboard_fab2(sch_1):vcc_va_3v3" )
			)
			( signal "USB3_P01_RXN"
				( objectStatus "@baseboard_fab2_lib.baseboard_fab2(sch_1):usb3_p01_rxn" )
			)
			( signal "USB3_P01_RXP"
				( objectStatus "@baseboard_fab2_lib.baseboard_fab2(sch_1):usb3_p01_rxp" )
			)
			( signal "USB3_P01_TXN"
				( objectStatus "@baseboard_fab2_lib.baseboard_fab2(sch_1):usb3_p01_txn" )
			)
			( signal "USB3_P01_TXP"
				( objectStatus "@baseboard_fab2_lib.baseboard_fab2(sch_1):usb3_p01_txp" )
			)
			( signal "USB_PCH_BMC_P4_DN"
				( objectStatus "@baseboard_fab2_lib.baseboard_fab2(sch_1):usb_pch_bmc_p4_dn" )
			)
			( signal "USB_PCH_BMC_P4_DP"
				( objectStatus "@baseboard_fab2_lib.baseboard_fab2(sch_1):usb_pch_bmc_p4_dp" )
			)
			( signal "VCC_PA_3V3"
				( objectStatus "@baseboard_fab2_lib.baseboard_fab2(sch_1):vcc_pa_3v3" )
			)
			( signal "PECI_BMC_R"
				( objectStatus "@baseboard_fab2_lib.baseboard_fab2(sch_1):peci_bmc_r" )
			)
			( signal "A_EXTCLKN"
				( objectStatus "@baseboard_fab2_lib.baseboard_fab2(sch_1):a_extclkn" )
			)
			( signal "A_EXTCLKP"
				( objectStatus "@baseboard_fab2_lib.baseboard_fab2(sch_1):a_extclkp" )
			)
			( signal "A_PCIE_RCOMP_N"
				( objectStatus "@baseboard_fab2_lib.baseboard_fab2(sch_1):a_pcie_rcomp_n" )
			)
			( signal "A_PCIE_RCOMP_P"
				( objectStatus "@baseboard_fab2_lib.baseboard_fab2(sch_1):a_pcie_rcomp_p" )
			)
			( signal "A_PCIEUP_RCOMP_N"
				( objectStatus "@baseboard_fab2_lib.baseboard_fab2(sch_1):a_pcieup_rcomp_n" )
			)
			( signal "A_PCIEUP_RCOMP_P"
				( objectStatus "@baseboard_fab2_lib.baseboard_fab2(sch_1):a_pcieup_rcomp_p" )
			)
			( signal "P2E_SSB_BMC_RX_C_DN"
				( objectStatus "@baseboard_fab2_lib.baseboard_fab2(sch_1):p2e_ssb_bmc_rx_c_dn" )
			)
			( signal "P2E_SSB_BMC_RX_C_DP"
				( objectStatus "@baseboard_fab2_lib.baseboard_fab2(sch_1):p2e_ssb_bmc_rx_c_dp" )
			)
			( signal "P2E_SSB_BMC_TX_C_DN"
				( objectStatus "@baseboard_fab2_lib.baseboard_fab2(sch_1):p2e_ssb_bmc_tx_c_dn" )
			)
			( signal "P2E_SSB_BMC_TX_C_DP"
				( objectStatus "@baseboard_fab2_lib.baseboard_fab2(sch_1):p2e_ssb_bmc_tx_c_dp" )
			)
			( signal "P2E_SSB_BMC_TX_DN"
				( objectStatus "@baseboard_fab2_lib.baseboard_fab2(sch_1):p2e_ssb_bmc_tx_dn" )
			)
			( signal "P2E_SSB_BMC_TX_DP"
				( objectStatus "@baseboard_fab2_lib.baseboard_fab2(sch_1):p2e_ssb_bmc_tx_dp" )
			)
			( signal "P3E_PCH_M2_RX_DN<1>"
				( objectStatus "@baseboard_fab2_lib.baseboard_fab2(sch_1):p3e_pch_m2_rx_dn(1)" )
			)
			( signal "P3E_PCH_M2_RX_DN<2>"
				( objectStatus "@baseboard_fab2_lib.baseboard_fab2(sch_1):p3e_pch_m2_rx_dn(2)" )
			)
			( signal "P3E_PCH_M2_RX_DN<3>"
				( objectStatus "@baseboard_fab2_lib.baseboard_fab2(sch_1):p3e_pch_m2_rx_dn(3)" )
			)
			( signal "P3E_PCH_M2_RX_DP<1>"
				( objectStatus "@baseboard_fab2_lib.baseboard_fab2(sch_1):p3e_pch_m2_rx_dp(1)" )
			)
			( signal "P3E_PCH_M2_RX_DP<2>"
				( objectStatus "@baseboard_fab2_lib.baseboard_fab2(sch_1):p3e_pch_m2_rx_dp(2)" )
			)
			( signal "P3E_PCH_M2_RX_DP<3>"
				( objectStatus "@baseboard_fab2_lib.baseboard_fab2(sch_1):p3e_pch_m2_rx_dp(3)" )
			)
			( signal "P3E_PCH_M2_TX_DN<1>"
				( objectStatus "@baseboard_fab2_lib.baseboard_fab2(sch_1):p3e_pch_m2_tx_dn(1)" )
			)
			( signal "P3E_PCH_M2_TX_DN<2>"
				( objectStatus "@baseboard_fab2_lib.baseboard_fab2(sch_1):p3e_pch_m2_tx_dn(2)" )
			)
			( signal "P3E_PCH_M2_TX_DN<3>"
				( objectStatus "@baseboard_fab2_lib.baseboard_fab2(sch_1):p3e_pch_m2_tx_dn(3)" )
			)
			( signal "P3E_PCH_M2_TX_DP<1>"
				( objectStatus "@baseboard_fab2_lib.baseboard_fab2(sch_1):p3e_pch_m2_tx_dp(1)" )
			)
			( signal "P3E_PCH_M2_TX_DP<2>"
				( objectStatus "@baseboard_fab2_lib.baseboard_fab2(sch_1):p3e_pch_m2_tx_dp(2)" )
			)
			( signal "P3E_PCH_M2_TX_DP<3>"
				( objectStatus "@baseboard_fab2_lib.baseboard_fab2(sch_1):p3e_pch_m2_tx_dp(3)" )
			)
			( signal "P3E_PCH_RX_0_DN"
				( objectStatus "@baseboard_fab2_lib.baseboard_fab2(sch_1):p3e_pch_rx_0_dn" )
			)
			( signal "P3E_PCH_RX_0_DP"
				( objectStatus "@baseboard_fab2_lib.baseboard_fab2(sch_1):p3e_pch_rx_0_dp" )
			)
			( signal "P3E_PCH_TX_0_DN"
				( objectStatus "@baseboard_fab2_lib.baseboard_fab2(sch_1):p3e_pch_tx_0_dn" )
			)
			( signal "P3E_PCH_TX_0_DP"
				( objectStatus "@baseboard_fab2_lib.baseboard_fab2(sch_1):p3e_pch_tx_0_dp" )
			)
			( signal "PE_PCH_SPRV_RX_C_DN"
				( objectStatus "@baseboard_fab2_lib.baseboard_fab2(sch_1):pe_pch_sprv_rx_c_dn" )
			)
			( signal "PE_PCH_SPRV_RX_C_DP"
				( objectStatus "@baseboard_fab2_lib.baseboard_fab2(sch_1):pe_pch_sprv_rx_c_dp" )
			)
			( signal "PE_PCH_SPRV_TX_DN"
				( objectStatus "@baseboard_fab2_lib.baseboard_fab2(sch_1):pe_pch_sprv_tx_dn" )
			)
			( signal "PE_PCH_SPRV_TX_DP"
				( objectStatus "@baseboard_fab2_lib.baseboard_fab2(sch_1):pe_pch_sprv_tx_dp" )
			)
			( signal "SATA6G_PCH_PCIE_UP_SATA_RXN<0>"
				( objectStatus "@baseboard_fab2_lib.baseboard_fab2(sch_1):sata6g_pch_pcie_up_sata_rxn(0)" )
			)
			( signal "SATA6G_PCH_PCIE_UP_SATA_RXN<1>"
				( objectStatus "@baseboard_fab2_lib.baseboard_fab2(sch_1):sata6g_pch_pcie_up_sata_rxn(1)" )
			)
			( signal "SATA6G_PCH_PCIE_UP_SATA_RXN<2>"
				( objectStatus "@baseboard_fab2_lib.baseboard_fab2(sch_1):sata6g_pch_pcie_up_sata_rxn(2)" )
			)
			( signal "SATA6G_PCH_PCIE_UP_SATA_RXN<3>"
				( objectStatus "@baseboard_fab2_lib.baseboard_fab2(sch_1):sata6g_pch_pcie_up_sata_rxn(3)" )
			)
			( signal "SATA6G_PCH_PCIE_UP_SATA_RXN<4>"
				( objectStatus "@baseboard_fab2_lib.baseboard_fab2(sch_1):sata6g_pch_pcie_up_sata_rxn(4)" )
			)
			( signal "SATA6G_PCH_PCIE_UP_SATA_RXN<5>"
				( objectStatus "@baseboard_fab2_lib.baseboard_fab2(sch_1):sata6g_pch_pcie_up_sata_rxn(5)" )
			)
			( signal "SATA6G_PCH_PCIE_UP_SATA_RXN<6>"
				( objectStatus "@baseboard_fab2_lib.baseboard_fab2(sch_1):sata6g_pch_pcie_up_sata_rxn(6)" )
			)
			( signal "SATA6G_PCH_PCIE_UP_SATA_RXN<7>"
				( objectStatus "@baseboard_fab2_lib.baseboard_fab2(sch_1):sata6g_pch_pcie_up_sata_rxn(7)" )
			)
			( signal "SATA6G_PCH_PCIE_UP_SATA_RXP<0>"
				( objectStatus "@baseboard_fab2_lib.baseboard_fab2(sch_1):sata6g_pch_pcie_up_sata_rxp(0)" )
			)
			( signal "SATA6G_PCH_PCIE_UP_SATA_RXP<1>"
				( objectStatus "@baseboard_fab2_lib.baseboard_fab2(sch_1):sata6g_pch_pcie_up_sata_rxp(1)" )
			)
			( signal "SATA6G_PCH_PCIE_UP_SATA_RXP<2>"
				( objectStatus "@baseboard_fab2_lib.baseboard_fab2(sch_1):sata6g_pch_pcie_up_sata_rxp(2)" )
			)
			( signal "SATA6G_PCH_PCIE_UP_SATA_RXP<3>"
				( objectStatus "@baseboard_fab2_lib.baseboard_fab2(sch_1):sata6g_pch_pcie_up_sata_rxp(3)" )
			)
			( signal "SATA6G_PCH_PCIE_UP_SATA_RXP<4>"
				( objectStatus "@baseboard_fab2_lib.baseboard_fab2(sch_1):sata6g_pch_pcie_up_sata_rxp(4)" )
			)
			( signal "SATA6G_PCH_PCIE_UP_SATA_RXP<5>"
				( objectStatus "@baseboard_fab2_lib.baseboard_fab2(sch_1):sata6g_pch_pcie_up_sata_rxp(5)" )
			)
			( signal "SATA6G_PCH_PCIE_UP_SATA_RXP<6>"
				( objectStatus "@baseboard_fab2_lib.baseboard_fab2(sch_1):sata6g_pch_pcie_up_sata_rxp(6)" )
			)
			( signal "SATA6G_PCH_PCIE_UP_SATA_RXP<7>"
				( objectStatus "@baseboard_fab2_lib.baseboard_fab2(sch_1):sata6g_pch_pcie_up_sata_rxp(7)" )
			)
			( signal "SATA6G_PCH_PCIE_UP_SATA_TXN<0>"
				( objectStatus "@baseboard_fab2_lib.baseboard_fab2(sch_1):sata6g_pch_pcie_up_sata_txn(0)" )
			)
			( signal "SATA6G_PCH_PCIE_UP_SATA_TXN<1>"
				( objectStatus "@baseboard_fab2_lib.baseboard_fab2(sch_1):sata6g_pch_pcie_up_sata_txn(1)" )
			)
			( signal "SATA6G_PCH_PCIE_UP_SATA_TXN<2>"
				( objectStatus "@baseboard_fab2_lib.baseboard_fab2(sch_1):sata6g_pch_pcie_up_sata_txn(2)" )
			)
			( signal "SATA6G_PCH_PCIE_UP_SATA_TXN<3>"
				( objectStatus "@baseboard_fab2_lib.baseboard_fab2(sch_1):sata6g_pch_pcie_up_sata_txn(3)" )
			)
			( signal "SATA6G_PCH_PCIE_UP_SATA_TXN<4>"
				( objectStatus "@baseboard_fab2_lib.baseboard_fab2(sch_1):sata6g_pch_pcie_up_sata_txn(4)" )
			)
			( signal "SATA6G_PCH_PCIE_UP_SATA_TXN<5>"
				( objectStatus "@baseboard_fab2_lib.baseboard_fab2(sch_1):sata6g_pch_pcie_up_sata_txn(5)" )
			)
			( signal "SATA6G_PCH_PCIE_UP_SATA_TXN<6>"
				( objectStatus "@baseboard_fab2_lib.baseboard_fab2(sch_1):sata6g_pch_pcie_up_sata_txn(6)" )
			)
			( signal "SATA6G_PCH_PCIE_UP_SATA_TXN<7>"
				( objectStatus "@baseboard_fab2_lib.baseboard_fab2(sch_1):sata6g_pch_pcie_up_sata_txn(7)" )
			)
			( signal "SATA6G_PCH_PCIE_UP_SATA_TXP<0>"
				( objectStatus "@baseboard_fab2_lib.baseboard_fab2(sch_1):sata6g_pch_pcie_up_sata_txp(0)" )
			)
			( signal "SATA6G_PCH_PCIE_UP_SATA_TXP<1>"
				( objectStatus "@baseboard_fab2_lib.baseboard_fab2(sch_1):sata6g_pch_pcie_up_sata_txp(1)" )
			)
			( signal "SATA6G_PCH_PCIE_UP_SATA_TXP<2>"
				( objectStatus "@baseboard_fab2_lib.baseboard_fab2(sch_1):sata6g_pch_pcie_up_sata_txp(2)" )
			)
			( signal "SATA6G_PCH_PCIE_UP_SATA_TXP<3>"
				( objectStatus "@baseboard_fab2_lib.baseboard_fab2(sch_1):sata6g_pch_pcie_up_sata_txp(3)" )
			)
			( signal "SATA6G_PCH_PCIE_UP_SATA_TXP<4>"
				( objectStatus "@baseboard_fab2_lib.baseboard_fab2(sch_1):sata6g_pch_pcie_up_sata_txp(4)" )
			)
			( signal "SATA6G_PCH_PCIE_UP_SATA_TXP<5>"
				( objectStatus "@baseboard_fab2_lib.baseboard_fab2(sch_1):sata6g_pch_pcie_up_sata_txp(5)" )
			)
			( signal "SATA6G_PCH_PCIE_UP_SATA_TXP<6>"
				( objectStatus "@baseboard_fab2_lib.baseboard_fab2(sch_1):sata6g_pch_pcie_up_sata_txp(6)" )
			)
			( signal "SATA6G_PCH_PCIE_UP_SATA_TXP<7>"
				( objectStatus "@baseboard_fab2_lib.baseboard_fab2(sch_1):sata6g_pch_pcie_up_sata_txp(7)" )
			)
			( signal "SATA6G_RX_DN<0>"
				( objectStatus "@baseboard_fab2_lib.baseboard_fab2(sch_1):sata6g_rx_dn(0)" )
			)
			( signal "SATA6G_RX_DN<1>"
				( objectStatus "@baseboard_fab2_lib.baseboard_fab2(sch_1):sata6g_rx_dn(1)" )
			)
			( signal "SATA6G_RX_DN<2>"
				( objectStatus "@baseboard_fab2_lib.baseboard_fab2(sch_1):sata6g_rx_dn(2)" )
			)
			( signal "SATA6G_RX_DN<3>"
				( objectStatus "@baseboard_fab2_lib.baseboard_fab2(sch_1):sata6g_rx_dn(3)" )
			)
			( signal "SATA6G_RX_DP<0>"
				( objectStatus "@baseboard_fab2_lib.baseboard_fab2(sch_1):sata6g_rx_dp(0)" )
			)
			( signal "SATA6G_RX_DP<1>"
				( objectStatus "@baseboard_fab2_lib.baseboard_fab2(sch_1):sata6g_rx_dp(1)" )
			)
			( signal "SATA6G_RX_DP<2>"
				( objectStatus "@baseboard_fab2_lib.baseboard_fab2(sch_1):sata6g_rx_dp(2)" )
			)
			( signal "SATA6G_RX_DP<3>"
				( objectStatus "@baseboard_fab2_lib.baseboard_fab2(sch_1):sata6g_rx_dp(3)" )
			)
			( signal "SATA6G_S0_RX_DN"
				( objectStatus "@baseboard_fab2_lib.baseboard_fab2(sch_1):sata6g_s0_rx_dn" )
			)
			( signal "SATA6G_S0_RX_DP"
				( objectStatus "@baseboard_fab2_lib.baseboard_fab2(sch_1):sata6g_s0_rx_dp" )
			)
			( signal "SATA6G_S0_TX_DN"
				( objectStatus "@baseboard_fab2_lib.baseboard_fab2(sch_1):sata6g_s0_tx_dn" )
			)
			( signal "SATA6G_S0_TX_DP"
				( objectStatus "@baseboard_fab2_lib.baseboard_fab2(sch_1):sata6g_s0_tx_dp" )
			)
			( signal "SATA6G_S1_RX_DN"
				( objectStatus "@baseboard_fab2_lib.baseboard_fab2(sch_1):sata6g_s1_rx_dn" )
			)
			( signal "SATA6G_S1_RX_DP"
				( objectStatus "@baseboard_fab2_lib.baseboard_fab2(sch_1):sata6g_s1_rx_dp" )
			)
			( signal "SATA6G_S1_TX_DN"
				( objectStatus "@baseboard_fab2_lib.baseboard_fab2(sch_1):sata6g_s1_tx_dn" )
			)
			( signal "SATA6G_S1_TX_DP"
				( objectStatus "@baseboard_fab2_lib.baseboard_fab2(sch_1):sata6g_s1_tx_dp" )
			)
			( signal "SATA6G_TX_DN<0>"
				( objectStatus "@baseboard_fab2_lib.baseboard_fab2(sch_1):sata6g_tx_dn(0)" )
			)
			( signal "SATA6G_TX_DN<1>"
				( objectStatus "@baseboard_fab2_lib.baseboard_fab2(sch_1):sata6g_tx_dn(1)" )
			)
			( signal "SATA6G_TX_DN<2>"
				( objectStatus "@baseboard_fab2_lib.baseboard_fab2(sch_1):sata6g_tx_dn(2)" )
			)
			( signal "SATA6G_TX_DN<3>"
				( objectStatus "@baseboard_fab2_lib.baseboard_fab2(sch_1):sata6g_tx_dn(3)" )
			)
			( signal "SATA6G_TX_DP<0>"
				( objectStatus "@baseboard_fab2_lib.baseboard_fab2(sch_1):sata6g_tx_dp(0)" )
			)
			( signal "SATA6G_TX_DP<1>"
				( objectStatus "@baseboard_fab2_lib.baseboard_fab2(sch_1):sata6g_tx_dp(1)" )
			)
			( signal "SATA6G_TX_DP<2>"
				( objectStatus "@baseboard_fab2_lib.baseboard_fab2(sch_1):sata6g_tx_dp(2)" )
			)
			( signal "SATA6G_TX_DP<3>"
				( objectStatus "@baseboard_fab2_lib.baseboard_fab2(sch_1):sata6g_tx_dp(3)" )
			)
			( signal "TP_PCH_RSVD47"
				( objectStatus "@baseboard_fab2_lib.baseboard_fab2(sch_1):tp_pch_rsvd47" )
			)
			( signal "TP_PCH_RSVD48"
				( objectStatus "@baseboard_fab2_lib.baseboard_fab2(sch_1):tp_pch_rsvd48" )
			)
			( signal "TP_PCH_RSVD49"
				( objectStatus "@baseboard_fab2_lib.baseboard_fab2(sch_1):tp_pch_rsvd49" )
			)
			( signal "TP_PCH_RSVD50"
				( objectStatus "@baseboard_fab2_lib.baseboard_fab2(sch_1):tp_pch_rsvd50" )
			)
			( signal "TP_PCH_RSVD51"
				( objectStatus "@baseboard_fab2_lib.baseboard_fab2(sch_1):tp_pch_rsvd51" )
			)
			( signal "TP_PCH_RSVD52"
				( objectStatus "@baseboard_fab2_lib.baseboard_fab2(sch_1):tp_pch_rsvd52" )
			)
			( signal "DMI_CPU0_PCH_RX_DN<0>"
				( objectStatus "@baseboard_fab2_lib.baseboard_fab2(sch_1):dmi_cpu0_pch_rx_dn(0)" )
			)
			( signal "DMI_CPU0_PCH_RX_DN<1>"
				( objectStatus "@baseboard_fab2_lib.baseboard_fab2(sch_1):dmi_cpu0_pch_rx_dn(1)" )
			)
			( signal "DMI_CPU0_PCH_RX_DN<2>"
				( objectStatus "@baseboard_fab2_lib.baseboard_fab2(sch_1):dmi_cpu0_pch_rx_dn(2)" )
			)
			( signal "DMI_CPU0_PCH_RX_DN<3>"
				( objectStatus "@baseboard_fab2_lib.baseboard_fab2(sch_1):dmi_cpu0_pch_rx_dn(3)" )
			)
			( signal "DMI_CPU0_PCH_RX_DP<0>"
				( objectStatus "@baseboard_fab2_lib.baseboard_fab2(sch_1):dmi_cpu0_pch_rx_dp(0)" )
			)
			( signal "DMI_CPU0_PCH_RX_DP<1>"
				( objectStatus "@baseboard_fab2_lib.baseboard_fab2(sch_1):dmi_cpu0_pch_rx_dp(1)" )
			)
			( signal "DMI_CPU0_PCH_RX_DP<2>"
				( objectStatus "@baseboard_fab2_lib.baseboard_fab2(sch_1):dmi_cpu0_pch_rx_dp(2)" )
			)
			( signal "DMI_CPU0_PCH_RX_DP<3>"
				( objectStatus "@baseboard_fab2_lib.baseboard_fab2(sch_1):dmi_cpu0_pch_rx_dp(3)" )
			)
			( signal "DMI_CPU0_PCH_TX_C_DN<0>"
				( objectStatus "@baseboard_fab2_lib.baseboard_fab2(sch_1):dmi_cpu0_pch_tx_c_dn(0)" )
			)
			( signal "DMI_CPU0_PCH_TX_C_DN<1>"
				( objectStatus "@baseboard_fab2_lib.baseboard_fab2(sch_1):dmi_cpu0_pch_tx_c_dn(1)" )
			)
			( signal "DMI_CPU0_PCH_TX_C_DN<2>"
				( objectStatus "@baseboard_fab2_lib.baseboard_fab2(sch_1):dmi_cpu0_pch_tx_c_dn(2)" )
			)
			( signal "DMI_CPU0_PCH_TX_C_DN<3>"
				( objectStatus "@baseboard_fab2_lib.baseboard_fab2(sch_1):dmi_cpu0_pch_tx_c_dn(3)" )
			)
			( signal "DMI_CPU0_PCH_TX_C_DP<0>"
				( objectStatus "@baseboard_fab2_lib.baseboard_fab2(sch_1):dmi_cpu0_pch_tx_c_dp(0)" )
			)
			( signal "DMI_CPU0_PCH_TX_C_DP<1>"
				( objectStatus "@baseboard_fab2_lib.baseboard_fab2(sch_1):dmi_cpu0_pch_tx_c_dp(1)" )
			)
			( signal "DMI_CPU0_PCH_TX_C_DP<2>"
				( objectStatus "@baseboard_fab2_lib.baseboard_fab2(sch_1):dmi_cpu0_pch_tx_c_dp(2)" )
			)
			( signal "DMI_CPU0_PCH_TX_C_DP<3>"
				( objectStatus "@baseboard_fab2_lib.baseboard_fab2(sch_1):dmi_cpu0_pch_tx_c_dp(3)" )
			)
			( signal "A_KR0_RBIAS"
				( objectStatus "@baseboard_fab2_lib.baseboard_fab2(sch_1):a_kr0_rbias" )
			)
			( signal "A_KR1_RBIAS"
				( objectStatus "@baseboard_fab2_lib.baseboard_fab2(sch_1):a_kr1_rbias" )
			)
			( signal "FM_10GBE_LOM_DISABLE_N"
				( objectStatus "@baseboard_fab2_lib.baseboard_fab2(sch_1):fm_10gbe_lom_disable_n" )
			)
			( signal "FM_1GB_LOM_DISABLE_N"
				( objectStatus "@baseboard_fab2_lib.baseboard_fab2(sch_1):fm_1gb_lom_disable_n" )
			)
			( signal "FM_BATTERY_SENSE_EN_N"
				( objectStatus "@baseboard_fab2_lib.baseboard_fab2(sch_1):fm_battery_sense_en_n" )
			)
			( signal "FM_BMC_CPLD_MP_RST_N"
				( objectStatus "@baseboard_fab2_lib.baseboard_fab2(sch_1):fm_bmc_cpld_mp_rst_n" )
			)
			( signal "FM_GBE_LOM_DISABLE_N"
				( objectStatus "@baseboard_fab2_lib.baseboard_fab2(sch_1):fm_gbe_lom_disable_n" )
			)
			( signal "FM_PCH_LVC1_THERMTRIP_N"
				( objectStatus "@baseboard_fab2_lib.baseboard_fab2(sch_1):fm_pch_lvc1_thermtrip_n" )
			)
			( signal "FM_PCH_PWRBTN_N"
				( objectStatus "@baseboard_fab2_lib.baseboard_fab2(sch_1):fm_pch_pwrbtn_n" )
			)
			( signal "FM_SLP_SUS_N"
				( objectStatus "@baseboard_fab2_lib.baseboard_fab2(sch_1):fm_slp_sus_n" )
			)
			( signal "FM_SLPS3_N"
				( objectStatus "@baseboard_fab2_lib.baseboard_fab2(sch_1):fm_slps3_n" )
			)
			( signal "FM_SLPS4_N"
				( objectStatus "@baseboard_fab2_lib.baseboard_fab2(sch_1):fm_slps4_n" )
			)
			( signal "H_PM_SYNC1_GTL_R"
				( objectStatus "@baseboard_fab2_lib.baseboard_fab2(sch_1):h_pm_sync1_gtl_r" )
			)
			( signal "IRQ_LVC3_WAKE_N"
				( objectStatus "@baseboard_fab2_lib.baseboard_fab2(sch_1):irq_lvc3_wake_n" )
			)
			( signal "IRQ_SML1_PMBUS_ALERT_N"
				( objectStatus "@baseboard_fab2_lib.baseboard_fab2(sch_1):irq_sml1_pmbus_alert_n" )
			)
			( signal "KR_P0_OCP_RX_C_DN"
				( objectStatus "@baseboard_fab2_lib.baseboard_fab2(sch_1):kr_p0_ocp_rx_c_dn" )
			)
			( signal "KR_P0_OCP_RX_C_DP"
				( objectStatus "@baseboard_fab2_lib.baseboard_fab2(sch_1):kr_p0_ocp_rx_c_dp" )
			)
			( signal "KR_P0_OCP_TX_DN"
				( objectStatus "@baseboard_fab2_lib.baseboard_fab2(sch_1):kr_p0_ocp_tx_dn" )
			)
			( signal "KR_P0_OCP_TX_DP"
				( objectStatus "@baseboard_fab2_lib.baseboard_fab2(sch_1):kr_p0_ocp_tx_dp" )
			)
			( signal "KR_P1_OCP_RX_C_DN"
				( objectStatus "@baseboard_fab2_lib.baseboard_fab2(sch_1):kr_p1_ocp_rx_c_dn" )
			)
			( signal "KR_P1_OCP_RX_C_DP"
				( objectStatus "@baseboard_fab2_lib.baseboard_fab2(sch_1):kr_p1_ocp_rx_c_dp" )
			)
			( signal "KR_P1_OCP_TX_DN"
				( objectStatus "@baseboard_fab2_lib.baseboard_fab2(sch_1):kr_p1_ocp_tx_dn" )
			)
			( signal "KR_P1_OCP_TX_DP"
				( objectStatus "@baseboard_fab2_lib.baseboard_fab2(sch_1):kr_p1_ocp_tx_dp" )
			)
			( signal "KR_P2_OCP_RX_C_DN"
				( objectStatus "@baseboard_fab2_lib.baseboard_fab2(sch_1):kr_p2_ocp_rx_c_dn" )
			)
			( signal "KR_P2_OCP_RX_C_DP"
				( objectStatus "@baseboard_fab2_lib.baseboard_fab2(sch_1):kr_p2_ocp_rx_c_dp" )
			)
			( signal "KR_P2_OCP_TX_DN"
				( objectStatus "@baseboard_fab2_lib.baseboard_fab2(sch_1):kr_p2_ocp_tx_dn" )
			)
			( signal "KR_P2_OCP_TX_DP"
				( objectStatus "@baseboard_fab2_lib.baseboard_fab2(sch_1):kr_p2_ocp_tx_dp" )
			)
			( signal "KR_P3_OCP_RX_C_DN"
				( objectStatus "@baseboard_fab2_lib.baseboard_fab2(sch_1):kr_p3_ocp_rx_c_dn" )
			)
			( signal "KR_P3_OCP_RX_C_DP"
				( objectStatus "@baseboard_fab2_lib.baseboard_fab2(sch_1):kr_p3_ocp_rx_c_dp" )
			)
			( signal "KR_P3_OCP_TX_DN"
				( objectStatus "@baseboard_fab2_lib.baseboard_fab2(sch_1):kr_p3_ocp_tx_dn" )
			)
			( signal "KR_P3_OCP_TX_DP"
				( objectStatus "@baseboard_fab2_lib.baseboard_fab2(sch_1):kr_p3_ocp_tx_dp" )
			)
			( signal "P1V05_PCH_STBY_KR_PLL"
				( attribute "VOLTAGE" "1.05V"
					( Units "uVoltage" "V" 1.000000)
					( Status sAliasFlattened )
					( Origin gFrontEnd )
				)
				( objectStatus "@baseboard_fab2_lib.baseboard_fab2(sch_1):p1v05_pch_stby_kr_pll" )
			)
			( signal "PECI_PCH"
				( objectStatus "@baseboard_fab2_lib.baseboard_fab2(sch_1):peci_pch" )
			)
			( signal "PWRGD_DSW_PWROK"
				( objectStatus "@baseboard_fab2_lib.baseboard_fab2(sch_1):pwrgd_dsw_pwrok" )
			)
			( signal "PWRGD_PCH_PWROK"
				( objectStatus "@baseboard_fab2_lib.baseboard_fab2(sch_1):pwrgd_pch_pwrok" )
			)
			( signal "PWRGD_PVCCIO_CPU0"
				( objectStatus "@baseboard_fab2_lib.baseboard_fab2(sch_1):pwrgd_pvccio_cpu0" )
			)
			( signal "PWRGD_SYS_PWROK"
				( objectStatus "@baseboard_fab2_lib.baseboard_fab2(sch_1):pwrgd_sys_pwrok" )
			)
			( signal "RST_BMC_SRST_N"
				( objectStatus "@baseboard_fab2_lib.baseboard_fab2(sch_1):rst_bmc_srst_n" )
			)
			( signal "RST_BMC_SRST_R_N"
				( objectStatus "@baseboard_fab2_lib.baseboard_fab2(sch_1):rst_bmc_srst_r_n" )
			)
			( signal "RST_BMC_SYSRST_BTN_OUT_B_N"
				( objectStatus "@baseboard_fab2_lib.baseboard_fab2(sch_1):rst_bmc_sysrst_btn_out_b_n" )
			)
			( signal "TP_10GBE_KR0_MON_DN"
				( objectStatus "@baseboard_fab2_lib.baseboard_fab2(sch_1):tp_10gbe_kr0_mon_dn" )
			)
			( signal "TP_10GBE_KR0_MON_DP"
				( objectStatus "@baseboard_fab2_lib.baseboard_fab2(sch_1):tp_10gbe_kr0_mon_dp" )
			)
			( signal "TP_10GBE_KR1_MON_DN"
				( objectStatus "@baseboard_fab2_lib.baseboard_fab2(sch_1):tp_10gbe_kr1_mon_dn" )
			)
			( signal "TP_10GBE_KR1_MON_DP"
				( objectStatus "@baseboard_fab2_lib.baseboard_fab2(sch_1):tp_10gbe_kr1_mon_dp" )
			)
			( signal "TP_CPU_PCH_TRIGGER_IN"
				( objectStatus "@baseboard_fab2_lib.baseboard_fab2(sch_1):tp_cpu_pch_trigger_in" )
			)
			( signal "TP_CPU_PCH_TRIGGER_OUT"
				( objectStatus "@baseboard_fab2_lib.baseboard_fab2(sch_1):tp_cpu_pch_trigger_out" )
			)
			( signal "TP_PCH_RSVD32"
				( objectStatus "@baseboard_fab2_lib.baseboard_fab2(sch_1):tp_pch_rsvd32" )
			)
			( signal "TP_PCH_RSVD33"
				( objectStatus "@baseboard_fab2_lib.baseboard_fab2(sch_1):tp_pch_rsvd33" )
			)
			( signal "TP_PCH_RSVD34"
				( objectStatus "@baseboard_fab2_lib.baseboard_fab2(sch_1):tp_pch_rsvd34" )
			)
			( signal "TP_PCH_RSVD35"
				( objectStatus "@baseboard_fab2_lib.baseboard_fab2(sch_1):tp_pch_rsvd35" )
			)
			( signal "TP_PCH_RSVD36"
				( objectStatus "@baseboard_fab2_lib.baseboard_fab2(sch_1):tp_pch_rsvd36" )
			)
			( signal "TP_PCH_RSVD37"
				( objectStatus "@baseboard_fab2_lib.baseboard_fab2(sch_1):tp_pch_rsvd37" )
			)
			( signal "TP_PCH_RSVD38"
				( objectStatus "@baseboard_fab2_lib.baseboard_fab2(sch_1):tp_pch_rsvd38" )
			)
			( signal "TP_PCH_RSVD41"
				( objectStatus "@baseboard_fab2_lib.baseboard_fab2(sch_1):tp_pch_rsvd41" )
			)
			( signal "TP_PCH_RSVD42"
				( objectStatus "@baseboard_fab2_lib.baseboard_fab2(sch_1):tp_pch_rsvd42" )
			)
			( signal "TP_PCH_RSVD45"
				( objectStatus "@baseboard_fab2_lib.baseboard_fab2(sch_1):tp_pch_rsvd45" )
			)
			( signal "TP_PCH_RSVD53"
				( objectStatus "@baseboard_fab2_lib.baseboard_fab2(sch_1):tp_pch_rsvd53" )
			)
			( signal "TP_PCH_RSVD54"
				( objectStatus "@baseboard_fab2_lib.baseboard_fab2(sch_1):tp_pch_rsvd54" )
			)
			( signal "TP_PLTRST_CPU_N"
				( objectStatus "@baseboard_fab2_lib.baseboard_fab2(sch_1):tp_pltrst_cpu_n" )
			)
			( signal "TP_PM_SYNC_GTL"
				( objectStatus "@baseboard_fab2_lib.baseboard_fab2(sch_1):tp_pm_sync_gtl" )
			)
			( signal "TP_SLP_LAN_N"
				( objectStatus "@baseboard_fab2_lib.baseboard_fab2(sch_1):tp_slp_lan_n" )
			)
			( signal "XDP_PCH_PWR_DEBUG_N"
				( objectStatus "@baseboard_fab2_lib.baseboard_fab2(sch_1):xdp_pch_pwr_debug_n" )
			)
			( signal "XTAL_KR_25M_IN"
				( objectStatus "@baseboard_fab2_lib.baseboard_fab2(sch_1):xtal_kr_25m_in" )
			)
			( signal "XTAL_KR_25M_OUT"
				( objectStatus "@baseboard_fab2_lib.baseboard_fab2(sch_1):xtal_kr_25m_out" )
			)
			( signal "CLK_24M_BMC_LPC"
				( objectStatus "@baseboard_fab2_lib.baseboard_fab2(sch_1):clk_24m_bmc_lpc" )
			)
			( signal "CLK_24M_BMC_LPC_R"
				( objectStatus "@baseboard_fab2_lib.baseboard_fab2(sch_1):clk_24m_bmc_lpc_r" )
			)
			( signal "FM_ADR_MODE_SEL"
				( objectStatus "@baseboard_fab2_lib.baseboard_fab2(sch_1):fm_adr_mode_sel" )
			)
			( signal "FM_ADR_MODE_SEL_R"
				( objectStatus "@baseboard_fab2_lib.baseboard_fab2(sch_1):fm_adr_mode_sel_r" )
			)
			( signal "FM_BB_BMC_MP_GPIO"
				( objectStatus "@baseboard_fab2_lib.baseboard_fab2(sch_1):fm_bb_bmc_mp_gpio" )
			)
			( signal "FM_BIOS_POST_CMPLT_N"
				( objectStatus "@baseboard_fab2_lib.baseboard_fab2(sch_1):fm_bios_post_cmplt_n" )
			)
			( signal "FM_BIOS_PREFRB2_GOOD"
				( objectStatus "@baseboard_fab2_lib.baseboard_fab2(sch_1):fm_bios_prefrb2_good" )
			)
			( signal "FM_BIOS_TOP_SWAP_SPKR"
				( objectStatus "@baseboard_fab2_lib.baseboard_fab2(sch_1):fm_bios_top_swap_spkr" )
			)
			( signal "FM_BMC_CPLD_GPO"
				( objectStatus "@baseboard_fab2_lib.baseboard_fab2(sch_1):fm_bmc_cpld_gpo" )
			)
			( signal "FM_BMC_ENABLE_N"
				( objectStatus "@baseboard_fab2_lib.baseboard_fab2(sch_1):fm_bmc_enable_n" )
			)
			( signal "FM_BMC_FAULT_LED_N"
				( objectStatus "@baseboard_fab2_lib.baseboard_fab2(sch_1):fm_bmc_fault_led_n" )
			)
			( signal "FM_BMC_HEARTBEAT_N"
				( objectStatus "@baseboard_fab2_lib.baseboard_fab2(sch_1):fm_bmc_heartbeat_n" )
			)
			( signal "FM_BMC_READY_N"
				( objectStatus "@baseboard_fab2_lib.baseboard_fab2(sch_1):fm_bmc_ready_n" )
			)
			( signal "FM_BOARD_REV_ID0"
				( objectStatus "@baseboard_fab2_lib.baseboard_fab2(sch_1):fm_board_rev_id0" )
			)
			( signal "FM_BOARD_REV_ID1"
				( objectStatus "@baseboard_fab2_lib.baseboard_fab2(sch_1):fm_board_rev_id1" )
			)
			( signal "FM_BOARD_REV_ID2"
				( objectStatus "@baseboard_fab2_lib.baseboard_fab2(sch_1):fm_board_rev_id2" )
			)
			( signal "FM_CPLD_BMC_PWRDN_N"
				( objectStatus "@baseboard_fab2_lib.baseboard_fab2(sch_1):fm_cpld_bmc_pwrdn_n" )
			)
			( signal "SMB_IE_3V3AUX_SDA"
				( objectStatus "@baseboard_fab2_lib.baseboard_fab2(sch_1):smb_ie_3v3aux_sda" )
			)
			( signal "FM_CPU0_THERMTRIP_LATCH_LVT3_N"
				( objectStatus "@baseboard_fab2_lib.baseboard_fab2(sch_1):fm_cpu0_thermtrip_latch_lvt3_n" )
			)
			( signal "FM_CPU1_RC_EN"
				( objectStatus "@baseboard_fab2_lib.baseboard_fab2(sch_1):fm_cpu1_rc_en" )
			)
			( signal "FM_CPU_BMC_INIT"
				( objectStatus "@baseboard_fab2_lib.baseboard_fab2(sch_1):fm_cpu_bmc_init" )
			)
			( signal "FM_CPU_CATERR_DLY_LVT3_N"
				( objectStatus "@baseboard_fab2_lib.baseboard_fab2(sch_1):fm_cpu_caterr_dly_lvt3_n" )
			)
			( signal "FM_CPU_CATERR_DLY_LVT3_R_N"
				( objectStatus "@baseboard_fab2_lib.baseboard_fab2(sch_1):fm_cpu_caterr_dly_lvt3_r_n" )
			)
			( signal "FM_FAST_PROCHOT_EN_N"
				( objectStatus "@baseboard_fab2_lib.baseboard_fab2(sch_1):fm_fast_prochot_en_n" )
			)
			( signal "FM_GLOBAL_RST_WARN_N"
				( objectStatus "@baseboard_fab2_lib.baseboard_fab2(sch_1):fm_global_rst_warn_n" )
			)
			( signal "FM_MB_SLOT_ID0"
				( objectStatus "@baseboard_fab2_lib.baseboard_fab2(sch_1):fm_mb_slot_id0" )
			)
			( signal "FM_MB_SLOT_ID1"
				( objectStatus "@baseboard_fab2_lib.baseboard_fab2(sch_1):fm_mb_slot_id1" )
			)
			( signal "FM_FLASH_DESC_OVERRIDE_R"
				( objectStatus "@baseboard_fab2_lib.baseboard_fab2(sch_1):fm_flash_desc_override_r" )
			)
			( signal "FM_MB_SLOT_ID2"
				( objectStatus "@baseboard_fab2_lib.baseboard_fab2(sch_1):fm_mb_slot_id2" )
			)
			( signal "FM_ME_RECOVER_N"
				( objectStatus "@baseboard_fab2_lib.baseboard_fab2(sch_1):fm_me_recover_n" )
			)
			( signal "FM_OCP_MEZZA_PRES_N"
				( objectStatus "@baseboard_fab2_lib.baseboard_fab2(sch_1):fm_ocp_mezza_pres_n" )
			)
			( signal "FM_PASSWORD_CLEAR_N"
				( objectStatus "@baseboard_fab2_lib.baseboard_fab2(sch_1):fm_password_clear_n" )
			)
			( signal "FM_PCH_BMC_THERMTRIP_EXI_STRAP_"
				( objectStatus "@baseboard_fab2_lib.baseboard_fab2(sch_1):fm_pch_bmc_thermtrip_exi_strap_n" )
			)
			( signal "FM_PCH_PLD_DATA"
				( objectStatus "@baseboard_fab2_lib.baseboard_fab2(sch_1):fm_pch_pld_data" )
			)
			( signal "FM_PCH_PLD_DATA_R"
				( objectStatus "@baseboard_fab2_lib.baseboard_fab2(sch_1):fm_pch_pld_data_r" )
			)
			( signal "FM_PCH_PWRBTN_OUT_N"
				( objectStatus "@baseboard_fab2_lib.baseboard_fab2(sch_1):fm_pch_pwrbtn_out_n" )
			)
			( signal "FM_PCH_SATA_RAID_KEY"
				( objectStatus "@baseboard_fab2_lib.baseboard_fab2(sch_1):fm_pch_sata_raid_key" )
			)
			( signal "FM_PMBUS_ALERT_BUF_EN_N"
				( objectStatus "@baseboard_fab2_lib.baseboard_fab2(sch_1):fm_pmbus_alert_buf_en_n" )
			)
			( signal "FM_POST_CARD_PRES_BMC_N"
				( objectStatus "@baseboard_fab2_lib.baseboard_fab2(sch_1):fm_post_card_pres_bmc_n" )
			)
			( signal "FM_PWR_BTN_N"
				( objectStatus "@baseboard_fab2_lib.baseboard_fab2(sch_1):fm_pwr_btn_n" )
			)
			( signal "FM_PWR_LED"
				( objectStatus "@baseboard_fab2_lib.baseboard_fab2(sch_1):fm_pwr_led" )
			)
			( signal "FM_PWR_LED_A"
				( objectStatus "@baseboard_fab2_lib.baseboard_fab2(sch_1):fm_pwr_led_a" )
			)
			( signal "FM_PWR_LED_K"
				( objectStatus "@baseboard_fab2_lib.baseboard_fab2(sch_1):fm_pwr_led_k" )
			)
			( signal "FM_PWR_LED_N"
				( objectStatus "@baseboard_fab2_lib.baseboard_fab2(sch_1):fm_pwr_led_n" )
			)
			( signal "FM_QAT_EN_N"
				( objectStatus "@baseboard_fab2_lib.baseboard_fab2(sch_1):fm_qat_en_n" )
			)
			( signal "FM_SLT_CFG2_R"
				( objectStatus "@baseboard_fab2_lib.baseboard_fab2(sch_1):fm_slt_cfg2_r" )
			)
			( signal "FM_TPM_PRES_N"
				( objectStatus "@baseboard_fab2_lib.baseboard_fab2(sch_1):fm_tpm_pres_n" )
			)
			( signal "FM_UART_ALERT_N"
				( objectStatus "@baseboard_fab2_lib.baseboard_fab2(sch_1):fm_uart_alert_n" )
			)
			( signal "FM_UART_PRES_N"
				( objectStatus "@baseboard_fab2_lib.baseboard_fab2(sch_1):fm_uart_pres_n" )
			)
			( signal "FM_USB_P0_EN_BOOT_BIOS_STRAP_N"
				( objectStatus "@baseboard_fab2_lib.baseboard_fab2(sch_1):fm_usb_p0_en_boot_bios_strap_n" )
			)
			( signal "FM_UV_ADR_TRIGGER_EN"
				( objectStatus "@baseboard_fab2_lib.baseboard_fab2(sch_1):fm_uv_adr_trigger_en" )
			)
			( signal "SMB_IPMB_3V3AUX_SCL"
				( objectStatus "@baseboard_fab2_lib.baseboard_fab2(sch_1):smb_ipmb_3v3aux_scl" )
			)
			( signal "FM_XRC_PRESENT_N"
				( objectStatus "@baseboard_fab2_lib.baseboard_fab2(sch_1):fm_xrc_present_n" )
			)
			( signal "FM_XRC_READY_N"
				( objectStatus "@baseboard_fab2_lib.baseboard_fab2(sch_1):fm_xrc_ready_n" )
			)
			( signal "FP_NMI_BTN_N"
				( objectStatus "@baseboard_fab2_lib.baseboard_fab2(sch_1):fp_nmi_btn_n" )
			)
			( signal "H_CPU0_FAST_WAKE_LVT3_N"
				( objectStatus "@baseboard_fab2_lib.baseboard_fab2(sch_1):h_cpu0_fast_wake_lvt3_n" )
			)
			( signal "IRQ_BMC_PCH_NMI_STBY_R_N"
				( objectStatus "@baseboard_fab2_lib.baseboard_fab2(sch_1):irq_bmc_pch_nmi_stby_r_n" )
			)
			( signal "IRQ_BMC_PCH_SCI_LPC_N"
				( objectStatus "@baseboard_fab2_lib.baseboard_fab2(sch_1):irq_bmc_pch_sci_lpc_n" )
			)
			( signal "IRQ_BMC_PCH_SMI_LPC_N"
				( objectStatus "@baseboard_fab2_lib.baseboard_fab2(sch_1):irq_bmc_pch_smi_lpc_n" )
			)
			( signal "IRQ_FORCE_NM_THROTTLE_N"
				( objectStatus "@baseboard_fab2_lib.baseboard_fab2(sch_1):irq_force_nm_throttle_n" )
			)
			( signal "IRQ_HSC_FAULT_N"
				( objectStatus "@baseboard_fab2_lib.baseboard_fab2(sch_1):irq_hsc_fault_n" )
			)
			( signal "IRQ_LOM_ALERT_N"
				( objectStatus "@baseboard_fab2_lib.baseboard_fab2(sch_1):irq_lom_alert_n" )
			)
			( signal "FM_BMC_ONCTL_R_N"
				( objectStatus "@baseboard_fab2_lib.baseboard_fab2(sch_1):fm_bmc_onctl_r_n" )
			)
			( signal "IRQ_LPC_SERIRQ_N"
				( objectStatus "@baseboard_fab2_lib.baseboard_fab2(sch_1):irq_lpc_serirq_n" )
			)
			( signal "IRQ_MEZZ_LAN_ALERT_N"
				( objectStatus "@baseboard_fab2_lib.baseboard_fab2(sch_1):irq_mezz_lan_alert_n" )
			)
			( signal "IRQ_PCH_NIC_ALERT_N"
				( objectStatus "@baseboard_fab2_lib.baseboard_fab2(sch_1):irq_pch_nic_alert_n" )
			)
			( signal "UNNAMED_239_21K5R2F-GP_I99_2"
				( objectStatus "@baseboard_fab2_lib.baseboard_fab2(sch_1):\unnamed_239_21k5r2f-gp_i99_2\" )
			)
			( signal "IRQ_PIRQA_SPI_TPM_N"
				( objectStatus "@baseboard_fab2_lib.baseboard_fab2(sch_1):irq_pirqa_spi_tpm_n" )
			)
			( signal "IRQ_SML0_ALERT_N"
				( objectStatus "@baseboard_fab2_lib.baseboard_fab2(sch_1):irq_sml0_alert_n" )
			)
			( signal "IRQ_VM_INT_N"
				( objectStatus "@baseboard_fab2_lib.baseboard_fab2(sch_1):irq_vm_int_n" )
			)
			( signal "LPC_LAD0_IO0"
				( objectStatus "@baseboard_fab2_lib.baseboard_fab2(sch_1):lpc_lad0_io0" )
			)
			( signal "LPC_LAD1_IO1"
				( objectStatus "@baseboard_fab2_lib.baseboard_fab2(sch_1):lpc_lad1_io1" )
			)
			( signal "LPC_LAD2_IO2"
				( objectStatus "@baseboard_fab2_lib.baseboard_fab2(sch_1):lpc_lad2_io2" )
			)
			( signal "LPC_LAD3_IO3"
				( objectStatus "@baseboard_fab2_lib.baseboard_fab2(sch_1):lpc_lad3_io3" )
			)
			( signal "LPC_LFRAME_N_CS0_N"
				( objectStatus "@baseboard_fab2_lib.baseboard_fab2(sch_1):lpc_lframe_n_cs0_n" )
			)
			( signal "PU_FM_RCIN_N"
				( objectStatus "@baseboard_fab2_lib.baseboard_fab2(sch_1):pu_fm_rcin_n" )
			)
			( signal "PU_IRQ_PCH_SCI_WHEA_N"
				( objectStatus "@baseboard_fab2_lib.baseboard_fab2(sch_1):pu_irq_pch_sci_whea_n" )
			)
			( signal "PU_IRQ_VRALERT_N"
				( objectStatus "@baseboard_fab2_lib.baseboard_fab2(sch_1):pu_irq_vralert_n" )
			)
			( signal "PU_LPC_CLKRUN_N"
				( objectStatus "@baseboard_fab2_lib.baseboard_fab2(sch_1):pu_lpc_clkrun_n" )
			)
			( signal "PU_LPC_PME_N"
				( objectStatus "@baseboard_fab2_lib.baseboard_fab2(sch_1):pu_lpc_pme_n" )
			)
			( signal "PU_PCH_TLS_ENABLE_STRAP"
				( objectStatus "@baseboard_fab2_lib.baseboard_fab2(sch_1):pu_pch_tls_enable_strap" )
			)
			( signal "RST_PCH_SYSRST_BTN_OUT_N"
				( objectStatus "@baseboard_fab2_lib.baseboard_fab2(sch_1):rst_pch_sysrst_btn_out_n" )
			)
			( signal "RST_PLTRST_N"
				( objectStatus "@baseboard_fab2_lib.baseboard_fab2(sch_1):rst_pltrst_n" )
			)
			( signal "RST_SYSTEM_BTN_N"
				( objectStatus "@baseboard_fab2_lib.baseboard_fab2(sch_1):rst_system_btn_n" )
			)
			( signal "SGPIO_PCH_SSATA_DOUT0"
				( objectStatus "@baseboard_fab2_lib.baseboard_fab2(sch_1):sgpio_pch_ssata_dout0" )
			)
			( signal "SMB_HOST_STBY_LVC3_SCL_R1"
				( objectStatus "@baseboard_fab2_lib.baseboard_fab2(sch_1):smb_host_stby_lvc3_scl_r1" )
			)
			( signal "SMB_HOST_STBY_LVC3_SDA_R1"
				( objectStatus "@baseboard_fab2_lib.baseboard_fab2(sch_1):smb_host_stby_lvc3_sda_r1" )
			)
			( signal "SMB_PMBUS_BMC_STBY_LVC3_SCL_R1"
				( objectStatus "@baseboard_fab2_lib.baseboard_fab2(sch_1):smb_pmbus_bmc_stby_lvc3_scl_r1" )
			)
			( signal "SMB_PMBUS_BMC_STBY_LVC3_SDA_R1"
				( objectStatus "@baseboard_fab2_lib.baseboard_fab2(sch_1):smb_pmbus_bmc_stby_lvc3_sda_r1" )
			)
			( signal "SMB_SLOTX24_STBY_LVC3_SCL_R1"
				( objectStatus "@baseboard_fab2_lib.baseboard_fab2(sch_1):smb_slotx24_stby_lvc3_scl_r1" )
			)
			( signal "SMB_SLOTX24_STBY_LVC3_SDA_R1"
				( objectStatus "@baseboard_fab2_lib.baseboard_fab2(sch_1):smb_slotx24_stby_lvc3_sda_r1" )
			)
			( signal "SMB_SMLINK0_STBY_LVC3_SCL_R1"
				( objectStatus "@baseboard_fab2_lib.baseboard_fab2(sch_1):smb_smlink0_stby_lvc3_scl_r1" )
			)
			( signal "SMB_SMLINK0_STBY_LVC3_SDA_R1"
				( objectStatus "@baseboard_fab2_lib.baseboard_fab2(sch_1):smb_smlink0_stby_lvc3_sda_r1" )
			)
			( signal "SP2_BMC_CM_UART_RX"
				( objectStatus "@baseboard_fab2_lib.baseboard_fab2(sch_1):sp2_bmc_cm_uart_rx" )
			)
			( signal "SP2_BMC_CM_UART_TX"
				( objectStatus "@baseboard_fab2_lib.baseboard_fab2(sch_1):sp2_bmc_cm_uart_tx" )
			)
			( signal "TP_PCH_GPP_D12"
				( objectStatus "@baseboard_fab2_lib.baseboard_fab2(sch_1):tp_pch_gpp_d12" )
			)
			( signal "VID_PCH_CORE_PVNN_AUX_VID_0"
				( objectStatus "@baseboard_fab2_lib.baseboard_fab2(sch_1):vid_pch_core_pvnn_aux_vid_0" )
			)
			( signal "VID_PCH_CORE_PVNN_AUX_VID_1"
				( objectStatus "@baseboard_fab2_lib.baseboard_fab2(sch_1):vid_pch_core_pvnn_aux_vid_1" )
			)
			( signal "A_RCOMP_3P3"
				( objectStatus "@baseboard_fab2_lib.baseboard_fab2(sch_1):a_rcomp_3p3" )
			)
			( signal "FAN_PWM_OUT_SYS0"
				( objectStatus "@baseboard_fab2_lib.baseboard_fab2(sch_1):fan_pwm_out_sys0" )
			)
			( signal "FAN_PWM_OUT_SYS1"
				( objectStatus "@baseboard_fab2_lib.baseboard_fab2(sch_1):fan_pwm_out_sys1" )
			)
			( signal "FAN_TACH0"
				( objectStatus "@baseboard_fab2_lib.baseboard_fab2(sch_1):fan_tach0" )
			)
			( signal "FAN_TACH1"
				( objectStatus "@baseboard_fab2_lib.baseboard_fab2(sch_1):fan_tach1" )
			)
			( signal "FAN_TACH2"
				( objectStatus "@baseboard_fab2_lib.baseboard_fab2(sch_1):fan_tach2" )
			)
			( signal "FAN_TACH3"
				( objectStatus "@baseboard_fab2_lib.baseboard_fab2(sch_1):fan_tach3" )
			)
			( signal "FM_ADR_COMPLETE_R1"
				( objectStatus "@baseboard_fab2_lib.baseboard_fab2(sch_1):fm_adr_complete_r1" )
			)
			( signal "FM_BACKUP_BIOS_SEL_N"
				( objectStatus "@baseboard_fab2_lib.baseboard_fab2(sch_1):fm_backup_bios_sel_n" )
			)
			( signal "SMB_PCIE_SSD_3V3AUX_SCL"
				( objectStatus "@baseboard_fab2_lib.baseboard_fab2(sch_1):smb_pcie_ssd_3v3aux_scl" )
			)
			( signal "FM_BIOS_MRC_DEBUG_MSG_DIS_N"
				( objectStatus "@baseboard_fab2_lib.baseboard_fab2(sch_1):fm_bios_mrc_debug_msg_dis_n" )
			)
			( signal "FM_BIOS_SMI_ACTIVE_N"
				( objectStatus "@baseboard_fab2_lib.baseboard_fab2(sch_1):fm_bios_smi_active_n" )
			)
			( signal "FM_BIOS_TOP_SWAP"
				( objectStatus "@baseboard_fab2_lib.baseboard_fab2(sch_1):fm_bios_top_swap" )
			)
			( signal "FM_BIOS_USB_RECOVERY"
				( objectStatus "@baseboard_fab2_lib.baseboard_fab2(sch_1):fm_bios_usb_recovery" )
			)
			( signal "FM_BMC_NMI_N"
				( objectStatus "@baseboard_fab2_lib.baseboard_fab2(sch_1):fm_bmc_nmi_n" )
			)
			( signal "FM_BOARD_SKU_ID0"
				( objectStatus "@baseboard_fab2_lib.baseboard_fab2(sch_1):fm_board_sku_id0" )
			)
			( signal "FM_BOARD_SKU_ID1"
				( objectStatus "@baseboard_fab2_lib.baseboard_fab2(sch_1):fm_board_sku_id1" )
			)
			( signal "FM_BOARD_SKU_ID2"
				( objectStatus "@baseboard_fab2_lib.baseboard_fab2(sch_1):fm_board_sku_id2" )
			)
			( signal "FM_BOARD_SKU_ID3"
				( objectStatus "@baseboard_fab2_lib.baseboard_fab2(sch_1):fm_board_sku_id3" )
			)
			( signal "FM_BOARD_SKU_ID4"
				( objectStatus "@baseboard_fab2_lib.baseboard_fab2(sch_1):fm_board_sku_id4" )
			)
			( signal "FM_CPLD_ADR_TRIGGER_N"
				( objectStatus "@baseboard_fab2_lib.baseboard_fab2(sch_1):fm_cpld_adr_trigger_n" )
			)
			( signal "FM_CPLD_ADR_TRIGGER_R_N"
				( objectStatus "@baseboard_fab2_lib.baseboard_fab2(sch_1):fm_cpld_adr_trigger_r_n" )
			)
			( signal "FM_CPU0_FIVR_FAULT_LVT3_N"
				( objectStatus "@baseboard_fab2_lib.baseboard_fab2(sch_1):fm_cpu0_fivr_fault_lvt3_n" )
			)
			( signal "FM_CPU0_RC_EN"
				( objectStatus "@baseboard_fab2_lib.baseboard_fab2(sch_1):fm_cpu0_rc_en" )
			)
			( signal "FM_CPU1_FIVR_FAULT_LVT3_N"
				( objectStatus "@baseboard_fab2_lib.baseboard_fab2(sch_1):fm_cpu1_fivr_fault_lvt3_n" )
			)
			( signal "FM_CPU1_THERMTRIP_LATCH_LVT3_N"
				( objectStatus "@baseboard_fab2_lib.baseboard_fab2(sch_1):fm_cpu1_thermtrip_latch_lvt3_n" )
			)
			( signal "FM_FLASH_ATTACH_CFG_STRAP"
				( objectStatus "@baseboard_fab2_lib.baseboard_fab2(sch_1):fm_flash_attach_cfg_strap" )
			)
			( signal "FM_FORCE_ADR_N"
				( objectStatus "@baseboard_fab2_lib.baseboard_fab2(sch_1):fm_force_adr_n" )
			)
			( signal "TP_SMB_STORAGE_BP_3V3AUX_SDA"
				( objectStatus "@baseboard_fab2_lib.baseboard_fab2(sch_1):tp_smb_storage_bp_3v3aux_sda" )
			)
			( signal "FM_GBE0_LVC3_MOD_ABS"
				( objectStatus "@baseboard_fab2_lib.baseboard_fab2(sch_1):fm_gbe0_lvc3_mod_abs" )
			)
			( signal "FM_GBE1_LVC3_MOD_ABS"
				( objectStatus "@baseboard_fab2_lib.baseboard_fab2(sch_1):fm_gbe1_lvc3_mod_abs" )
			)
			( signal "FM_GBE2_LVC3_MOD_ABS"
				( objectStatus "@baseboard_fab2_lib.baseboard_fab2(sch_1):fm_gbe2_lvc3_mod_abs" )
			)
			( signal "FM_GBE3_LVC3_MOD_ABS"
				( objectStatus "@baseboard_fab2_lib.baseboard_fab2(sch_1):fm_gbe3_lvc3_mod_abs" )
			)
			( signal "FM_HSC_TIMER_EXP_N"
				( objectStatus "@baseboard_fab2_lib.baseboard_fab2(sch_1):fm_hsc_timer_exp_n" )
			)
			( signal "FM_IE_DISABLE_N"
				( objectStatus "@baseboard_fab2_lib.baseboard_fab2(sch_1):fm_ie_disable_n" )
			)
			( signal "FM_MEM_THERM_EVENT_PCH_N"
				( objectStatus "@baseboard_fab2_lib.baseboard_fab2(sch_1):fm_mem_therm_event_pch_n" )
			)
			( signal "FM_MP_PS_FAIL_N"
				( objectStatus "@baseboard_fab2_lib.baseboard_fab2(sch_1):fm_mp_ps_fail_n" )
			)
			( signal "FM_MP_PS_REDUNDANT_LOST_N"
				( objectStatus "@baseboard_fab2_lib.baseboard_fab2(sch_1):fm_mp_ps_redundant_lost_n" )
			)
			( signal "FM_NMI_EVENT_N"
				( objectStatus "@baseboard_fab2_lib.baseboard_fab2(sch_1):fm_nmi_event_n" )
			)
			( signal "FM_OC0_USB_N"
				( objectStatus "@baseboard_fab2_lib.baseboard_fab2(sch_1):fm_oc0_usb_n" )
			)
			( signal "FM_OC_DETECT_EN_N"
				( objectStatus "@baseboard_fab2_lib.baseboard_fab2(sch_1):fm_oc_detect_en_n" )
			)
			( signal "FM_PCH_BMC_THERMTRIP_N"
				( objectStatus "@baseboard_fab2_lib.baseboard_fab2(sch_1):fm_pch_bmc_thermtrip_n" )
			)
			( signal "FM_SOL_UART_CH_SEL"
				( objectStatus "@baseboard_fab2_lib.baseboard_fab2(sch_1):fm_sol_uart_ch_sel" )
			)
			( signal "FM_SSATA_PCIE_M2_SEL"
				( objectStatus "@baseboard_fab2_lib.baseboard_fab2(sch_1):fm_ssata_pcie_m2_sel" )
			)
			( signal "FM_UARTSW_LSB_N"
				( objectStatus "@baseboard_fab2_lib.baseboard_fab2(sch_1):fm_uartsw_lsb_n" )
			)
			( signal "TP_SMB_STORAGE_BP_3V3AUX_SCL"
				( objectStatus "@baseboard_fab2_lib.baseboard_fab2(sch_1):tp_smb_storage_bp_3v3aux_scl" )
			)
			( signal "FM_UARTSW_MSB_N"
				( objectStatus "@baseboard_fab2_lib.baseboard_fab2(sch_1):fm_uartsw_msb_n" )
			)
			( signal "SMB_IPMB_3V3AUX_SDA"
				( objectStatus "@baseboard_fab2_lib.baseboard_fab2(sch_1):smb_ipmb_3v3aux_sda" )
			)
			( signal "FP_PWR_ID_LED_N"
				( objectStatus "@baseboard_fab2_lib.baseboard_fab2(sch_1):fp_pwr_id_led_n" )
			)
			( signal "IRQ_BMC_PCH_NMI_STBY_N"
				( objectStatus "@baseboard_fab2_lib.baseboard_fab2(sch_1):irq_bmc_pch_nmi_stby_n" )
			)
			( signal "IRQ_BOARD_BMC_ALERT_N"
				( objectStatus "@baseboard_fab2_lib.baseboard_fab2(sch_1):irq_board_bmc_alert_n" )
			)
			( signal "IRQ_OC_DETECT_N"
				( objectStatus "@baseboard_fab2_lib.baseboard_fab2(sch_1):irq_oc_detect_n" )
			)
			( signal "IRQ_UV_DETECT_N"
				( objectStatus "@baseboard_fab2_lib.baseboard_fab2(sch_1):irq_uv_detect_n" )
			)
			( signal "JTAG_PCH_GBE_CLK"
				( objectStatus "@baseboard_fab2_lib.baseboard_fab2(sch_1):jtag_pch_gbe_clk" )
			)
			( signal "JTAG_PCH_GBE_TDI"
				( objectStatus "@baseboard_fab2_lib.baseboard_fab2(sch_1):jtag_pch_gbe_tdi" )
			)
			( signal "JTAG_PCH_GBE_TDO"
				( objectStatus "@baseboard_fab2_lib.baseboard_fab2(sch_1):jtag_pch_gbe_tdo" )
			)
			( signal "JTAG_PCH_GBE_TMS"
				( objectStatus "@baseboard_fab2_lib.baseboard_fab2(sch_1):jtag_pch_gbe_tms" )
			)
			( signal "JTAG_PCH_GBE_TRST_N"
				( objectStatus "@baseboard_fab2_lib.baseboard_fab2(sch_1):jtag_pch_gbe_trst_n" )
			)
			( signal "JTAG_PCH_PLD_TCK"
				( objectStatus "@baseboard_fab2_lib.baseboard_fab2(sch_1):jtag_pch_pld_tck" )
			)
			( signal "JTAG_PCH_PLD_TDI"
				( objectStatus "@baseboard_fab2_lib.baseboard_fab2(sch_1):jtag_pch_pld_tdi" )
			)
			( signal "JTAG_PCH_PLD_TDO"
				( objectStatus "@baseboard_fab2_lib.baseboard_fab2(sch_1):jtag_pch_pld_tdo" )
			)
			( signal "JTAG_PCH_PLD_TMS"
				( objectStatus "@baseboard_fab2_lib.baseboard_fab2(sch_1):jtag_pch_pld_tms" )
			)
			( signal "LED_GBE_P0_0"
				( objectStatus "@baseboard_fab2_lib.baseboard_fab2(sch_1):led_gbe_p0_0" )
			)
			( signal "LED_GBE_P0_1"
				( objectStatus "@baseboard_fab2_lib.baseboard_fab2(sch_1):led_gbe_p0_1" )
			)
			( signal "LED_GBE_P1_0"
				( objectStatus "@baseboard_fab2_lib.baseboard_fab2(sch_1):led_gbe_p1_0" )
			)
			( signal "LED_GBE_P1_1"
				( objectStatus "@baseboard_fab2_lib.baseboard_fab2(sch_1):led_gbe_p1_1" )
			)
			( signal "LED_GBE_P2_0"
				( objectStatus "@baseboard_fab2_lib.baseboard_fab2(sch_1):led_gbe_p2_0" )
			)
			( signal "LED_GBE_P2_1"
				( objectStatus "@baseboard_fab2_lib.baseboard_fab2(sch_1):led_gbe_p2_1" )
			)
			( signal "LED_GBE_P3_0"
				( objectStatus "@baseboard_fab2_lib.baseboard_fab2(sch_1):led_gbe_p3_0" )
			)
			( signal "LED_GBE_P3_1"
				( objectStatus "@baseboard_fab2_lib.baseboard_fab2(sch_1):led_gbe_p3_1" )
			)
			( signal "LED_PCH_SATA_HDD_N"
				( objectStatus "@baseboard_fab2_lib.baseboard_fab2(sch_1):led_pch_sata_hdd_n" )
			)
			( signal "LED_PCH_SSATA_HDD_N"
				( objectStatus "@baseboard_fab2_lib.baseboard_fab2(sch_1):led_pch_ssata_hdd_n" )
			)
			( signal "LED_POSTCODE_0"
				( objectStatus "@baseboard_fab2_lib.baseboard_fab2(sch_1):led_postcode_0" )
			)
			( signal "LED_POSTCODE_1"
				( objectStatus "@baseboard_fab2_lib.baseboard_fab2(sch_1):led_postcode_1" )
			)
			( signal "LED_POSTCODE_2"
				( objectStatus "@baseboard_fab2_lib.baseboard_fab2(sch_1):led_postcode_2" )
			)
			( signal "LED_POSTCODE_3"
				( objectStatus "@baseboard_fab2_lib.baseboard_fab2(sch_1):led_postcode_3" )
			)
			( signal "LED_POSTCODE_4"
				( objectStatus "@baseboard_fab2_lib.baseboard_fab2(sch_1):led_postcode_4" )
			)
			( signal "LED_POSTCODE_5"
				( objectStatus "@baseboard_fab2_lib.baseboard_fab2(sch_1):led_postcode_5" )
			)
			( signal "LED_POSTCODE_6"
				( objectStatus "@baseboard_fab2_lib.baseboard_fab2(sch_1):led_postcode_6" )
			)
			( signal "LED_POSTCODE_7"
				( objectStatus "@baseboard_fab2_lib.baseboard_fab2(sch_1):led_postcode_7" )
			)
			( signal "PU_10GBE_LOM_PCI_DISABLE_N"
				( objectStatus "@baseboard_fab2_lib.baseboard_fab2(sch_1):pu_10gbe_lom_pci_disable_n" )
			)
			( signal "PU_ADR_TIMER_HOLD_OFF_N"
				( objectStatus "@baseboard_fab2_lib.baseboard_fab2(sch_1):pu_adr_timer_hold_off_n" )
			)
			( signal "SGPIO_PCH_SATA_CLOCK"
				( objectStatus "@baseboard_fab2_lib.baseboard_fab2(sch_1):sgpio_pch_sata_clock" )
			)
			( signal "SGPIO_PCH_SATA_DOUT0"
				( objectStatus "@baseboard_fab2_lib.baseboard_fab2(sch_1):sgpio_pch_sata_dout0" )
			)
			( signal "SGPIO_PCH_SATA_LOAD"
				( objectStatus "@baseboard_fab2_lib.baseboard_fab2(sch_1):sgpio_pch_sata_load" )
			)
			( signal "SGPIO_PCH_SSATA_CLOCK"
				( objectStatus "@baseboard_fab2_lib.baseboard_fab2(sch_1):sgpio_pch_ssata_clock" )
			)
			( signal "SGPIO_PCH_SSATA_LOAD"
				( objectStatus "@baseboard_fab2_lib.baseboard_fab2(sch_1):sgpio_pch_ssata_load" )
			)
			( signal "SMB_LAN_STBY_LVC3_SCL_R1"
				( objectStatus "@baseboard_fab2_lib.baseboard_fab2(sch_1):smb_lan_stby_lvc3_scl_r1" )
			)
			( signal "SMB_LAN_STBY_LVC3_SCL_R2"
				( objectStatus "@baseboard_fab2_lib.baseboard_fab2(sch_1):smb_lan_stby_lvc3_scl_r2" )
			)
			( signal "SMB_LAN_STBY_LVC3_SDA_R1"
				( objectStatus "@baseboard_fab2_lib.baseboard_fab2(sch_1):smb_lan_stby_lvc3_sda_r1" )
			)
			( signal "SMB_LAN_STBY_LVC3_SDA_R2"
				( objectStatus "@baseboard_fab2_lib.baseboard_fab2(sch_1):smb_lan_stby_lvc3_sda_r2" )
			)
			( signal "SMB_PCH_MEZZ_LOM0_SCL"
				( objectStatus "@baseboard_fab2_lib.baseboard_fab2(sch_1):smb_pch_mezz_lom0_scl" )
			)
			( signal "SMB_PCH_MEZZ_LOM0_SDA"
				( objectStatus "@baseboard_fab2_lib.baseboard_fab2(sch_1):smb_pch_mezz_lom0_sda" )
			)
			( signal "SMB_PCH_MEZZ_LOM1_SCL"
				( objectStatus "@baseboard_fab2_lib.baseboard_fab2(sch_1):smb_pch_mezz_lom1_scl" )
			)
			( signal "SMB_PCH_MEZZ_LOM1_SDA"
				( objectStatus "@baseboard_fab2_lib.baseboard_fab2(sch_1):smb_pch_mezz_lom1_sda" )
			)
			( signal "SMB_PCH_MEZZ_LOM2_SCL"
				( objectStatus "@baseboard_fab2_lib.baseboard_fab2(sch_1):smb_pch_mezz_lom2_scl" )
			)
			( signal "SMB_PCH_MEZZ_LOM2_SDA"
				( objectStatus "@baseboard_fab2_lib.baseboard_fab2(sch_1):smb_pch_mezz_lom2_sda" )
			)
			( signal "SMB_PCH_MEZZ_LOM3_SCL"
				( objectStatus "@baseboard_fab2_lib.baseboard_fab2(sch_1):smb_pch_mezz_lom3_scl" )
			)
			( signal "SMB_PCH_MEZZ_LOM3_SDA"
				( objectStatus "@baseboard_fab2_lib.baseboard_fab2(sch_1):smb_pch_mezz_lom3_sda" )
			)
			( signal "SMB_SENSOR_STBY_LVC3_SCL_R1"
				( objectStatus "@baseboard_fab2_lib.baseboard_fab2(sch_1):smb_sensor_stby_lvc3_scl_r1" )
			)
			( signal "SMB_SENSOR_STBY_LVC3_SDA_R1"
				( objectStatus "@baseboard_fab2_lib.baseboard_fab2(sch_1):smb_sensor_stby_lvc3_sda_r1" )
			)
			( signal "SMB_VR_STBY_LVC3_SCL_R1"
				( objectStatus "@baseboard_fab2_lib.baseboard_fab2(sch_1):smb_vr_stby_lvc3_scl_r1" )
			)
			( signal "SMB_VR_STBY_LVC3_SDA_R1"
				( objectStatus "@baseboard_fab2_lib.baseboard_fab2(sch_1):smb_vr_stby_lvc3_sda_r1" )
			)
			( signal "TP_PCH_GPP_F12"
				( objectStatus "@baseboard_fab2_lib.baseboard_fab2(sch_1):tp_pch_gpp_f12" )
			)
			( signal "TP_PCH_GPP_J17"
				( objectStatus "@baseboard_fab2_lib.baseboard_fab2(sch_1):tp_pch_gpp_j17" )
			)
			( signal "TP_PCH_GPP_J19"
				( objectStatus "@baseboard_fab2_lib.baseboard_fab2(sch_1):tp_pch_gpp_j19" )
			)
			( signal "TP_PCH_GPP_J21"
				( objectStatus "@baseboard_fab2_lib.baseboard_fab2(sch_1):tp_pch_gpp_j21" )
			)
			( signal "TP_PCH_GPP_J23"
				( objectStatus "@baseboard_fab2_lib.baseboard_fab2(sch_1):tp_pch_gpp_j23" )
			)
			( signal "A_1P8_3P3_RCOMP"
				( objectStatus "@baseboard_fab2_lib.baseboard_fab2(sch_1):a_1p8_3p3_rcomp" )
			)
			( signal "FM_FLASH_DESC_OVERRIDE"
				( objectStatus "@baseboard_fab2_lib.baseboard_fab2(sch_1):fm_flash_desc_override" )
			)
			( signal "FM_INTRUDER_HDR_PCH_N"
				( objectStatus "@baseboard_fab2_lib.baseboard_fab2(sch_1):fm_intruder_hdr_pch_n" )
			)
			( signal "FM_OCP_MEZZB_PRES_N"
				( objectStatus "@baseboard_fab2_lib.baseboard_fab2(sch_1):fm_ocp_mezzb_pres_n" )
			)
			( signal "FM_OCP_MEZZC_PRES_N"
				( objectStatus "@baseboard_fab2_lib.baseboard_fab2(sch_1):fm_ocp_mezzc_pres_n" )
			)
			( signal "FM_PCH_PRSNT_N"
				( objectStatus "@baseboard_fab2_lib.baseboard_fab2(sch_1):fm_pch_prsnt_n" )
			)
			( signal "FM_SINT_PRSNT_N"
				( objectStatus "@baseboard_fab2_lib.baseboard_fab2(sch_1):fm_sint_prsnt_n" )
			)
			( signal "FM_WBG_PRSNT_N"
				( objectStatus "@baseboard_fab2_lib.baseboard_fab2(sch_1):fm_wbg_prsnt_n" )
			)
			( signal "H_CPU0_MEMABC_MEMHOT_PCH_N"
				( objectStatus "@baseboard_fab2_lib.baseboard_fab2(sch_1):h_cpu0_memabc_memhot_pch_n" )
			)
			( signal "H_CPU0_MEMDEF_MEMHOT_PCH_N"
				( objectStatus "@baseboard_fab2_lib.baseboard_fab2(sch_1):h_cpu0_memdef_memhot_pch_n" )
			)
			( signal "H_CPU1_MEMGHJ_MEMHOT_PCH_N"
				( objectStatus "@baseboard_fab2_lib.baseboard_fab2(sch_1):h_cpu1_memghj_memhot_pch_n" )
			)
			( signal "H_CPU1_MEMKLM_MEMHOT_PCH_N"
				( objectStatus "@baseboard_fab2_lib.baseboard_fab2(sch_1):h_cpu1_memklm_memhot_pch_n" )
			)
			( signal "RMII_BMC_PCH_SPRNGVLLE_CRSDV"
				( objectStatus "@baseboard_fab2_lib.baseboard_fab2(sch_1):rmii_bmc_pch_sprngvlle_crsdv" )
			)
			( signal "RMII_BMC_PCH_SPRNGVLLE_CRSDV_R1"
				( objectStatus "@baseboard_fab2_lib.baseboard_fab2(sch_1):rmii_bmc_pch_sprngvlle_crsdv_r1" )
			)
			( signal "RMII_BMC_PCH_SPRNGVLLE_RXER"
				( objectStatus "@baseboard_fab2_lib.baseboard_fab2(sch_1):rmii_bmc_pch_sprngvlle_rxer" )
			)
			( signal "RMII_BMC_PCH_SPRNGVLLE_RXER_R"
				( objectStatus "@baseboard_fab2_lib.baseboard_fab2(sch_1):rmii_bmc_pch_sprngvlle_rxer_r" )
			)
			( signal "RMII_BMC_PCH_SPRNGVLLE_TXD0"
				( objectStatus "@baseboard_fab2_lib.baseboard_fab2(sch_1):rmii_bmc_pch_sprngvlle_txd0" )
			)
			( signal "RMII_BMC_PCH_SPRNGVLLE_TXD1"
				( objectStatus "@baseboard_fab2_lib.baseboard_fab2(sch_1):rmii_bmc_pch_sprngvlle_txd1" )
			)
			( signal "RMII_BMC_PCH_SPRNGVLLE_TXEN"
				( objectStatus "@baseboard_fab2_lib.baseboard_fab2(sch_1):rmii_bmc_pch_sprngvlle_txen" )
			)
			( signal "RMII_PCH_SPRNGVLLE_ARB_IN"
				( objectStatus "@baseboard_fab2_lib.baseboard_fab2(sch_1):rmii_pch_sprngvlle_arb_in" )
			)
			( signal "RMII_PCH_SPRNGVLLE_ARB_OUT"
				( objectStatus "@baseboard_fab2_lib.baseboard_fab2(sch_1):rmii_pch_sprngvlle_arb_out" )
			)
			( signal "RMII_PCH_SPRNGVLLE_ARB_OUT_R"
				( objectStatus "@baseboard_fab2_lib.baseboard_fab2(sch_1):rmii_pch_sprngvlle_arb_out_r" )
			)
			( signal "RMII_SPRNGVLLE_BMC_PCH_RXD0"
				( objectStatus "@baseboard_fab2_lib.baseboard_fab2(sch_1):rmii_sprngvlle_bmc_pch_rxd0" )
			)
			( signal "RMII_SPRNGVLLE_BMC_PCH_RXD0_R1"
				( objectStatus "@baseboard_fab2_lib.baseboard_fab2(sch_1):rmii_sprngvlle_bmc_pch_rxd0_r1" )
			)
			( signal "RMII_SPRNGVLLE_BMC_PCH_RXD1"
				( objectStatus "@baseboard_fab2_lib.baseboard_fab2(sch_1):rmii_sprngvlle_bmc_pch_rxd1" )
			)
			( signal "RMII_SPRNGVLLE_BMC_PCH_RXD1_R1"
				( objectStatus "@baseboard_fab2_lib.baseboard_fab2(sch_1):rmii_sprngvlle_bmc_pch_rxd1_r1" )
			)
			( signal "RST_PCIE_PCH_PERST_N"
				( objectStatus "@baseboard_fab2_lib.baseboard_fab2(sch_1):rst_pcie_pch_perst_n" )
			)
			( signal "RST_RTCRST_N"
				( objectStatus "@baseboard_fab2_lib.baseboard_fab2(sch_1):rst_rtcrst_n" )
			)
			( signal "RST_SRTCRST_N"
				( objectStatus "@baseboard_fab2_lib.baseboard_fab2(sch_1):rst_srtcrst_n" )
			)
			( signal "SPI_PCH_CLK"
				( objectStatus "@baseboard_fab2_lib.baseboard_fab2(sch_1):spi_pch_clk" )
			)
			( signal "SPI_PCH_CS0_N"
				( objectStatus "@baseboard_fab2_lib.baseboard_fab2(sch_1):spi_pch_cs0_n" )
			)
			( signal "SPI_PCH_CS0_R_N"
				( objectStatus "@baseboard_fab2_lib.baseboard_fab2(sch_1):spi_pch_cs0_r_n" )
			)
			( signal "SPI_PCH_IO3"
				( objectStatus "@baseboard_fab2_lib.baseboard_fab2(sch_1):spi_pch_io3" )
			)
			( signal "SPI_PCH_MISO"
				( objectStatus "@baseboard_fab2_lib.baseboard_fab2(sch_1):spi_pch_miso" )
			)
			( signal "SPI_PCH_MOSI_R"
				( objectStatus "@baseboard_fab2_lib.baseboard_fab2(sch_1):spi_pch_mosi_r" )
			)
			( signal "SPI_PCH_TPM_CS_N"
				( objectStatus "@baseboard_fab2_lib.baseboard_fab2(sch_1):spi_pch_tpm_cs_n" )
			)
			( signal "TP_PCH_DISPA_BCLK"
				( objectStatus "@baseboard_fab2_lib.baseboard_fab2(sch_1):tp_pch_dispa_bclk" )
			)
			( signal "TP_PCH_DISPA_SDI"
				( objectStatus "@baseboard_fab2_lib.baseboard_fab2(sch_1):tp_pch_dispa_sdi" )
			)
			( signal "TP_PCH_DISPA_SDO"
				( objectStatus "@baseboard_fab2_lib.baseboard_fab2(sch_1):tp_pch_dispa_sdo" )
			)
			( signal "TP_PCH_GPP_L10"
				( objectStatus "@baseboard_fab2_lib.baseboard_fab2(sch_1):tp_pch_gpp_l10" )
			)
			( signal "TP_PCH_GPP_L11"
				( objectStatus "@baseboard_fab2_lib.baseboard_fab2(sch_1):tp_pch_gpp_l11" )
			)
			( signal "TP_PCH_HDA_BCLK"
				( objectStatus "@baseboard_fab2_lib.baseboard_fab2(sch_1):tp_pch_hda_bclk" )
			)
			( signal "TP_PCH_HDA_SDI_0"
				( objectStatus "@baseboard_fab2_lib.baseboard_fab2(sch_1):tp_pch_hda_sdi_0" )
			)
			( signal "TP_PCH_HDA_SDI_1"
				( objectStatus "@baseboard_fab2_lib.baseboard_fab2(sch_1):tp_pch_hda_sdi_1" )
			)
			( signal "TP_PCH_HDA_SYNC"
				( objectStatus "@baseboard_fab2_lib.baseboard_fab2(sch_1):tp_pch_hda_sync" )
			)
			( signal "TP_PCH_HSA_RST_N"
				( objectStatus "@baseboard_fab2_lib.baseboard_fab2(sch_1):tp_pch_hsa_rst_n" )
			)
			( signal "TP_PCH_RSVD0"
				( objectStatus "@baseboard_fab2_lib.baseboard_fab2(sch_1):tp_pch_rsvd0" )
			)
			( signal "TP_PCH_RSVD1"
				( objectStatus "@baseboard_fab2_lib.baseboard_fab2(sch_1):tp_pch_rsvd1" )
			)
			( signal "TP_PCH_RSVD12"
				( objectStatus "@baseboard_fab2_lib.baseboard_fab2(sch_1):tp_pch_rsvd12" )
			)
			( signal "TP_PCH_RSVD13"
				( objectStatus "@baseboard_fab2_lib.baseboard_fab2(sch_1):tp_pch_rsvd13" )
			)
			( signal "TP_PCH_RSVD14"
				( objectStatus "@baseboard_fab2_lib.baseboard_fab2(sch_1):tp_pch_rsvd14" )
			)
			( signal "TP_PCH_RSVD15"
				( objectStatus "@baseboard_fab2_lib.baseboard_fab2(sch_1):tp_pch_rsvd15" )
			)
			( signal "TP_PCH_RSVD16"
				( objectStatus "@baseboard_fab2_lib.baseboard_fab2(sch_1):tp_pch_rsvd16" )
			)
			( signal "TP_PCH_RSVD17"
				( objectStatus "@baseboard_fab2_lib.baseboard_fab2(sch_1):tp_pch_rsvd17" )
			)
			( signal "TP_PCH_RSVD18"
				( objectStatus "@baseboard_fab2_lib.baseboard_fab2(sch_1):tp_pch_rsvd18" )
			)
			( signal "TP_PCH_RSVD19"
				( objectStatus "@baseboard_fab2_lib.baseboard_fab2(sch_1):tp_pch_rsvd19" )
			)
			( signal "TP_PCH_RSVD2"
				( objectStatus "@baseboard_fab2_lib.baseboard_fab2(sch_1):tp_pch_rsvd2" )
			)
			( signal "TP_PCH_RSVD20"
				( objectStatus "@baseboard_fab2_lib.baseboard_fab2(sch_1):tp_pch_rsvd20" )
			)
			( signal "TP_PCH_RSVD21"
				( objectStatus "@baseboard_fab2_lib.baseboard_fab2(sch_1):tp_pch_rsvd21" )
			)
			( signal "TP_PCH_RSVD22"
				( objectStatus "@baseboard_fab2_lib.baseboard_fab2(sch_1):tp_pch_rsvd22" )
			)
			( signal "TP_PCH_RSVD23"
				( objectStatus "@baseboard_fab2_lib.baseboard_fab2(sch_1):tp_pch_rsvd23" )
			)
			( signal "TP_PCH_RSVD24"
				( objectStatus "@baseboard_fab2_lib.baseboard_fab2(sch_1):tp_pch_rsvd24" )
			)
			( signal "TP_PCH_RSVD25"
				( objectStatus "@baseboard_fab2_lib.baseboard_fab2(sch_1):tp_pch_rsvd25" )
			)
			( signal "TP_PCH_RSVD26"
				( objectStatus "@baseboard_fab2_lib.baseboard_fab2(sch_1):tp_pch_rsvd26" )
			)
			( signal "TP_PCH_RSVD27"
				( objectStatus "@baseboard_fab2_lib.baseboard_fab2(sch_1):tp_pch_rsvd27" )
			)
			( signal "TP_PCH_RSVD3"
				( objectStatus "@baseboard_fab2_lib.baseboard_fab2(sch_1):tp_pch_rsvd3" )
			)
			( signal "TP_PCH_RSVD4"
				( objectStatus "@baseboard_fab2_lib.baseboard_fab2(sch_1):tp_pch_rsvd4" )
			)
			( signal "TP_PCH_RSVD46"
				( objectStatus "@baseboard_fab2_lib.baseboard_fab2(sch_1):tp_pch_rsvd46" )
			)
			( signal "TP_PCH_RSVD5"
				( objectStatus "@baseboard_fab2_lib.baseboard_fab2(sch_1):tp_pch_rsvd5" )
			)
			( signal "TP_PCH_RSVD6"
				( objectStatus "@baseboard_fab2_lib.baseboard_fab2(sch_1):tp_pch_rsvd6" )
			)
			( signal "TP_PCH_RSVD7"
				( objectStatus "@baseboard_fab2_lib.baseboard_fab2(sch_1):tp_pch_rsvd7" )
			)
			( signal "TP_PCH_RSVD8"
				( objectStatus "@baseboard_fab2_lib.baseboard_fab2(sch_1):tp_pch_rsvd8" )
			)
			( signal "TP_PCH_RSVD9"
				( objectStatus "@baseboard_fab2_lib.baseboard_fab2(sch_1):tp_pch_rsvd9" )
			)
			( signal "TP_SPI_PCH_CS1_R1_N"
				( objectStatus "@baseboard_fab2_lib.baseboard_fab2(sch_1):tp_spi_pch_cs1_r1_n" )
			)
			( signal "A_PVCCRTC_EXT_CAP"
				( objectStatus "@baseboard_fab2_lib.baseboard_fab2(sch_1):a_pvccrtc_ext_cap" )
			)
			( signal "P1V05_PCH_STBY_ISCLK_PLL"
				( attribute "VOLTAGE" "1.05V"
					( Units "uVoltage" "V" 1.000000)
					( Status sAliasFlattened )
					( Origin gFrontEnd )
				)
				( objectStatus "@baseboard_fab2_lib.baseboard_fab2(sch_1):p1v05_pch_stby_isclk_pll" )
			)
			( signal "P1V05_PCH_STBY_VCCA_PLL0"
				( attribute "VOLTAGE" "1.05V"
					( Units "uVoltage" "V" 1.000000)
					( Status sAliasFlattened )
					( Origin gFrontEnd )
				)
				( objectStatus "@baseboard_fab2_lib.baseboard_fab2(sch_1):p1v05_pch_stby_vcca_pll0" )
			)
			( signal "P1V05_PCH_STBY_VCCA_PLL1"
				( attribute "VOLTAGE" "1.05V"
					( Units "uVoltage" "V" 1.000000)
					( Status sAliasFlattened )
					( Origin gFrontEnd )
				)
				( objectStatus "@baseboard_fab2_lib.baseboard_fab2(sch_1):p1v05_pch_stby_vcca_pll1" )
			)
			( signal "P1V05_PCH_STBY_VCCA_XTAL"
				( attribute "VOLTAGE" "1.05V"
					( Units "uVoltage" "V" 1.000000)
					( Status sAliasFlattened )
					( Origin gFrontEnd )
				)
				( objectStatus "@baseboard_fab2_lib.baseboard_fab2(sch_1):p1v05_pch_stby_vcca_xtal" )
			)
			( signal "P1V05_PCH_STBY_WM20_PLL"
				( attribute "VOLTAGE" "1.05V"
					( Units "uVoltage" "V" 1.000000)
					( Status sAliasFlattened )
					( Origin gFrontEnd )
				)
				( objectStatus "@baseboard_fab2_lib.baseboard_fab2(sch_1):p1v05_pch_stby_wm20_pll" )
			)
			( signal "P1V05_PCH_STBY_WM26_PLL"
				( attribute "VOLTAGE" "1.05V"
					( Units "uVoltage" "V" 1.000000)
					( Status sAliasFlattened )
					( Origin gFrontEnd )
				)
				( objectStatus "@baseboard_fab2_lib.baseboard_fab2(sch_1):p1v05_pch_stby_wm26_pll" )
			)
			( signal "P1V8_PCH_STBY"
				( attribute "VOLTAGE" "1.8V"
					( Units "uVoltage" "V" 1.000000)
					( Status sAliasFlattened )
					( Origin gFrontEnd )
				)
				( objectStatus "@baseboard_fab2_lib.baseboard_fab2(sch_1):p1v8_pch_stby" )
			)
			( signal "P3V3_RTC_STBY"
				( attribute "VOLTAGE" "3.3V"
					( Units "uVoltage" "V" 1.000000)
					( Status sAliasFlattened )
					( Origin gFrontEnd )
				)
				( objectStatus "@baseboard_fab2_lib.baseboard_fab2(sch_1):p3v3_rtc_stby" )
			)
			( signal "TP_PCH_RSVD28"
				( objectStatus "@baseboard_fab2_lib.baseboard_fab2(sch_1):tp_pch_rsvd28" )
			)
			( signal "TP_PCH_RSVD29"
				( objectStatus "@baseboard_fab2_lib.baseboard_fab2(sch_1):tp_pch_rsvd29" )
			)
			( signal "TP_PCH_RSVD30"
				( objectStatus "@baseboard_fab2_lib.baseboard_fab2(sch_1):tp_pch_rsvd30" )
			)
			( signal "TP_PCH_RSVD31"
				( objectStatus "@baseboard_fab2_lib.baseboard_fab2(sch_1):tp_pch_rsvd31" )
			)
			( signal "TP_PCH_RSVD58"
				( objectStatus "@baseboard_fab2_lib.baseboard_fab2(sch_1):tp_pch_rsvd58" )
			)
			( signal "TP_PCH_RSVD59"
				( objectStatus "@baseboard_fab2_lib.baseboard_fab2(sch_1):tp_pch_rsvd59" )
			)
			( signal "PVNN_PCH_STBY"
				( attribute "VOLTAGE" "1.0V"
					( Units "uVoltage" "V" 1.000000)
					( Status sAliasFlattened )
					( Origin gFrontEnd )
				)
				( objectStatus "@baseboard_fab2_lib.baseboard_fab2(sch_1):pvnn_pch_stby" )
			)
			( signal "VSENSE_PVNN_PCH_STBY_FPK"
				( objectStatus "@baseboard_fab2_lib.baseboard_fab2(sch_1):vsense_pvnn_pch_stby_fpk" )
			)
			( signal "VSENSE_PVNN_PCH_STBY_QAT"
				( objectStatus "@baseboard_fab2_lib.baseboard_fab2(sch_1):vsense_pvnn_pch_stby_qat" )
			)
			( signal "RST_RSMRST_DLY"
				( objectStatus "@baseboard_fab2_lib.baseboard_fab2(sch_1):rst_rsmrst_dly" )
			)
			( signal "FM_THERMTRIP_DLY"
				( objectStatus "@baseboard_fab2_lib.baseboard_fab2(sch_1):fm_thermtrip_dly" )
			)
			( signal "FM_THERMTRIP_DLY_R"
				( objectStatus "@baseboard_fab2_lib.baseboard_fab2(sch_1):fm_thermtrip_dly_r" )
			)
			( signal "RST_PLTRST_BUF_N"
				( objectStatus "@baseboard_fab2_lib.baseboard_fab2(sch_1):rst_pltrst_buf_n" )
			)
			( signal "FM_CPLD_UART_CH_LOCK_N"
				( objectStatus "@baseboard_fab2_lib.baseboard_fab2(sch_1):fm_cpld_uart_ch_lock_n" )
			)
			( signal "FM_DIS_ADR_DLY"
				( objectStatus "@baseboard_fab2_lib.baseboard_fab2(sch_1):fm_dis_adr_dly" )
			)
			( signal "FM_PCH_SATA_RAID_KEY_R"
				( objectStatus "@baseboard_fab2_lib.baseboard_fab2(sch_1):fm_pch_sata_raid_key_r" )
			)
			( signal "PU_KEY_CONN_PIN2_R"
				( objectStatus "@baseboard_fab2_lib.baseboard_fab2(sch_1):pu_key_conn_pin2_r" )
			)
			( signal "TP_JUMPER_BLOCK_1_7"
				( objectStatus "@baseboard_fab2_lib.baseboard_fab2(sch_1):\tp_jumper_block_ 1_7\" )
			)
			( signal "TP_JUMPER_BLOCK_1_1"
				( objectStatus "@baseboard_fab2_lib.baseboard_fab2(sch_1):tp_jumper_block_1_1" )
			)
			( signal "TP_JUMPER_BLOCK_1_2"
				( objectStatus "@baseboard_fab2_lib.baseboard_fab2(sch_1):tp_jumper_block_1_2" )
			)
			( signal "TP_JUMPER_BLOCK_1_8"
				( objectStatus "@baseboard_fab2_lib.baseboard_fab2(sch_1):tp_jumper_block_1_8" )
			)
			( signal "FM_BIOS_TOP_SWAP_SPKR_R"
				( objectStatus "@baseboard_fab2_lib.baseboard_fab2(sch_1):fm_bios_top_swap_spkr_r" )
			)
			( signal "PD_ME_RCVR_N"
				( objectStatus "@baseboard_fab2_lib.baseboard_fab2(sch_1):pd_me_rcvr_n" )
			)
			( signal "PD_PASSWORD_CLEAR"
				( objectStatus "@baseboard_fab2_lib.baseboard_fab2(sch_1):pd_password_clear" )
			)
			( signal "PU_BIOS_RECOVER_BOOT"
				( objectStatus "@baseboard_fab2_lib.baseboard_fab2(sch_1):pu_bios_recover_boot" )
			)
			( signal "PU_BIOS_USB_RECOVERY"
				( objectStatus "@baseboard_fab2_lib.baseboard_fab2(sch_1):pu_bios_usb_recovery" )
			)
			( signal "RST_PLTRST_TOP_SWAP"
				( objectStatus "@baseboard_fab2_lib.baseboard_fab2(sch_1):rst_pltrst_top_swap" )
			)
			( signal "TP_BIOS_RECOVER_BOOT"
				( objectStatus "@baseboard_fab2_lib.baseboard_fab2(sch_1):tp_bios_recover_boot" )
			)
			( signal "TP_BIOS_USB_RECOVERY"
				( objectStatus "@baseboard_fab2_lib.baseboard_fab2(sch_1):tp_bios_usb_recovery" )
			)
			( signal "TP_ME_RCVR_BOOT"
				( objectStatus "@baseboard_fab2_lib.baseboard_fab2(sch_1):tp_me_rcvr_boot" )
			)
			( signal "TP_PASSWORD_CLEAR"
				( objectStatus "@baseboard_fab2_lib.baseboard_fab2(sch_1):tp_password_clear" )
			)
			( signal "FM_BMC_DISABLE"
				( objectStatus "@baseboard_fab2_lib.baseboard_fab2(sch_1):fm_bmc_disable" )
			)
			( signal "FM_ROMA<0>"
				( objectStatus "@baseboard_fab2_lib.baseboard_fab2(sch_1):fm_roma(0)" )
			)
			( signal "PD_IE_DEBUG_MODE"
				( objectStatus "@baseboard_fab2_lib.baseboard_fab2(sch_1):pd_ie_debug_mode" )
			)
			( signal "PD_RST_RTCRST_N"
				( objectStatus "@baseboard_fab2_lib.baseboard_fab2(sch_1):pd_rst_rtcrst_n" )
			)
			( signal "TP_BMC_DISABLE"
				( objectStatus "@baseboard_fab2_lib.baseboard_fab2(sch_1):tp_bmc_disable" )
			)
			( signal "TP_IE_DEBUG_MODE"
				( objectStatus "@baseboard_fab2_lib.baseboard_fab2(sch_1):tp_ie_debug_mode" )
			)
			( signal "TP_JUMPER_BLOCK_2_10"
				( objectStatus "@baseboard_fab2_lib.baseboard_fab2(sch_1):tp_jumper_block_2_10" )
			)
			( signal "TP_JUMPER_BLOCK_2_12"
				( objectStatus "@baseboard_fab2_lib.baseboard_fab2(sch_1):tp_jumper_block_2_12" )
			)
			( signal "TP_JUMPER_BLOCK_2_8"
				( objectStatus "@baseboard_fab2_lib.baseboard_fab2(sch_1):tp_jumper_block_2_8" )
			)
			( signal "TP_RST_RTCRST_N"
				( objectStatus "@baseboard_fab2_lib.baseboard_fab2(sch_1):tp_rst_rtcrst_n" )
			)
			( signal "SMB_BMC_PMBUS_STBY_LVC3_SCL"
				( objectStatus "@baseboard_fab2_lib.baseboard_fab2(sch_1):smb_bmc_pmbus_stby_lvc3_scl" )
			)
			( signal "SMB_BMC_PMBUS_STBY_LVC3_SDA"
				( objectStatus "@baseboard_fab2_lib.baseboard_fab2(sch_1):smb_bmc_pmbus_stby_lvc3_sda" )
			)
			( signal "SMB_LAN_STBY_LVC3_SCL"
				( objectStatus "@baseboard_fab2_lib.baseboard_fab2(sch_1):smb_lan_stby_lvc3_scl" )
			)
			( signal "SMB_LAN_STBY_LVC3_SDA"
				( objectStatus "@baseboard_fab2_lib.baseboard_fab2(sch_1):smb_lan_stby_lvc3_sda" )
			)
			( signal "SMB_SENSOR_PCH_STBY_LVC3_SCL"
				( objectStatus "@baseboard_fab2_lib.baseboard_fab2(sch_1):smb_sensor_pch_stby_lvc3_scl" )
			)
			( signal "SMB_SENSOR_PCH_STBY_LVC3_SDA"
				( objectStatus "@baseboard_fab2_lib.baseboard_fab2(sch_1):smb_sensor_pch_stby_lvc3_sda" )
			)
			( signal "SMB_SMLINK0_STBY_LVC3_SCL"
				( objectStatus "@baseboard_fab2_lib.baseboard_fab2(sch_1):smb_smlink0_stby_lvc3_scl" )
			)
			( signal "SMB_SMLINK0_STBY_LVC3_SDA"
				( objectStatus "@baseboard_fab2_lib.baseboard_fab2(sch_1):smb_smlink0_stby_lvc3_sda" )
			)
			( signal "SMB_VR_STBY_LVC3_SCL"
				( objectStatus "@baseboard_fab2_lib.baseboard_fab2(sch_1):smb_vr_stby_lvc3_scl" )
			)
			( signal "SMB_VR_STBY_LVC3_SDA"
				( objectStatus "@baseboard_fab2_lib.baseboard_fab2(sch_1):smb_vr_stby_lvc3_sda" )
			)
			( signal "A_CBOT"
				( objectStatus "@baseboard_fab2_lib.baseboard_fab2(sch_1):a_cbot" )
			)
			( signal "A_CTOP"
				( objectStatus "@baseboard_fab2_lib.baseboard_fab2(sch_1):a_ctop" )
			)
			( signal "FM_PE_SPRV_WAKE_N"
				( objectStatus "@baseboard_fab2_lib.baseboard_fab2(sch_1):fm_pe_sprv_wake_n" )
			)
			( signal "LED_LAN_0_N"
				( objectStatus "@baseboard_fab2_lib.baseboard_fab2(sch_1):led_lan_0_n" )
			)
			( signal "LED_LAN_1_N"
				( objectStatus "@baseboard_fab2_lib.baseboard_fab2(sch_1):led_lan_1_n" )
			)
			( signal "LED_LAN_2_N"
				( objectStatus "@baseboard_fab2_lib.baseboard_fab2(sch_1):led_lan_2_n" )
			)
			( signal "NC_SPRNGVLLE_22"
				( objectStatus "@baseboard_fab2_lib.baseboard_fab2(sch_1):nc_sprngvlle_22" )
			)
			( signal "NIC_MDI_SPRV_RJ45_0_DN"
				( objectStatus "@baseboard_fab2_lib.baseboard_fab2(sch_1):nic_mdi_sprv_rj45_0_dn" )
			)
			( signal "NIC_MDI_SPRV_RJ45_0_DP"
				( objectStatus "@baseboard_fab2_lib.baseboard_fab2(sch_1):nic_mdi_sprv_rj45_0_dp" )
			)
			( signal "NIC_MDI_SPRV_RJ45_1_DN"
				( objectStatus "@baseboard_fab2_lib.baseboard_fab2(sch_1):nic_mdi_sprv_rj45_1_dn" )
			)
			( signal "NIC_MDI_SPRV_RJ45_1_DP"
				( objectStatus "@baseboard_fab2_lib.baseboard_fab2(sch_1):nic_mdi_sprv_rj45_1_dp" )
			)
			( signal "NIC_SER_N_MDI_3_DN"
				( objectStatus "@baseboard_fab2_lib.baseboard_fab2(sch_1):nic_ser_n_mdi_3_dn" )
			)
			( signal "NIC_SER_P_MDI_3_DP"
				( objectStatus "@baseboard_fab2_lib.baseboard_fab2(sch_1):nic_ser_p_mdi_3_dp" )
			)
			( signal "NIC_SET_N_MDI_2_DN"
				( objectStatus "@baseboard_fab2_lib.baseboard_fab2(sch_1):nic_set_n_mdi_2_dn" )
			)
			( signal "NIC_SET_P_MDI_2_DP"
				( objectStatus "@baseboard_fab2_lib.baseboard_fab2(sch_1):nic_set_p_mdi_2_dp" )
			)
			( signal "P0V9_LAN"
				( attribute "VOLTAGE" "0.9V"
					( Units "uVoltage" "V" 1.000000)
					( Status sAliasFlattened )
					( Origin gFrontEnd )
				)
				( objectStatus "@baseboard_fab2_lib.baseboard_fab2(sch_1):p0v9_lan" )
			)
			( signal "P0V9_LAN_I210"
				( attribute "VOLTAGE" "0.9"
					( Units "uVoltage" "V" 1.000000)
					( Status sAliasFlattened )
					( Origin gFrontEnd )
				)
				( objectStatus "@baseboard_fab2_lib.baseboard_fab2(sch_1):p0v9_lan_i210" )
			)
			( signal "P1V5_LAN"
				( attribute "VOLTAGE" "1.5V"
					( Units "uVoltage" "V" 1.000000)
					( Status sAliasFlattened )
					( Origin gFrontEnd )
				)
				( objectStatus "@baseboard_fab2_lib.baseboard_fab2(sch_1):p1v5_lan" )
			)
			( signal "P1V5_LAN_I210"
				( attribute "VOLTAGE" "1.5"
					( Units "uVoltage" "V" 1.000000)
					( Status sAliasFlattened )
					( Origin gFrontEnd )
				)
				( objectStatus "@baseboard_fab2_lib.baseboard_fab2(sch_1):p1v5_lan_i210" )
			)
			( signal "P3V3_STBY_P1V5_LAN_I210"
				( attribute "VOLTAGE" "3.3"
					( Units "uVoltage" "V" 1.000000)
					( Status sAliasFlattened )
					( Origin gFrontEnd )
				)
				( objectStatus "@baseboard_fab2_lib.baseboard_fab2(sch_1):p3v3_stby_p1v5_lan_i210" )
			)
			( signal "PD_SPRV_RSET"
				( objectStatus "@baseboard_fab2_lib.baseboard_fab2(sch_1):pd_sprv_rset" )
			)
			( signal "PE_PCH_SPRV_RX_DN"
				( objectStatus "@baseboard_fab2_lib.baseboard_fab2(sch_1):pe_pch_sprv_rx_dn" )
			)
			( signal "PE_PCH_SPRV_RX_DP"
				( objectStatus "@baseboard_fab2_lib.baseboard_fab2(sch_1):pe_pch_sprv_rx_dp" )
			)
			( signal "PE_PCH_SPRV_TX_C_DN"
				( objectStatus "@baseboard_fab2_lib.baseboard_fab2(sch_1):pe_pch_sprv_tx_c_dn" )
			)
			( signal "PE_PCH_SPRV_TX_C_DP"
				( objectStatus "@baseboard_fab2_lib.baseboard_fab2(sch_1):pe_pch_sprv_tx_c_dp" )
			)
			( signal "PU_JTAG_SPRV_TCK"
				( objectStatus "@baseboard_fab2_lib.baseboard_fab2(sch_1):pu_jtag_sprv_tck" )
			)
			( signal "PU_JTAG_SPRV_TDI"
				( objectStatus "@baseboard_fab2_lib.baseboard_fab2(sch_1):pu_jtag_sprv_tdi" )
			)
			( signal "PU_JTAG_SPRV_TDO"
				( objectStatus "@baseboard_fab2_lib.baseboard_fab2(sch_1):pu_jtag_sprv_tdo" )
			)
			( signal "PU_JTAG_SPRV_TMS"
				( objectStatus "@baseboard_fab2_lib.baseboard_fab2(sch_1):pu_jtag_sprv_tms" )
			)
			( signal "PU_SPRV_LAN_PWR_GOOD"
				( objectStatus "@baseboard_fab2_lib.baseboard_fab2(sch_1):pu_sprv_lan_pwr_good" )
			)
			( signal "RMII_BMC_PCH_SPRNGVLLE_CRSDV_R"
				( objectStatus "@baseboard_fab2_lib.baseboard_fab2(sch_1):rmii_bmc_pch_sprngvlle_crsdv_r" )
			)
			( signal "RMII_PCH_SPRNGVLLE_ARB_IN_R"
				( objectStatus "@baseboard_fab2_lib.baseboard_fab2(sch_1):rmii_pch_sprngvlle_arb_in_r" )
			)
			( signal "RMII_SPRNGVLLE_BMC_PCH_RXD0_R"
				( objectStatus "@baseboard_fab2_lib.baseboard_fab2(sch_1):rmii_sprngvlle_bmc_pch_rxd0_r" )
			)
			( signal "RMII_SPRNGVLLE_BMC_PCH_RXD1_R"
				( objectStatus "@baseboard_fab2_lib.baseboard_fab2(sch_1):rmii_sprngvlle_bmc_pch_rxd1_r" )
			)
			( signal "RST_PLTRST_SPRV_R_N"
				( objectStatus "@baseboard_fab2_lib.baseboard_fab2(sch_1):rst_pltrst_sprv_r_n" )
			)
			( signal "SMB_SPRINGVILLE_STBY_LVC3_SCL"
				( objectStatus "@baseboard_fab2_lib.baseboard_fab2(sch_1):smb_springville_stby_lvc3_scl" )
			)
			( signal "SMB_SPRINGVILLE_STBY_LVC3_SDA"
				( objectStatus "@baseboard_fab2_lib.baseboard_fab2(sch_1):smb_springville_stby_lvc3_sda" )
			)
			( signal "SPI_NIC_CS_N"
				( objectStatus "@baseboard_fab2_lib.baseboard_fab2(sch_1):spi_nic_cs_n" )
			)
			( signal "SPI_NIC_CS_R_N"
				( objectStatus "@baseboard_fab2_lib.baseboard_fab2(sch_1):spi_nic_cs_r_n" )
			)
			( signal "SPI_NIC_MISO"
				( objectStatus "@baseboard_fab2_lib.baseboard_fab2(sch_1):spi_nic_miso" )
			)
			( signal "SPI_NIC_MOSI"
				( objectStatus "@baseboard_fab2_lib.baseboard_fab2(sch_1):spi_nic_mosi" )
			)
			( signal "SPI_NIC_MOSI_R"
				( objectStatus "@baseboard_fab2_lib.baseboard_fab2(sch_1):spi_nic_mosi_r" )
			)
			( signal "SPI_NIC_SCLK"
				( objectStatus "@baseboard_fab2_lib.baseboard_fab2(sch_1):spi_nic_sclk" )
			)
			( signal "SPI_NIC_SCLK_R"
				( objectStatus "@baseboard_fab2_lib.baseboard_fab2(sch_1):spi_nic_sclk_r" )
			)
			( signal "TP_SPRV_SDP0"
				( objectStatus "@baseboard_fab2_lib.baseboard_fab2(sch_1):tp_sprv_sdp0" )
			)
			( signal "TP_SPRV_SDP1"
				( objectStatus "@baseboard_fab2_lib.baseboard_fab2(sch_1):tp_sprv_sdp1" )
			)
			( signal "TP_SPRV_SDP2"
				( objectStatus "@baseboard_fab2_lib.baseboard_fab2(sch_1):tp_sprv_sdp2" )
			)
			( signal "TP_SPRV_SDP3"
				( objectStatus "@baseboard_fab2_lib.baseboard_fab2(sch_1):tp_sprv_sdp3" )
			)
			( signal "XTAL_25MHZ_IN"
				( objectStatus "@baseboard_fab2_lib.baseboard_fab2(sch_1):xtal_25mhz_in" )
			)
			( signal "XTAL_25MHZ_IN_R"
				( objectStatus "@baseboard_fab2_lib.baseboard_fab2(sch_1):xtal_25mhz_in_r" )
			)
			( signal "XTAL_25MHZ_OUT"
				( objectStatus "@baseboard_fab2_lib.baseboard_fab2(sch_1):xtal_25mhz_out" )
			)
			( signal "XTAL_25MHZ_OUT_R"
				( objectStatus "@baseboard_fab2_lib.baseboard_fab2(sch_1):xtal_25mhz_out_r" )
			)
			( signal "PU_NV_HOLD_N"
				( objectStatus "@baseboard_fab2_lib.baseboard_fab2(sch_1):pu_nv_hold_n" )
			)
			( signal "PU_NV_WP_N"
				( objectStatus "@baseboard_fab2_lib.baseboard_fab2(sch_1):pu_nv_wp_n" )
			)
			( signal "SPI_NIC_MISO_R"
				( objectStatus "@baseboard_fab2_lib.baseboard_fab2(sch_1):spi_nic_miso_r" )
			)
			( signal "GND_LAN_TRCT1234_C"
				( attribute "VOLTAGE" "0"
					( Units "uVoltage" "V" 1.000000)
					( Status sAliasFlattened )
					( Origin gFrontEnd )
				)
				( objectStatus "@baseboard_fab2_lib.baseboard_fab2(sch_1):gnd_lan_trct1234_c" )
			)
			( signal "GND_NIC"
				( attribute "VOLTAGE" "0.0V"
					( Units "uVoltage" "V" 1.000000)
					( Status sAliasFlattened )
					( Origin gFrontEnd )
				)
				( objectStatus "@baseboard_fab2_lib.baseboard_fab2(sch_1):gnd_nic" )
			)
			( signal "LED_LAN_0_R_N"
				( objectStatus "@baseboard_fab2_lib.baseboard_fab2(sch_1):led_lan_0_r_n" )
			)
			( signal "LED_LAN_1_R_N"
				( objectStatus "@baseboard_fab2_lib.baseboard_fab2(sch_1):led_lan_1_r_n" )
			)
			( signal "LED_LAN_2_R_N"
				( objectStatus "@baseboard_fab2_lib.baseboard_fab2(sch_1):led_lan_2_r_n" )
			)
			( signal "NIC_LED_ACT_ANODE_R"
				( objectStatus "@baseboard_fab2_lib.baseboard_fab2(sch_1):nic_led_act_anode_r" )
			)
			( signal "NIC_MDI_MNG_RX_DN"
				( objectStatus "@baseboard_fab2_lib.baseboard_fab2(sch_1):nic_mdi_mng_rx_dn" )
			)
			( signal "NIC_MDI_MNG_RX_DP"
				( objectStatus "@baseboard_fab2_lib.baseboard_fab2(sch_1):nic_mdi_mng_rx_dp" )
			)
			( signal "NIC_MDI_MNG_TX_DN"
				( objectStatus "@baseboard_fab2_lib.baseboard_fab2(sch_1):nic_mdi_mng_tx_dn" )
			)
			( signal "NIC_MDI_MNG_TX_DP"
				( objectStatus "@baseboard_fab2_lib.baseboard_fab2(sch_1):nic_mdi_mng_tx_dp" )
			)
			( signal "NIC_MDI_SPRV_RJ45_0_R_DN"
				( objectStatus "@baseboard_fab2_lib.baseboard_fab2(sch_1):nic_mdi_sprv_rj45_0_r_dn" )
			)
			( signal "NIC_MDI_SPRV_RJ45_0_R_DP"
				( objectStatus "@baseboard_fab2_lib.baseboard_fab2(sch_1):nic_mdi_sprv_rj45_0_r_dp" )
			)
			( signal "NIC_MDI_SPRV_RJ45_1_R_DN"
				( objectStatus "@baseboard_fab2_lib.baseboard_fab2(sch_1):nic_mdi_sprv_rj45_1_r_dn" )
			)
			( signal "NIC_MDI_SPRV_RJ45_1_R_DP"
				( objectStatus "@baseboard_fab2_lib.baseboard_fab2(sch_1):nic_mdi_sprv_rj45_1_r_dp" )
			)
			( signal "NIC_MDI_SPRV_RJ45_2_R_DN"
				( objectStatus "@baseboard_fab2_lib.baseboard_fab2(sch_1):nic_mdi_sprv_rj45_2_r_dn" )
			)
			( signal "NIC_MDI_SPRV_RJ45_2_R_DP"
				( objectStatus "@baseboard_fab2_lib.baseboard_fab2(sch_1):nic_mdi_sprv_rj45_2_r_dp" )
			)
			( signal "NIC_MDI_SPRV_RJ45_3_R_DN"
				( objectStatus "@baseboard_fab2_lib.baseboard_fab2(sch_1):nic_mdi_sprv_rj45_3_r_dn" )
			)
			( signal "NIC_MDI_SPRV_RJ45_3_R_DP"
				( objectStatus "@baseboard_fab2_lib.baseboard_fab2(sch_1):nic_mdi_sprv_rj45_3_r_dp" )
			)
			( signal "FM_ALL_WAKE_N"
				( objectStatus "@baseboard_fab2_lib.baseboard_fab2(sch_1):fm_all_wake_n" )
			)
			( signal "FM_PE_BMC_WAKE_N"
				( objectStatus "@baseboard_fab2_lib.baseboard_fab2(sch_1):fm_pe_bmc_wake_n" )
			)
			( signal "FM_PE_M2_WAKE_N"
				( objectStatus "@baseboard_fab2_lib.baseboard_fab2(sch_1):fm_pe_m2_wake_n" )
			)
			( signal "FM_PE_OCP_WAKE_N"
				( objectStatus "@baseboard_fab2_lib.baseboard_fab2(sch_1):fm_pe_ocp_wake_n" )
			)
			( signal "IRQ_LVC3_WAKE_R_N"
				( objectStatus "@baseboard_fab2_lib.baseboard_fab2(sch_1):irq_lvc3_wake_r_n" )
			)
			( signal "PU_TRI_STATE_EN"
				( objectStatus "@baseboard_fab2_lib.baseboard_fab2(sch_1):pu_tri_state_en" )
			)
			( signal "JTAG_BMC_TCK"
				( objectStatus "@baseboard_fab2_lib.baseboard_fab2(sch_1):jtag_bmc_tck" )
			)
			( signal "TP_VGAVS_GPIOJ5"
				( objectStatus "@baseboard_fab2_lib.baseboard_fab2(sch_1):tp_vgavs_gpioj5" )
			)
			( signal "JTAG_BMC_TDI"
				( objectStatus "@baseboard_fab2_lib.baseboard_fab2(sch_1):jtag_bmc_tdi" )
			)
			( signal "TP_VGAHS_GPIOJ4"
				( objectStatus "@baseboard_fab2_lib.baseboard_fab2(sch_1):tp_vgahs_gpioj4" )
			)
			( signal "JTAG_BMC_TDO"
				( objectStatus "@baseboard_fab2_lib.baseboard_fab2(sch_1):jtag_bmc_tdo" )
			)
			( signal "TP_DDCDAT_GPIOJ7"
				( objectStatus "@baseboard_fab2_lib.baseboard_fab2(sch_1):tp_ddcdat_gpioj7" )
			)
			( signal "JTAG_BMC_TMS"
				( objectStatus "@baseboard_fab2_lib.baseboard_fab2(sch_1):jtag_bmc_tms" )
			)
			( signal "TP_DDCCLK_GPIOJ6"
				( objectStatus "@baseboard_fab2_lib.baseboard_fab2(sch_1):tp_ddcclk_gpioj6" )
			)
			( signal "JTAG_BMC_TRST_N"
				( objectStatus "@baseboard_fab2_lib.baseboard_fab2(sch_1):jtag_bmc_trst_n" )
			)
			( signal "TP_DACR"
				( objectStatus "@baseboard_fab2_lib.baseboard_fab2(sch_1):tp_dacr" )
			)
			( signal "SGPIO_BMC_CLK"
				( objectStatus "@baseboard_fab2_lib.baseboard_fab2(sch_1):sgpio_bmc_clk" )
			)
			( signal "SGPIO_BMC_DIN"
				( objectStatus "@baseboard_fab2_lib.baseboard_fab2(sch_1):sgpio_bmc_din" )
			)
			( signal "SGPIO_BMC_DOUT"
				( objectStatus "@baseboard_fab2_lib.baseboard_fab2(sch_1):sgpio_bmc_dout" )
			)
			( signal "SGPIO_BMC_LD_N"
				( objectStatus "@baseboard_fab2_lib.baseboard_fab2(sch_1):sgpio_bmc_ld_n" )
			)
			( signal "SMB_BMC_PMBUS_STBY_LVC3_SCL_R"
				( objectStatus "@baseboard_fab2_lib.baseboard_fab2(sch_1):smb_bmc_pmbus_stby_lvc3_scl_r" )
			)
			( signal "SMB_BMC_PMBUS_STBY_LVC3_SDA_R"
				( objectStatus "@baseboard_fab2_lib.baseboard_fab2(sch_1):smb_bmc_pmbus_stby_lvc3_sda_r" )
			)
			( signal "SMB_HOST_STBY_LVC3_SCL_R"
				( objectStatus "@baseboard_fab2_lib.baseboard_fab2(sch_1):smb_host_stby_lvc3_scl_r" )
			)
			( signal "SMB_HOST_STBY_LVC3_SDA_R"
				( objectStatus "@baseboard_fab2_lib.baseboard_fab2(sch_1):smb_host_stby_lvc3_sda_r" )
			)
			( signal "SMB_LAN_STBY_LVC3_SCL_R"
				( objectStatus "@baseboard_fab2_lib.baseboard_fab2(sch_1):smb_lan_stby_lvc3_scl_r" )
			)
			( signal "SMB_LAN_STBY_LVC3_SDA_R"
				( objectStatus "@baseboard_fab2_lib.baseboard_fab2(sch_1):smb_lan_stby_lvc3_sda_r" )
			)
			( signal "SMB_OCP_FRU_STBY_LVC3_SCL_R"
				( objectStatus "@baseboard_fab2_lib.baseboard_fab2(sch_1):smb_ocp_fru_stby_lvc3_scl_r" )
			)
			( signal "SMB_OCP_FRU_STBY_LVC3_SDA_R"
				( objectStatus "@baseboard_fab2_lib.baseboard_fab2(sch_1):smb_ocp_fru_stby_lvc3_sda_r" )
			)
			( signal "SMB_OCP_LAN_STBY_LVC3_SCL_R"
				( objectStatus "@baseboard_fab2_lib.baseboard_fab2(sch_1):smb_ocp_lan_stby_lvc3_scl_r" )
			)
			( signal "SMB_OCP_LAN_STBY_LVC3_SDA_R"
				( objectStatus "@baseboard_fab2_lib.baseboard_fab2(sch_1):smb_ocp_lan_stby_lvc3_sda_r" )
			)
			( signal "SMB_SENSOR_BMC_STBY_LVC3_SCL"
				( objectStatus "@baseboard_fab2_lib.baseboard_fab2(sch_1):smb_sensor_bmc_stby_lvc3_scl" )
			)
			( signal "SMB_SENSOR_BMC_STBY_LVC3_SDA"
				( objectStatus "@baseboard_fab2_lib.baseboard_fab2(sch_1):smb_sensor_bmc_stby_lvc3_sda" )
			)
			( signal "SMB_SLOTX24_STBY_LVC3_SCL_R"
				( objectStatus "@baseboard_fab2_lib.baseboard_fab2(sch_1):smb_slotx24_stby_lvc3_scl_r" )
			)
			( signal "SMB_SLOTX24_STBY_LVC3_SDA_R"
				( objectStatus "@baseboard_fab2_lib.baseboard_fab2(sch_1):smb_slotx24_stby_lvc3_sda_r" )
			)
			( signal "SMB_SMLINK0_STBY_LVC3_SCL_R"
				( objectStatus "@baseboard_fab2_lib.baseboard_fab2(sch_1):smb_smlink0_stby_lvc3_scl_r" )
			)
			( signal "SMB_SMLINK0_STBY_LVC3_SDA_R"
				( objectStatus "@baseboard_fab2_lib.baseboard_fab2(sch_1):smb_smlink0_stby_lvc3_sda_r" )
			)
			( signal "SMB_VR_STBY_LVC3_SCL_R"
				( objectStatus "@baseboard_fab2_lib.baseboard_fab2(sch_1):smb_vr_stby_lvc3_scl_r" )
			)
			( signal "SMB_VR_STBY_LVC3_SDA_R"
				( objectStatus "@baseboard_fab2_lib.baseboard_fab2(sch_1):smb_vr_stby_lvc3_sda_r" )
			)
			( signal "SPI_BMC_CLK"
				( objectStatus "@baseboard_fab2_lib.baseboard_fab2(sch_1):spi_bmc_clk" )
			)
			( signal "SPI_BMC_CS0_N"
				( objectStatus "@baseboard_fab2_lib.baseboard_fab2(sch_1):spi_bmc_cs0_n" )
			)
			( signal "SPI_BMC_DI"
				( objectStatus "@baseboard_fab2_lib.baseboard_fab2(sch_1):spi_bmc_di" )
			)
			( signal "SPI_BMC_DO"
				( objectStatus "@baseboard_fab2_lib.baseboard_fab2(sch_1):spi_bmc_do" )
			)
			( signal "FM_BMC_ONCTL_N"
				( objectStatus "@baseboard_fab2_lib.baseboard_fab2(sch_1):fm_bmc_onctl_n" )
			)
			( signal "FM_BMC_PWRBTN_OUT_N"
				( objectStatus "@baseboard_fab2_lib.baseboard_fab2(sch_1):fm_bmc_pwrbtn_out_n" )
			)
			( signal "H_CPU0_MEMABC_MEMHOT_LVT3_BMC_N"
				( objectStatus "@baseboard_fab2_lib.baseboard_fab2(sch_1):h_cpu0_memabc_memhot_lvt3_bmc_n" )
			)
			( signal "H_CPU0_MEMDEF_MEMHOT_LVT3_BMC_N"
				( objectStatus "@baseboard_fab2_lib.baseboard_fab2(sch_1):h_cpu0_memdef_memhot_lvt3_bmc_n" )
			)
			( signal "FM_CPU1_FIVR_FAULT_LVT3_R_N"
				( objectStatus "@baseboard_fab2_lib.baseboard_fab2(sch_1):fm_cpu1_fivr_fault_lvt3_r_n" )
			)
			( signal "H_CPU1_MEMGHJ_MEMHOT_LVT3_BMC_N"
				( objectStatus "@baseboard_fab2_lib.baseboard_fab2(sch_1):h_cpu1_memghj_memhot_lvt3_bmc_n" )
			)
			( signal "FM_CPU0_FIVR_FAULT_LVT3_R_N"
				( objectStatus "@baseboard_fab2_lib.baseboard_fab2(sch_1):fm_cpu0_fivr_fault_lvt3_r_n" )
			)
			( signal "H_CPU1_MEMKLM_MEMHOT_LVT3_BMC_N"
				( objectStatus "@baseboard_fab2_lib.baseboard_fab2(sch_1):h_cpu1_memklm_memhot_lvt3_bmc_n" )
			)
			( signal "P2E_SSB_BMC_RX_DN"
				( objectStatus "@baseboard_fab2_lib.baseboard_fab2(sch_1):p2e_ssb_bmc_rx_dn" )
			)
			( signal "P2E_SSB_BMC_RX_DP"
				( objectStatus "@baseboard_fab2_lib.baseboard_fab2(sch_1):p2e_ssb_bmc_rx_dp" )
			)
			( signal "PD_PEREXT"
				( objectStatus "@baseboard_fab2_lib.baseboard_fab2(sch_1):pd_perext" )
			)
			( signal "CLK_24M_BMC_CLKIN_R"
				( objectStatus "@baseboard_fab2_lib.baseboard_fab2(sch_1):clk_24m_bmc_clkin_r" )
			)
			( signal "PECI_BMC"
				( objectStatus "@baseboard_fab2_lib.baseboard_fab2(sch_1):peci_bmc" )
			)
			( signal "PD_SP_ENTEST"
				( objectStatus "@baseboard_fab2_lib.baseboard_fab2(sch_1):pd_sp_entest" )
			)
			( signal "CLK_24M_25M_BMC_CLKIN"
				( objectStatus "@baseboard_fab2_lib.baseboard_fab2(sch_1):clk_24m_25m_bmc_clkin" )
			)
			( signal "RST_BMC_SYSRST_BTN_OUT_N"
				( objectStatus "@baseboard_fab2_lib.baseboard_fab2(sch_1):rst_bmc_sysrst_btn_out_n" )
			)
			( signal "SP1_BMC_HOST_UART_RX"
				( objectStatus "@baseboard_fab2_lib.baseboard_fab2(sch_1):sp1_bmc_host_uart_rx" )
			)
			( signal "SP1_BMC_HOST_UART_TX"
				( objectStatus "@baseboard_fab2_lib.baseboard_fab2(sch_1):sp1_bmc_host_uart_tx" )
			)
			( signal "UART_BMC_RXD5"
				( objectStatus "@baseboard_fab2_lib.baseboard_fab2(sch_1):uart_bmc_rxd5" )
			)
			( signal "UART_BMC_TXD5"
				( objectStatus "@baseboard_fab2_lib.baseboard_fab2(sch_1):uart_bmc_txd5" )
			)
			( signal "TP_TPM_SPI_6"
				( objectStatus "@baseboard_fab2_lib.baseboard_fab2(sch_1):tp_tpm_spi_6" )
			)
			( signal "TP_TPM_SPI_5"
				( objectStatus "@baseboard_fab2_lib.baseboard_fab2(sch_1):tp_tpm_spi_5" )
			)
			( signal "TP_TPM_SPI_4"
				( objectStatus "@baseboard_fab2_lib.baseboard_fab2(sch_1):tp_tpm_spi_4" )
			)
			( signal "TP_TPM_SPI_3"
				( objectStatus "@baseboard_fab2_lib.baseboard_fab2(sch_1):tp_tpm_spi_3" )
			)
			( signal "TP_TPM_SPI_2"
				( objectStatus "@baseboard_fab2_lib.baseboard_fab2(sch_1):tp_tpm_spi_2" )
			)
			( signal "TP_TPM_SPI_1"
				( objectStatus "@baseboard_fab2_lib.baseboard_fab2(sch_1):tp_tpm_spi_1" )
			)
			( signal "TP_TPM_SPI_0"
				( objectStatus "@baseboard_fab2_lib.baseboard_fab2(sch_1):tp_tpm_spi_0" )
			)
			( signal "SPI_TPM_BMC_DI_R_"
				( objectStatus "@baseboard_fab2_lib.baseboard_fab2(sch_1):\spi_tpm_bmc_di_r_\" )
			)
			( signal "PU_TPM_SPI_FLASH_RESET_2_N"
				( objectStatus "@baseboard_fab2_lib.baseboard_fab2(sch_1):pu_tpm_spi_flash_reset_2_n" )
			)
			( signal "PU_TPM_SPI_BMC_WP_N"
				( objectStatus "@baseboard_fab2_lib.baseboard_fab2(sch_1):pu_tpm_spi_bmc_wp_n" )
			)
			( signal "P3V3_USB2A_ALG"
				( objectStatus "@baseboard_fab2_lib.baseboard_fab2(sch_1):p3v3_usb2a_alg" )
			)
			( signal "PU_TPM_SPI_BMC_HOLD_N"
				( objectStatus "@baseboard_fab2_lib.baseboard_fab2(sch_1):pu_tpm_spi_bmc_hold_n" )
			)
			( signal "SPI_BMC_BT_CLK"
				( objectStatus "@baseboard_fab2_lib.baseboard_fab2(sch_1):spi_bmc_bt_clk" )
			)
			( signal "SPI_BMC_BT_CLK_R"
				( objectStatus "@baseboard_fab2_lib.baseboard_fab2(sch_1):spi_bmc_bt_clk_r" )
			)
			( signal "SPI_BMC_BT_CS_N"
				( objectStatus "@baseboard_fab2_lib.baseboard_fab2(sch_1):spi_bmc_bt_cs_n" )
			)
			( signal "SPI_BMC_BT_CS_R_N"
				( objectStatus "@baseboard_fab2_lib.baseboard_fab2(sch_1):spi_bmc_bt_cs_r_n" )
			)
			( signal "SPI_BMC_BT_DI"
				( objectStatus "@baseboard_fab2_lib.baseboard_fab2(sch_1):spi_bmc_bt_di" )
			)
			( signal "SPI_BMC_BT_DO"
				( objectStatus "@baseboard_fab2_lib.baseboard_fab2(sch_1):spi_bmc_bt_do" )
			)
			( signal "SPI_BMC_BT_DO_R"
				( objectStatus "@baseboard_fab2_lib.baseboard_fab2(sch_1):spi_bmc_bt_do_r" )
			)
			( signal "A_P12V_STBY_SCALED"
				( attribute "VOLTAGE" "+2V"
					( Units "uVoltage" "V" 1.000000)
					( Status sAliasFlattened )
					( Origin gFrontEnd )
				)
				( objectStatus "@baseboard_fab2_lib.baseboard_fab2(sch_1):a_p12v_stby_scaled" )
			)
			( signal "A_P1V05_STBY_PCH_SENSOR"
				( attribute "VOLTAGE" "+1.2V"
					( Units "uVoltage" "V" 1.000000)
					( Status sAliasFlattened )
					( Origin gFrontEnd )
				)
				( objectStatus "@baseboard_fab2_lib.baseboard_fab2(sch_1):a_p1v05_stby_pch_sensor" )
			)
			( signal "A_P3V3_SCALED"
				( attribute "VOLTAGE" "+2V"
					( Units "uVoltage" "V" 1.000000)
					( Status sAliasFlattened )
					( Origin gFrontEnd )
				)
				( objectStatus "@baseboard_fab2_lib.baseboard_fab2(sch_1):a_p3v3_scaled" )
			)
			( signal "A_P3V3_STBY_SCALED"
				( attribute "VOLTAGE" "+1.8V"
					( Units "uVoltage" "V" 1.000000)
					( Status sAliasFlattened )
					( Origin gFrontEnd )
				)
				( objectStatus "@baseboard_fab2_lib.baseboard_fab2(sch_1):a_p3v3_stby_scaled" )
			)
			( signal "A_P3V_BAT_SCALED"
				( attribute "VOLTAGE" "+1V"
					( Units "uVoltage" "V" 1.000000)
					( Status sAliasFlattened )
					( Origin gFrontEnd )
				)
				( objectStatus "@baseboard_fab2_lib.baseboard_fab2(sch_1):a_p3v_bat_scaled" )
			)
			( signal "A_P5V_SCALED"
				( attribute "VOLTAGE" "+2V"
					( Units "uVoltage" "V" 1.000000)
					( Status sAliasFlattened )
					( Origin gFrontEnd )
				)
				( objectStatus "@baseboard_fab2_lib.baseboard_fab2(sch_1):a_p5v_scaled" )
			)
			( signal "A_P5V_STBY_SCALED"
				( attribute "VOLTAGE" "+2V"
					( Units "uVoltage" "V" 1.000000)
					( Status sAliasFlattened )
					( Origin gFrontEnd )
				)
				( objectStatus "@baseboard_fab2_lib.baseboard_fab2(sch_1):a_p5v_stby_scaled" )
			)
			( signal "A_PVNN_STBY_PCH_SENSOR"
				( attribute "VOLTAGE" "+1.2V"
					( Units "uVoltage" "V" 1.000000)
					( Status sAliasFlattened )
					( Origin gFrontEnd )
				)
				( objectStatus "@baseboard_fab2_lib.baseboard_fab2(sch_1):a_pvnn_stby_pch_sensor" )
			)
			( signal "FM_BIOS_SPI_BMC_CTRL"
				( objectStatus "@baseboard_fab2_lib.baseboard_fab2(sch_1):fm_bios_spi_bmc_ctrl" )
			)
			( signal "FM_HEARTBEAT_LED"
				( objectStatus "@baseboard_fab2_lib.baseboard_fab2(sch_1):fm_heartbeat_led" )
			)
			( signal "FM_HEARTBEAT_LED_A"
				( objectStatus "@baseboard_fab2_lib.baseboard_fab2(sch_1):fm_heartbeat_led_a" )
			)
			( signal "FM_HEARTBEAT_LED_K"
				( objectStatus "@baseboard_fab2_lib.baseboard_fab2(sch_1):fm_heartbeat_led_k" )
			)
			( signal "P3V3_STBY_BMC_ADCVREFN"
				( attribute "VOLTAGE" "+3.3V"
					( Units "uVoltage" "V" 1.000000)
					( Status sAliasFlattened )
					( Origin gFrontEnd )
				)
				( objectStatus "@baseboard_fab2_lib.baseboard_fab2(sch_1):p3v3_stby_bmc_adcvrefn" )
			)
			( signal "P3V3_STBY_BMC_ADCVREFP"
				( attribute "VOLTAGE" "+3.3V"
					( Units "uVoltage" "V" 1.000000)
					( Status sAliasFlattened )
					( Origin gFrontEnd )
				)
				( objectStatus "@baseboard_fab2_lib.baseboard_fab2(sch_1):p3v3_stby_bmc_adcvrefp" )
			)
			( signal "PD_ADCREXT"
				( objectStatus "@baseboard_fab2_lib.baseboard_fab2(sch_1):pd_adcrext" )
			)
			( signal "RMII_BMC_OCP_CRSDV"
				( objectStatus "@baseboard_fab2_lib.baseboard_fab2(sch_1):rmii_bmc_ocp_crsdv" )
			)
			( signal "RMII_BMC_OCP_RXD0"
				( objectStatus "@baseboard_fab2_lib.baseboard_fab2(sch_1):rmii_bmc_ocp_rxd0" )
			)
			( signal "RMII_BMC_OCP_RXD1"
				( objectStatus "@baseboard_fab2_lib.baseboard_fab2(sch_1):rmii_bmc_ocp_rxd1" )
			)
			( signal "RMII_BMC_OCP_RXER"
				( objectStatus "@baseboard_fab2_lib.baseboard_fab2(sch_1):rmii_bmc_ocp_rxer" )
			)
			( signal "RMII_BMC_OCP_TXD0"
				( objectStatus "@baseboard_fab2_lib.baseboard_fab2(sch_1):rmii_bmc_ocp_txd0" )
			)
			( signal "RMII_BMC_OCP_TXD0_R"
				( objectStatus "@baseboard_fab2_lib.baseboard_fab2(sch_1):rmii_bmc_ocp_txd0_r" )
			)
			( signal "RMII_BMC_OCP_TXD1"
				( objectStatus "@baseboard_fab2_lib.baseboard_fab2(sch_1):rmii_bmc_ocp_txd1" )
			)
			( signal "RMII_BMC_OCP_TXD1_R"
				( objectStatus "@baseboard_fab2_lib.baseboard_fab2(sch_1):rmii_bmc_ocp_txd1_r" )
			)
			( signal "RMII_BMC_OCP_TXEN"
				( objectStatus "@baseboard_fab2_lib.baseboard_fab2(sch_1):rmii_bmc_ocp_txen" )
			)
			( signal "RMII_BMC_OCP_TXEN_R"
				( objectStatus "@baseboard_fab2_lib.baseboard_fab2(sch_1):rmii_bmc_ocp_txen_r" )
			)
			( signal "RMII_BMC_PCH_SPRNGVLLE_TXD0_R"
				( objectStatus "@baseboard_fab2_lib.baseboard_fab2(sch_1):rmii_bmc_pch_sprngvlle_txd0_r" )
			)
			( signal "RMII_BMC_PCH_SPRNGVLLE_TXD1_R"
				( objectStatus "@baseboard_fab2_lib.baseboard_fab2(sch_1):rmii_bmc_pch_sprngvlle_txd1_r" )
			)
			( signal "RMII_BMC_SPRNGVLLE_TXEN_R"
				( objectStatus "@baseboard_fab2_lib.baseboard_fab2(sch_1):rmii_bmc_sprngvlle_txen_r" )
			)
			( signal "TP_RGMII1TXD2_GPIOT4"
				( objectStatus "@baseboard_fab2_lib.baseboard_fab2(sch_1):tp_rgmii1txd2_gpiot4" )
			)
			( signal "TP_RGMII1TXD3_GPIOT5"
				( objectStatus "@baseboard_fab2_lib.baseboard_fab2(sch_1):tp_rgmii1txd3_gpiot5" )
			)
			( signal "TP_RGMII2TXD2_GPIOT4"
				( objectStatus "@baseboard_fab2_lib.baseboard_fab2(sch_1):tp_rgmii2txd2_gpiot4" )
			)
			( signal "TP_RGMII2TXD3_GPIOT5"
				( objectStatus "@baseboard_fab2_lib.baseboard_fab2(sch_1):tp_rgmii2txd3_gpiot5" )
			)
			( signal "VCC_DACAV3V3"
				( objectStatus "@baseboard_fab2_lib.baseboard_fab2(sch_1):vcc_dacav3v3" )
			)
			( signal "RST_BMC_DDR3_BUF_IN_N"
				( objectStatus "@baseboard_fab2_lib.baseboard_fab2(sch_1):rst_bmc_ddr3_buf_in_n" )
			)
			( signal "VCC_ADCAV3V3"
				( attribute "VOLTAGE" "+3.3V"
					( Units "uVoltage" "V" 1.000000)
					( Status sAliasFlattened )
					( Origin gFrontEnd )
				)
				( objectStatus "@baseboard_fab2_lib.baseboard_fab2(sch_1):vcc_adcav3v3" )
			)
			( signal "RST_BMC_DDR3_R_N"
				( objectStatus "@baseboard_fab2_lib.baseboard_fab2(sch_1):rst_bmc_ddr3_r_n" )
			)
			( signal "H_CPU0_ABC_MEMHOT_LVT3_R_N"
				( objectStatus "@baseboard_fab2_lib.baseboard_fab2(sch_1):h_cpu0_abc_memhot_lvt3_r_n" )
			)
			( signal "H_CPU0_DEF_MEMHOT_LVT3_R_N"
				( objectStatus "@baseboard_fab2_lib.baseboard_fab2(sch_1):h_cpu0_def_memhot_lvt3_r_n" )
			)
			( signal "H_CPU0_MEMABC_MEMHOT_G_PCH_N"
				( objectStatus "@baseboard_fab2_lib.baseboard_fab2(sch_1):h_cpu0_memabc_memhot_g_pch_n" )
			)
			( signal "H_CPU0_MEMABC_MEMHOT_G_R_N"
				( objectStatus "@baseboard_fab2_lib.baseboard_fab2(sch_1):h_cpu0_memabc_memhot_g_r_n" )
			)
			( signal "H_CPU0_MEMABC_MEMHOT_LVT3_K_N"
				( objectStatus "@baseboard_fab2_lib.baseboard_fab2(sch_1):h_cpu0_memabc_memhot_lvt3_k_n" )
			)
			( signal "H_CPU0_MEMABC_MEMHOT_LVT3_N"
				( objectStatus "@baseboard_fab2_lib.baseboard_fab2(sch_1):h_cpu0_memabc_memhot_lvt3_n" )
			)
			( signal "H_CPU0_MEMDEF_MEMHOT_G_PCH_N"
				( objectStatus "@baseboard_fab2_lib.baseboard_fab2(sch_1):h_cpu0_memdef_memhot_g_pch_n" )
			)
			( signal "H_CPU0_MEMDEF_MEMHOT_G_R_N"
				( objectStatus "@baseboard_fab2_lib.baseboard_fab2(sch_1):h_cpu0_memdef_memhot_g_r_n" )
			)
			( signal "H_CPU0_MEMDEF_MEMHOT_LVT3_K_N"
				( objectStatus "@baseboard_fab2_lib.baseboard_fab2(sch_1):h_cpu0_memdef_memhot_lvt3_k_n" )
			)
			( signal "H_CPU0_MEMDEF_MEMHOT_LVT3_N"
				( objectStatus "@baseboard_fab2_lib.baseboard_fab2(sch_1):h_cpu0_memdef_memhot_lvt3_n" )
			)
			( signal "H_CPU1_GHJ_MEMHOT_LVT3_R_N"
				( objectStatus "@baseboard_fab2_lib.baseboard_fab2(sch_1):h_cpu1_ghj_memhot_lvt3_r_n" )
			)
			( signal "H_CPU1_KLM_MEMHOT_LVT3_R_N"
				( objectStatus "@baseboard_fab2_lib.baseboard_fab2(sch_1):h_cpu1_klm_memhot_lvt3_r_n" )
			)
			( signal "H_CPU1_MEMGHJ_MEMHOT_G_PCH_N"
				( objectStatus "@baseboard_fab2_lib.baseboard_fab2(sch_1):h_cpu1_memghj_memhot_g_pch_n" )
			)
			( signal "H_CPU1_MEMGHJ_MEMHOT_G_R_N"
				( objectStatus "@baseboard_fab2_lib.baseboard_fab2(sch_1):h_cpu1_memghj_memhot_g_r_n" )
			)
			( signal "H_CPU1_MEMGHJ_MEMHOT_LVT3_K_N"
				( objectStatus "@baseboard_fab2_lib.baseboard_fab2(sch_1):h_cpu1_memghj_memhot_lvt3_k_n" )
			)
			( signal "H_CPU1_MEMGHJ_MEMHOT_LVT3_N"
				( objectStatus "@baseboard_fab2_lib.baseboard_fab2(sch_1):h_cpu1_memghj_memhot_lvt3_n" )
			)
			( signal "H_CPU1_MEMKLM_MEMHOT_G_PCH_N"
				( objectStatus "@baseboard_fab2_lib.baseboard_fab2(sch_1):h_cpu1_memklm_memhot_g_pch_n" )
			)
			( signal "H_CPU1_MEMKLM_MEMHOT_G_R_N"
				( objectStatus "@baseboard_fab2_lib.baseboard_fab2(sch_1):h_cpu1_memklm_memhot_g_r_n" )
			)
			( signal "H_CPU1_MEMKLM_MEMHOT_LVT3_K_N"
				( objectStatus "@baseboard_fab2_lib.baseboard_fab2(sch_1):h_cpu1_memklm_memhot_lvt3_k_n" )
			)
			( signal "H_CPU1_MEMKLM_MEMHOT_LVT3_N"
				( objectStatus "@baseboard_fab2_lib.baseboard_fab2(sch_1):h_cpu1_memklm_memhot_lvt3_n" )
			)
			( signal "P0V7_GTL2014_2"
				( attribute "VOLTAGE" "+0.7"
					( Units "uVoltage" "V" 1.000000)
					( Status sAliasFlattened )
					( Origin gFrontEnd )
				)
				( objectStatus "@baseboard_fab2_lib.baseboard_fab2(sch_1):p0v7_gtl2014_2" )
			)
			( signal "PD_DIR_2"
				( objectStatus "@baseboard_fab2_lib.baseboard_fab2(sch_1):pd_dir_2" )
			)
			( signal "PU_BIOS_SPI_HOLD0_N"
				( objectStatus "@baseboard_fab2_lib.baseboard_fab2(sch_1):pu_bios_spi_hold0_n" )
			)
			( signal "PU_BIOS_SPI_HOLD1_N"
				( objectStatus "@baseboard_fab2_lib.baseboard_fab2(sch_1):pu_bios_spi_hold1_n" )
			)
			( signal "PU_BIOS_SPI_WP0_N"
				( objectStatus "@baseboard_fab2_lib.baseboard_fab2(sch_1):pu_bios_spi_wp0_n" )
			)
			( signal "PU_BIOS_SPI_WP1_N"
				( objectStatus "@baseboard_fab2_lib.baseboard_fab2(sch_1):pu_bios_spi_wp1_n" )
			)
			( signal "PU_SPI0_RST"
				( objectStatus "@baseboard_fab2_lib.baseboard_fab2(sch_1):pu_spi0_rst" )
			)
			( signal "PU_SPI1_RST"
				( objectStatus "@baseboard_fab2_lib.baseboard_fab2(sch_1):pu_spi1_rst" )
			)
			( signal "SPI_BIOS_SOCKET_IO2"
				( objectStatus "@baseboard_fab2_lib.baseboard_fab2(sch_1):spi_bios_socket_io2" )
			)
			( signal "SPI_BIOS_SOCKET_IO3"
				( objectStatus "@baseboard_fab2_lib.baseboard_fab2(sch_1):spi_bios_socket_io3" )
			)
			( signal "SPI_CLK_R0"
				( objectStatus "@baseboard_fab2_lib.baseboard_fab2(sch_1):spi_clk_r0" )
			)
			( signal "SPI_CLK_R1"
				( objectStatus "@baseboard_fab2_lib.baseboard_fab2(sch_1):spi_clk_r1" )
			)
			( signal "SPI_CS0_PRIMARY_R_N"
				( objectStatus "@baseboard_fab2_lib.baseboard_fab2(sch_1):spi_cs0_primary_r_n" )
			)
			( signal "SPI_CS0_SECONDARY_R_N"
				( objectStatus "@baseboard_fab2_lib.baseboard_fab2(sch_1):spi_cs0_secondary_r_n" )
			)
			( signal "SPI_MISO_R0"
				( objectStatus "@baseboard_fab2_lib.baseboard_fab2(sch_1):spi_miso_r0" )
			)
			( signal "SPI_MISO_R1"
				( objectStatus "@baseboard_fab2_lib.baseboard_fab2(sch_1):spi_miso_r1" )
			)
			( signal "SPI_SWITCH_CLK"
				( objectStatus "@baseboard_fab2_lib.baseboard_fab2(sch_1):spi_switch_clk" )
			)
			( signal "SPI_SWITCH_MISO"
				( objectStatus "@baseboard_fab2_lib.baseboard_fab2(sch_1):spi_switch_miso" )
			)
			( signal "SPI_SWITCH_MOSI"
				( objectStatus "@baseboard_fab2_lib.baseboard_fab2(sch_1):spi_switch_mosi" )
			)
			( signal "SPI_SWITCH_MOSI_R0"
				( objectStatus "@baseboard_fab2_lib.baseboard_fab2(sch_1):spi_switch_mosi_r0" )
			)
			( signal "SPI_SWITCH_MOSI_R1"
				( objectStatus "@baseboard_fab2_lib.baseboard_fab2(sch_1):spi_switch_mosi_r1" )
			)
			( signal "TP_SPI_0_0"
				( objectStatus "@baseboard_fab2_lib.baseboard_fab2(sch_1):tp_spi_0_0" )
			)
			( signal "TP_SPI_0_1"
				( objectStatus "@baseboard_fab2_lib.baseboard_fab2(sch_1):tp_spi_0_1" )
			)
			( signal "TP_SPI_0_2"
				( objectStatus "@baseboard_fab2_lib.baseboard_fab2(sch_1):tp_spi_0_2" )
			)
			( signal "TP_SPI_0_3"
				( objectStatus "@baseboard_fab2_lib.baseboard_fab2(sch_1):tp_spi_0_3" )
			)
			( signal "TP_SPI_0_4"
				( objectStatus "@baseboard_fab2_lib.baseboard_fab2(sch_1):tp_spi_0_4" )
			)
			( signal "TP_SPI_0_5"
				( objectStatus "@baseboard_fab2_lib.baseboard_fab2(sch_1):tp_spi_0_5" )
			)
			( signal "TP_SPI_0_6"
				( objectStatus "@baseboard_fab2_lib.baseboard_fab2(sch_1):tp_spi_0_6" )
			)
			( signal "TP_SPI_1_0"
				( objectStatus "@baseboard_fab2_lib.baseboard_fab2(sch_1):tp_spi_1_0" )
			)
			( signal "TP_SPI_1_1"
				( objectStatus "@baseboard_fab2_lib.baseboard_fab2(sch_1):tp_spi_1_1" )
			)
			( signal "TP_SPI_1_2"
				( objectStatus "@baseboard_fab2_lib.baseboard_fab2(sch_1):tp_spi_1_2" )
			)
			( signal "TP_SPI_1_3"
				( objectStatus "@baseboard_fab2_lib.baseboard_fab2(sch_1):tp_spi_1_3" )
			)
			( signal "TP_SPI_1_4"
				( objectStatus "@baseboard_fab2_lib.baseboard_fab2(sch_1):tp_spi_1_4" )
			)
			( signal "TP_SPI_1_5"
				( objectStatus "@baseboard_fab2_lib.baseboard_fab2(sch_1):tp_spi_1_5" )
			)
			( signal "TP_SPI_1_6"
				( objectStatus "@baseboard_fab2_lib.baseboard_fab2(sch_1):tp_spi_1_6" )
			)
			( signal "FM_DUAL_BIOS_SEL_N"
				( objectStatus "@baseboard_fab2_lib.baseboard_fab2(sch_1):fm_dual_bios_sel_n" )
			)
			( signal "SPI_CS0_PRIMARY_N"
				( objectStatus "@baseboard_fab2_lib.baseboard_fab2(sch_1):spi_cs0_primary_n" )
			)
			( signal "SPI_CS0_SECONDARY_N"
				( objectStatus "@baseboard_fab2_lib.baseboard_fab2(sch_1):spi_cs0_secondary_n" )
			)
			( signal "SPI_PCH_IO2_R1"
				( objectStatus "@baseboard_fab2_lib.baseboard_fab2(sch_1):spi_pch_io2_r1" )
			)
			( signal "SPI_PCH_IO3_R1"
				( objectStatus "@baseboard_fab2_lib.baseboard_fab2(sch_1):spi_pch_io3_r1" )
			)
			( signal "SPI_PCH_MISO_R"
				( objectStatus "@baseboard_fab2_lib.baseboard_fab2(sch_1):spi_pch_miso_r" )
			)
			( signal "SPI_SWITCH_CS0_N"
				( objectStatus "@baseboard_fab2_lib.baseboard_fab2(sch_1):spi_switch_cs0_n" )
			)
			( signal "TP_SPI_SWITCH1_10"
				( objectStatus "@baseboard_fab2_lib.baseboard_fab2(sch_1):tp_spi_switch1_10" )
			)
			( signal "TP_SPI_SWITCH1_11"
				( objectStatus "@baseboard_fab2_lib.baseboard_fab2(sch_1):tp_spi_switch1_11" )
			)
			( signal "TP_SPI_SWITCH1_12"
				( objectStatus "@baseboard_fab2_lib.baseboard_fab2(sch_1):tp_spi_switch1_12" )
			)
			( signal "TP_SPI_SWITCH1_13"
				( objectStatus "@baseboard_fab2_lib.baseboard_fab2(sch_1):tp_spi_switch1_13" )
			)
			( signal "TP_SPI_SWITCH1_14"
				( objectStatus "@baseboard_fab2_lib.baseboard_fab2(sch_1):tp_spi_switch1_14" )
			)
			( signal "TP_SPI_SWITCH1_3"
				( objectStatus "@baseboard_fab2_lib.baseboard_fab2(sch_1):tp_spi_switch1_3" )
			)
			( signal "TP_SPI_SWITCH1_6"
				( objectStatus "@baseboard_fab2_lib.baseboard_fab2(sch_1):tp_spi_switch1_6" )
			)
			( signal "TP_SPI_SWITCH1_9"
				( objectStatus "@baseboard_fab2_lib.baseboard_fab2(sch_1):tp_spi_switch1_9" )
			)
			( signal "FM_CPLD_DBG_PWR_EN"
				( objectStatus "@baseboard_fab2_lib.baseboard_fab2(sch_1):fm_cpld_dbg_pwr_en" )
			)
			( signal "FM_CPLD_DBG_PWR_EN_N"
				( objectStatus "@baseboard_fab2_lib.baseboard_fab2(sch_1):fm_cpld_dbg_pwr_en_n" )
			)
			( signal "FM_CPLD_DBG_PWR_EN_R_N"
				( objectStatus "@baseboard_fab2_lib.baseboard_fab2(sch_1):fm_cpld_dbg_pwr_en_r_n" )
			)
			( signal "FM_UART_SWITCH_N"
				( objectStatus "@baseboard_fab2_lib.baseboard_fab2(sch_1):fm_uart_switch_n" )
			)
			( signal "LED_POSTCODE_0_R"
				( objectStatus "@baseboard_fab2_lib.baseboard_fab2(sch_1):led_postcode_0_r" )
			)
			( signal "LED_POSTCODE_1_R"
				( objectStatus "@baseboard_fab2_lib.baseboard_fab2(sch_1):led_postcode_1_r" )
			)
			( signal "LED_POSTCODE_2_R"
				( objectStatus "@baseboard_fab2_lib.baseboard_fab2(sch_1):led_postcode_2_r" )
			)
			( signal "LED_POSTCODE_3_R"
				( objectStatus "@baseboard_fab2_lib.baseboard_fab2(sch_1):led_postcode_3_r" )
			)
			( signal "LED_POSTCODE_4_R"
				( objectStatus "@baseboard_fab2_lib.baseboard_fab2(sch_1):led_postcode_4_r" )
			)
			( signal "LED_POSTCODE_5_R"
				( objectStatus "@baseboard_fab2_lib.baseboard_fab2(sch_1):led_postcode_5_r" )
			)
			( signal "LED_POSTCODE_6_R"
				( objectStatus "@baseboard_fab2_lib.baseboard_fab2(sch_1):led_postcode_6_r" )
			)
			( signal "LED_POSTCODE_7_R"
				( objectStatus "@baseboard_fab2_lib.baseboard_fab2(sch_1):led_postcode_7_r" )
			)
			( signal "P12V_STBY"
				( attribute "VOLTAGE" "12.0V"
					( Units "uVoltage" "V" 1.000000)
					( Status sAliasFlattened )
					( Origin gFrontEnd )
				)
				( objectStatus "@baseboard_fab2_lib.baseboard_fab2(sch_1):p12v_stby" )
			)
			( signal "P5V_STBY"
				( attribute "VOLTAGE" "5.0V"
					( Units "uVoltage" "V" 1.000000)
					( Status sAliasFlattened )
					( Status sAliasConflict )
					( Origin gFrontEnd )
				)
				( objectStatus "@baseboard_fab2_lib.baseboard_fab2(sch_1):p5v_stby" )
			)
			( signal "P5V_STBY_DBG"
				( attribute "VOLTAGE" "5"
					( Units "uVoltage" "V" 1.000000)
					( Status sAliasFlattened )
					( Origin gFrontEnd )
				)
				( objectStatus "@baseboard_fab2_lib.baseboard_fab2(sch_1):p5v_stby_dbg" )
			)
			( signal "P5V_STBY_DGB_FS"
				( attribute "VOLTAGE" "5"
					( Units "uVoltage" "V" 1.000000)
					( Status sAliasFlattened )
					( Origin gFrontEnd )
				)
				( objectStatus "@baseboard_fab2_lib.baseboard_fab2(sch_1):p5v_stby_dgb_fs" )
			)
			( signal "SPA_5V_SIN_SW"
				( objectStatus "@baseboard_fab2_lib.baseboard_fab2(sch_1):spa_5v_sin_sw" )
			)
			( signal "SPA_MID_DBG_RX"
				( objectStatus "@baseboard_fab2_lib.baseboard_fab2(sch_1):spa_mid_dbg_rx" )
			)
			( signal "SPA_MID_DBG_TX"
				( objectStatus "@baseboard_fab2_lib.baseboard_fab2(sch_1):spa_mid_dbg_tx" )
			)
			( signal "SPA_SIN_SW_R"
				( objectStatus "@baseboard_fab2_lib.baseboard_fab2(sch_1):spa_sin_sw_r" )
			)
			( signal "FM_PCH_PWRBTN_R_N"
				( objectStatus "@baseboard_fab2_lib.baseboard_fab2(sch_1):fm_pch_pwrbtn_r_n" )
			)
			( signal "RST_BMC_SYSRST_BTN_OUT_B_R_N"
				( objectStatus "@baseboard_fab2_lib.baseboard_fab2(sch_1):rst_bmc_sysrst_btn_out_b_r_n" )
			)
			( signal "FP_NMI_BTN"
				( objectStatus "@baseboard_fab2_lib.baseboard_fab2(sch_1):fp_nmi_btn" )
			)
			( signal "FP_NMI_BTN_OUT_N"
				( objectStatus "@baseboard_fab2_lib.baseboard_fab2(sch_1):fp_nmi_btn_out_n" )
			)
			( signal "FP_NMI_BTN_OUT_R_N"
				( objectStatus "@baseboard_fab2_lib.baseboard_fab2(sch_1):fp_nmi_btn_out_r_n" )
			)
			( signal "FP_NMI_BTN_R_N"
				( objectStatus "@baseboard_fab2_lib.baseboard_fab2(sch_1):fp_nmi_btn_r_n" )
			)
			( signal "H_CPU0_FAST_WAKE"
				( objectStatus "@baseboard_fab2_lib.baseboard_fab2(sch_1):h_cpu0_fast_wake" )
			)
			( signal "H_CPU0_FAST_WAKE_B_N"
				( objectStatus "@baseboard_fab2_lib.baseboard_fab2(sch_1):h_cpu0_fast_wake_b_n" )
			)
			( signal "RST_BMC_SRST_R2_N"
				( objectStatus "@baseboard_fab2_lib.baseboard_fab2(sch_1):rst_bmc_srst_r2_n" )
			)
			( signal "FM_UARTSW_LSB_R_N"
				( objectStatus "@baseboard_fab2_lib.baseboard_fab2(sch_1):fm_uartsw_lsb_r_n" )
			)
			( signal "FM_UARTSW_MSB_R_N"
				( objectStatus "@baseboard_fab2_lib.baseboard_fab2(sch_1):fm_uartsw_msb_r_n" )
			)
			( signal "SP2_BMC_CM_UART_RX_R"
				( objectStatus "@baseboard_fab2_lib.baseboard_fab2(sch_1):sp2_bmc_cm_uart_rx_r" )
			)
			( signal "SP2_BMC_CM_UART_RX_R1"
				( objectStatus "@baseboard_fab2_lib.baseboard_fab2(sch_1):sp2_bmc_cm_uart_rx_r1" )
			)
			( signal "SP2_BMC_CM_UART_TX_R"
				( objectStatus "@baseboard_fab2_lib.baseboard_fab2(sch_1):sp2_bmc_cm_uart_tx_r" )
			)
			( signal "SP2_BMC_CM_UART_TX_R1"
				( objectStatus "@baseboard_fab2_lib.baseboard_fab2(sch_1):sp2_bmc_cm_uart_tx_r1" )
			)
			( signal "UART_MUX_IN_R"
				( objectStatus "@baseboard_fab2_lib.baseboard_fab2(sch_1):uart_mux_in_r" )
			)
			( signal "UART_MUX_OUT_R"
				( objectStatus "@baseboard_fab2_lib.baseboard_fab2(sch_1):uart_mux_out_r" )
			)
			( signal "SMB_OCP_LAN_STBY_LVC3_SCL"
				( objectStatus "@baseboard_fab2_lib.baseboard_fab2(sch_1):smb_ocp_lan_stby_lvc3_scl" )
			)
			( signal "SMB_OCP_LAN_STBY_LVC3_SDA"
				( objectStatus "@baseboard_fab2_lib.baseboard_fab2(sch_1):smb_ocp_lan_stby_lvc3_sda" )
			)
			( signal "FAN_PWM_OUT_SYS0_BUF"
				( objectStatus "@baseboard_fab2_lib.baseboard_fab2(sch_1):fan_pwm_out_sys0_buf" )
			)
			( signal "FAN_PWM_OUT_SYS0_R"
				( objectStatus "@baseboard_fab2_lib.baseboard_fab2(sch_1):fan_pwm_out_sys0_r" )
			)
			( signal "FAN_PWM_OUT_SYS1_BUF"
				( objectStatus "@baseboard_fab2_lib.baseboard_fab2(sch_1):fan_pwm_out_sys1_buf" )
			)
			( signal "FAN_PWM_OUT_SYS1_R"
				( objectStatus "@baseboard_fab2_lib.baseboard_fab2(sch_1):fan_pwm_out_sys1_r" )
			)
			( signal "FAN_TACH0_CPU0_D1"
				( objectStatus "@baseboard_fab2_lib.baseboard_fab2(sch_1):fan_tach0_cpu0_d1" )
			)
			( signal "FAN_TACH0_CPU0_D2"
				( objectStatus "@baseboard_fab2_lib.baseboard_fab2(sch_1):fan_tach0_cpu0_d2" )
			)
			( signal "FAN_TACH1_CPU1_D1"
				( objectStatus "@baseboard_fab2_lib.baseboard_fab2(sch_1):fan_tach1_cpu1_d1" )
			)
			( signal "FAN_TACH1_CPU1_D2"
				( objectStatus "@baseboard_fab2_lib.baseboard_fab2(sch_1):fan_tach1_cpu1_d2" )
			)
			( signal "FAN_TACH2_CPU1_D1"
				( objectStatus "@baseboard_fab2_lib.baseboard_fab2(sch_1):fan_tach2_cpu1_d1" )
			)
			( signal "FAN_TACH2_CPU1_D2"
				( objectStatus "@baseboard_fab2_lib.baseboard_fab2(sch_1):fan_tach2_cpu1_d2" )
			)
			( signal "FAN_TACH3_CPU1_D1"
				( objectStatus "@baseboard_fab2_lib.baseboard_fab2(sch_1):fan_tach3_cpu1_d1" )
			)
			( signal "FAN_TACH3_CPU1_D2"
				( objectStatus "@baseboard_fab2_lib.baseboard_fab2(sch_1):fan_tach3_cpu1_d2" )
			)
			( signal "FM_CTNR_PS_ON"
				( objectStatus "@baseboard_fab2_lib.baseboard_fab2(sch_1):fm_ctnr_ps_on" )
			)
			( signal "FM_DISABLE_FAN_N"
				( objectStatus "@baseboard_fab2_lib.baseboard_fab2(sch_1):fm_disable_fan_n" )
			)
			( signal "FM_ENABLE_FAN_POWER"
				( objectStatus "@baseboard_fab2_lib.baseboard_fab2(sch_1):fm_enable_fan_power" )
			)
			( signal "P12V_FAN"
				( attribute "VOLTAGE" "12.0V"
					( Units "uVoltage" "V" 1.000000)
					( Status sAliasFlattened )
					( Origin gFrontEnd )
				)
				( objectStatus "@baseboard_fab2_lib.baseboard_fab2(sch_1):p12v_fan" )
			)
			( signal "TP_FAN_0"
				( objectStatus "@baseboard_fab2_lib.baseboard_fab2(sch_1):tp_fan_0" )
			)
			( signal "TP_FAN_1"
				( objectStatus "@baseboard_fab2_lib.baseboard_fab2(sch_1):tp_fan_1" )
			)
			( signal "PU_SPI_BMC_BT_HOLD_N"
				( objectStatus "@baseboard_fab2_lib.baseboard_fab2(sch_1):pu_spi_bmc_bt_hold_n" )
			)
			( signal "PU_SPI_BMC_BT_WP_N"
				( objectStatus "@baseboard_fab2_lib.baseboard_fab2(sch_1):pu_spi_bmc_bt_wp_n" )
			)
			( signal "PU_SPI_FLASH_RESET_2_N"
				( objectStatus "@baseboard_fab2_lib.baseboard_fab2(sch_1):pu_spi_flash_reset_2_n" )
			)
			( signal "SPI_BMC_BT_DI_R"
				( objectStatus "@baseboard_fab2_lib.baseboard_fab2(sch_1):spi_bmc_bt_di_r" )
			)
			( signal "TP_SPI_2_0"
				( objectStatus "@baseboard_fab2_lib.baseboard_fab2(sch_1):tp_spi_2_0" )
			)
			( signal "TP_SPI_2_1"
				( objectStatus "@baseboard_fab2_lib.baseboard_fab2(sch_1):tp_spi_2_1" )
			)
			( signal "TP_SPI_2_2"
				( objectStatus "@baseboard_fab2_lib.baseboard_fab2(sch_1):tp_spi_2_2" )
			)
			( signal "TP_SPI_2_3"
				( objectStatus "@baseboard_fab2_lib.baseboard_fab2(sch_1):tp_spi_2_3" )
			)
			( signal "TP_SPI_2_4"
				( objectStatus "@baseboard_fab2_lib.baseboard_fab2(sch_1):tp_spi_2_4" )
			)
			( signal "TP_SPI_2_5"
				( objectStatus "@baseboard_fab2_lib.baseboard_fab2(sch_1):tp_spi_2_5" )
			)
			( signal "TP_SPI_2_6"
				( objectStatus "@baseboard_fab2_lib.baseboard_fab2(sch_1):tp_spi_2_6" )
			)
			( signal "SMB_CPU1_PE_HP_GTL_R_SCL"
				( objectStatus "@baseboard_fab2_lib.baseboard_fab2(sch_1):smb_cpu1_pe_hp_gtl_r_scl" )
			)
			( signal "SMB_CPU1_PE_HP_GTL_R_SDA"
				( objectStatus "@baseboard_fab2_lib.baseboard_fab2(sch_1):smb_cpu1_pe_hp_gtl_r_sda" )
			)
			( signal "SMB_PEHPCPU1_STBY_LVC3_R_SCL"
				( objectStatus "@baseboard_fab2_lib.baseboard_fab2(sch_1):smb_pehpcpu1_stby_lvc3_r_scl" )
			)
			( signal "SMB_PEHPCPU1_STBY_LVC3_R_SDA"
				( objectStatus "@baseboard_fab2_lib.baseboard_fab2(sch_1):smb_pehpcpu1_stby_lvc3_r_sda" )
			)
			( signal "SMB_PEHPCPU1_STBY_LVC3_SCL"
				( objectStatus "@baseboard_fab2_lib.baseboard_fab2(sch_1):smb_pehpcpu1_stby_lvc3_scl" )
			)
			( signal "SMB_PEHPCPU1_STBY_LVC3_SDA"
				( objectStatus "@baseboard_fab2_lib.baseboard_fab2(sch_1):smb_pehpcpu1_stby_lvc3_sda" )
			)
			( signal "TP_SMB_PEHPCPU1_EN"
				( objectStatus "@baseboard_fab2_lib.baseboard_fab2(sch_1):tp_smb_pehpcpu1_en" )
			)
			( signal "FM_ADC128_A0"
				( objectStatus "@baseboard_fab2_lib.baseboard_fab2(sch_1):fm_adc128_a0" )
			)
			( signal "FM_ADC128_A1"
				( objectStatus "@baseboard_fab2_lib.baseboard_fab2(sch_1):fm_adc128_a1" )
			)
			( signal "IRQ_VM_INT_R_N"
				( objectStatus "@baseboard_fab2_lib.baseboard_fab2(sch_1):irq_vm_int_r_n" )
			)
			( signal "P3V3_FB_ADC128_VCC"
				( attribute "VOLTAGE" "+3.3V"
					( Units "uVoltage" "V" 1.000000)
					( Status sAliasFlattened )
					( Origin gFrontEnd )
				)
				( objectStatus "@baseboard_fab2_lib.baseboard_fab2(sch_1):p3v3_fb_adc128_vcc" )
			)
			( signal "TP_ADC128_VREF"
				( objectStatus "@baseboard_fab2_lib.baseboard_fab2(sch_1):tp_adc128_vref" )
			)
			( signal "ISENSE_TMP421_1_BC"
				( objectStatus "@baseboard_fab2_lib.baseboard_fab2(sch_1):isense_tmp421_1_bc" )
			)
			( signal "ISENSE_TMP421_1_DXN"
				( objectStatus "@baseboard_fab2_lib.baseboard_fab2(sch_1):isense_tmp421_1_dxn" )
			)
			( signal "ISENSE_TMP421_1_DXP"
				( objectStatus "@baseboard_fab2_lib.baseboard_fab2(sch_1):isense_tmp421_1_dxp" )
			)
			( signal "ISENSE_TMP421_1_E"
				( objectStatus "@baseboard_fab2_lib.baseboard_fab2(sch_1):isense_tmp421_1_e" )
			)
			( signal "ISENSE_TMP421_2_BC"
				( objectStatus "@baseboard_fab2_lib.baseboard_fab2(sch_1):isense_tmp421_2_bc" )
			)
			( signal "ISENSE_TMP421_2_DXN"
				( objectStatus "@baseboard_fab2_lib.baseboard_fab2(sch_1):isense_tmp421_2_dxn" )
			)
			( signal "ISENSE_TMP421_2_DXP"
				( objectStatus "@baseboard_fab2_lib.baseboard_fab2(sch_1):isense_tmp421_2_dxp" )
			)
			( signal "ISENSE_TMP421_2_E"
				( objectStatus "@baseboard_fab2_lib.baseboard_fab2(sch_1):isense_tmp421_2_e" )
			)
			( signal "PD_FRU_WP"
				( objectStatus "@baseboard_fab2_lib.baseboard_fab2(sch_1):pd_fru_wp" )
			)
			( signal "PD_TMP421_1_A0"
				( objectStatus "@baseboard_fab2_lib.baseboard_fab2(sch_1):pd_tmp421_1_a0" )
			)
			( signal "PD_TMP421_2_A1"
				( objectStatus "@baseboard_fab2_lib.baseboard_fab2(sch_1):pd_tmp421_2_a1" )
			)
			( signal "PU_AT24C64_A2"
				( objectStatus "@baseboard_fab2_lib.baseboard_fab2(sch_1):pu_at24c64_a2" )
			)
			( signal "PU_TMP421_1_A1"
				( objectStatus "@baseboard_fab2_lib.baseboard_fab2(sch_1):pu_tmp421_1_a1" )
			)
			( signal "PU_TMP421_2_A0"
				( objectStatus "@baseboard_fab2_lib.baseboard_fab2(sch_1):pu_tmp421_2_a0" )
			)
			( signal "SMB_SENSOR_STBY_LVC3_SCL"
				( objectStatus "@baseboard_fab2_lib.baseboard_fab2(sch_1):smb_sensor_stby_lvc3_scl" )
			)
			( signal "SMB_SENSOR_STBY_LVC3_SCL_R2"
				( objectStatus "@baseboard_fab2_lib.baseboard_fab2(sch_1):smb_sensor_stby_lvc3_scl_r2" )
			)
			( signal "SMB_SENSOR_STBY_LVC3_SDA"
				( objectStatus "@baseboard_fab2_lib.baseboard_fab2(sch_1):smb_sensor_stby_lvc3_sda" )
			)
			( signal "SMB_SENSOR_STBY_LVC3_SDA_R2"
				( objectStatus "@baseboard_fab2_lib.baseboard_fab2(sch_1):smb_sensor_stby_lvc3_sda_r2" )
			)
			( signal "SMB_SENSOR_TMP421_1_SCL"
				( objectStatus "@baseboard_fab2_lib.baseboard_fab2(sch_1):smb_sensor_tmp421_1_scl" )
			)
			( signal "SMB_SENSOR_TMP421_1_SDA"
				( objectStatus "@baseboard_fab2_lib.baseboard_fab2(sch_1):smb_sensor_tmp421_1_sda" )
			)
			( signal "SMB_SENSOR_TMP421_2_SCL"
				( objectStatus "@baseboard_fab2_lib.baseboard_fab2(sch_1):smb_sensor_tmp421_2_scl" )
			)
			( signal "SMB_SENSOR_TMP421_2_SDA"
				( objectStatus "@baseboard_fab2_lib.baseboard_fab2(sch_1):smb_sensor_tmp421_2_sda" )
			)
			( signal "FM_DB_PRESENT"
				( objectStatus "@baseboard_fab2_lib.baseboard_fab2(sch_1):fm_db_present" )
			)
			( signal "FM_DB_UART_SEL0_N"
				( objectStatus "@baseboard_fab2_lib.baseboard_fab2(sch_1):fm_db_uart_sel0_n" )
			)
			( signal "FM_DB_UART_SEL1_N"
				( objectStatus "@baseboard_fab2_lib.baseboard_fab2(sch_1):fm_db_uart_sel1_n" )
			)
			( signal "FM_DB_UART_SEL2_N"
				( objectStatus "@baseboard_fab2_lib.baseboard_fab2(sch_1):fm_db_uart_sel2_n" )
			)
			( signal "FM_DB_UART_SEL3_N"
				( objectStatus "@baseboard_fab2_lib.baseboard_fab2(sch_1):fm_db_uart_sel3_n" )
			)
			( signal "FM_DB_UART_SEL4_N"
				( objectStatus "@baseboard_fab2_lib.baseboard_fab2(sch_1):fm_db_uart_sel4_n" )
			)
			( signal "FM_UART_SEL_N"
				( objectStatus "@baseboard_fab2_lib.baseboard_fab2(sch_1):fm_uart_sel_n" )
			)
			( signal "TP_FET_Q56_3"
				( objectStatus "@baseboard_fab2_lib.baseboard_fab2(sch_1):tp_fet_q56_3" )
			)
			( signal "TP_FET_Q56_4"
				( objectStatus "@baseboard_fab2_lib.baseboard_fab2(sch_1):tp_fet_q56_4" )
			)
			( signal "A_P3V_BAT_R"
				( attribute "VOLTAGE" "+3 V"
					( Units "uVoltage" "V" 1.000000)
					( Status sAliasFlattened )
					( Origin gFrontEnd )
				)
				( objectStatus "@baseboard_fab2_lib.baseboard_fab2(sch_1):a_p3v_bat_r" )
			)
			( signal "FM_BATTERY_SENSE_EN"
				( objectStatus "@baseboard_fab2_lib.baseboard_fab2(sch_1):fm_battery_sense_en" )
			)
			( signal "P3V_BAT_SOURCE_R"
				( attribute "VOLTAGE" "+3V"
					( Units "uVoltage" "V" 1.000000)
					( Status sAliasFlattened )
					( Origin gFrontEnd )
				)
				( objectStatus "@baseboard_fab2_lib.baseboard_fab2(sch_1):p3v_bat_source_r" )
			)
			( signal "P5V"
				( attribute "VOLTAGE" "5.0V"
					( Units "uVoltage" "V" 1.000000)
					( Status sAliasFlattened )
					( Status sAliasConflict )
					( Origin gFrontEnd )
				)
				( objectStatus "@baseboard_fab2_lib.baseboard_fab2(sch_1):p5v" )
			)
			( signal "FM_FAST_PROCHOT_AND_OUT_0_N"
				( objectStatus "@baseboard_fab2_lib.baseboard_fab2(sch_1):fm_fast_prochot_and_out_0_n" )
			)
			( signal "FM_FAST_PROCHOT_AND_OUT_1_N"
				( objectStatus "@baseboard_fab2_lib.baseboard_fab2(sch_1):fm_fast_prochot_and_out_1_n" )
			)
			( signal "FM_FAST_PROCHOT_EN"
				( objectStatus "@baseboard_fab2_lib.baseboard_fab2(sch_1):fm_fast_prochot_en" )
			)
			( signal "FM_FAST_PROCHOT_THROTTLE_DLY_BU"
				( objectStatus "@baseboard_fab2_lib.baseboard_fab2(sch_1):fm_fast_prochot_throttle_dly_buf_n" )
			)
			( signal "FM_FAST_PROCHOT_THROTTLE_DLY_N"
				( objectStatus "@baseboard_fab2_lib.baseboard_fab2(sch_1):fm_fast_prochot_throttle_dly_n" )
			)
			( signal "FM_FAST_PROCHOT_THROTTLE_IN_N"
				( objectStatus "@baseboard_fab2_lib.baseboard_fab2(sch_1):fm_fast_prochot_throttle_in_n" )
			)
			( signal "FM_OC_DETECT_N"
				( objectStatus "@baseboard_fab2_lib.baseboard_fab2(sch_1):fm_oc_detect_n" )
			)
			( signal "FM_PMBUS_ALERT_BUF_EN"
				( objectStatus "@baseboard_fab2_lib.baseboard_fab2(sch_1):fm_pmbus_alert_buf_en" )
			)
			( signal "FM_THROTTLE_R1_N"
				( objectStatus "@baseboard_fab2_lib.baseboard_fab2(sch_1):fm_throttle_r1_n" )
			)
			( signal "IRQ_FORCE_NM_THROTTLE_R_N"
				( objectStatus "@baseboard_fab2_lib.baseboard_fab2(sch_1):irq_force_nm_throttle_r_n" )
			)
			( signal "IRQ_SML1_PMBUS_ALERT_BUF_N"
				( objectStatus "@baseboard_fab2_lib.baseboard_fab2(sch_1):irq_sml1_pmbus_alert_buf_n" )
			)
			( signal "P12V_HDD_SATA"
				( attribute "VOLTAGE" "12"
					( Units "uVoltage" "V" 1.000000)
					( Status sAliasFlattened )
					( Origin gFrontEnd )
				)
				( objectStatus "@baseboard_fab2_lib.baseboard_fab2(sch_1):p12v_hdd_sata" )
			)
			( signal "P5V_HDD_SATA"
				( attribute "VOLTAGE" "5"
					( Units "uVoltage" "V" 1.000000)
					( Status sAliasFlattened )
					( Origin gFrontEnd )
				)
				( objectStatus "@baseboard_fab2_lib.baseboard_fab2(sch_1):p5v_hdd_sata" )
			)
			( signal "SATA6G_S1_RX_C_DN"
				( objectStatus "@baseboard_fab2_lib.baseboard_fab2(sch_1):sata6g_s1_rx_c_dn" )
			)
			( signal "SATA6G_S1_RX_C_DP"
				( objectStatus "@baseboard_fab2_lib.baseboard_fab2(sch_1):sata6g_s1_rx_c_dp" )
			)
			( signal "SATA6G_S1_TX_C_DN"
				( objectStatus "@baseboard_fab2_lib.baseboard_fab2(sch_1):sata6g_s1_tx_c_dn" )
			)
			( signal "SATA6G_S1_TX_C_DP"
				( objectStatus "@baseboard_fab2_lib.baseboard_fab2(sch_1):sata6g_s1_tx_c_dp" )
			)
			( signal "PD_SATA0_CONTROLLER_TYPE_R"
				( objectStatus "@baseboard_fab2_lib.baseboard_fab2(sch_1):pd_sata0_controller_type_r" )
			)
			( signal "PD_SATA1_CONTROLLER_TYPE_R"
				( objectStatus "@baseboard_fab2_lib.baseboard_fab2(sch_1):pd_sata1_controller_type_r" )
			)
			( signal "PU_DATAIN1_SATA_0_R"
				( objectStatus "@baseboard_fab2_lib.baseboard_fab2(sch_1):pu_datain1_sata_0_r" )
			)
			( signal "PU_DATAIN1_SATA_1_R"
				( objectStatus "@baseboard_fab2_lib.baseboard_fab2(sch_1):pu_datain1_sata_1_r" )
			)
			( signal "SATA6G_P0_RX_C_DN"
				( objectStatus "@baseboard_fab2_lib.baseboard_fab2(sch_1):sata6g_p0_rx_c_dn" )
			)
			( signal "SATA6G_P0_RX_C_DP"
				( objectStatus "@baseboard_fab2_lib.baseboard_fab2(sch_1):sata6g_p0_rx_c_dp" )
			)
			( signal "SATA6G_P0_TX_C_DN"
				( objectStatus "@baseboard_fab2_lib.baseboard_fab2(sch_1):sata6g_p0_tx_c_dn" )
			)
			( signal "SATA6G_P0_TX_C_DP"
				( objectStatus "@baseboard_fab2_lib.baseboard_fab2(sch_1):sata6g_p0_tx_c_dp" )
			)
			( signal "SATA6G_P1_RX_C_DN"
				( objectStatus "@baseboard_fab2_lib.baseboard_fab2(sch_1):sata6g_p1_rx_c_dn" )
			)
			( signal "SATA6G_P1_RX_C_DP"
				( objectStatus "@baseboard_fab2_lib.baseboard_fab2(sch_1):sata6g_p1_rx_c_dp" )
			)
			( signal "SATA6G_P1_TX_C_DN"
				( objectStatus "@baseboard_fab2_lib.baseboard_fab2(sch_1):sata6g_p1_tx_c_dn" )
			)
			( signal "SATA6G_P1_TX_C_DP"
				( objectStatus "@baseboard_fab2_lib.baseboard_fab2(sch_1):sata6g_p1_tx_c_dp" )
			)
			( signal "SATA6G_P2_RX_C_DN"
				( objectStatus "@baseboard_fab2_lib.baseboard_fab2(sch_1):sata6g_p2_rx_c_dn" )
			)
			( signal "SATA6G_P2_RX_C_DP"
				( objectStatus "@baseboard_fab2_lib.baseboard_fab2(sch_1):sata6g_p2_rx_c_dp" )
			)
			( signal "SATA6G_P2_TX_C_DN"
				( objectStatus "@baseboard_fab2_lib.baseboard_fab2(sch_1):sata6g_p2_tx_c_dn" )
			)
			( signal "SATA6G_P2_TX_C_DP"
				( objectStatus "@baseboard_fab2_lib.baseboard_fab2(sch_1):sata6g_p2_tx_c_dp" )
			)
			( signal "SATA6G_P3_RX_C_DN"
				( objectStatus "@baseboard_fab2_lib.baseboard_fab2(sch_1):sata6g_p3_rx_c_dn" )
			)
			( signal "SATA6G_P3_RX_C_DP"
				( objectStatus "@baseboard_fab2_lib.baseboard_fab2(sch_1):sata6g_p3_rx_c_dp" )
			)
			( signal "SATA6G_P3_TX_C_DN"
				( objectStatus "@baseboard_fab2_lib.baseboard_fab2(sch_1):sata6g_p3_tx_c_dn" )
			)
			( signal "SATA6G_P3_TX_C_DP"
				( objectStatus "@baseboard_fab2_lib.baseboard_fab2(sch_1):sata6g_p3_tx_c_dp" )
			)
			( signal "SATA6G_P4_RX_C_DN"
				( objectStatus "@baseboard_fab2_lib.baseboard_fab2(sch_1):sata6g_p4_rx_c_dn" )
			)
			( signal "SATA6G_P4_RX_C_DP"
				( objectStatus "@baseboard_fab2_lib.baseboard_fab2(sch_1):sata6g_p4_rx_c_dp" )
			)
			( signal "SATA6G_P4_TX_C_DN"
				( objectStatus "@baseboard_fab2_lib.baseboard_fab2(sch_1):sata6g_p4_tx_c_dn" )
			)
			( signal "SATA6G_P4_TX_C_DP"
				( objectStatus "@baseboard_fab2_lib.baseboard_fab2(sch_1):sata6g_p4_tx_c_dp" )
			)
			( signal "SATA6G_P5_RX_C_DN"
				( objectStatus "@baseboard_fab2_lib.baseboard_fab2(sch_1):sata6g_p5_rx_c_dn" )
			)
			( signal "SATA6G_P5_RX_C_DP"
				( objectStatus "@baseboard_fab2_lib.baseboard_fab2(sch_1):sata6g_p5_rx_c_dp" )
			)
			( signal "SATA6G_P5_TX_C_DN"
				( objectStatus "@baseboard_fab2_lib.baseboard_fab2(sch_1):sata6g_p5_tx_c_dn" )
			)
			( signal "SATA6G_P5_TX_C_DP"
				( objectStatus "@baseboard_fab2_lib.baseboard_fab2(sch_1):sata6g_p5_tx_c_dp" )
			)
			( signal "SATA6G_P6_RX_C_DN"
				( objectStatus "@baseboard_fab2_lib.baseboard_fab2(sch_1):sata6g_p6_rx_c_dn" )
			)
			( signal "SATA6G_P6_RX_C_DP"
				( objectStatus "@baseboard_fab2_lib.baseboard_fab2(sch_1):sata6g_p6_rx_c_dp" )
			)
			( signal "SATA6G_P6_TX_C_DN"
				( objectStatus "@baseboard_fab2_lib.baseboard_fab2(sch_1):sata6g_p6_tx_c_dn" )
			)
			( signal "SATA6G_P6_TX_C_DP"
				( objectStatus "@baseboard_fab2_lib.baseboard_fab2(sch_1):sata6g_p6_tx_c_dp" )
			)
			( signal "SATA6G_P7_RX_C_DN"
				( objectStatus "@baseboard_fab2_lib.baseboard_fab2(sch_1):sata6g_p7_rx_c_dn" )
			)
			( signal "SATA6G_P7_RX_C_DP"
				( objectStatus "@baseboard_fab2_lib.baseboard_fab2(sch_1):sata6g_p7_rx_c_dp" )
			)
			( signal "SATA6G_P7_TX_C_DN"
				( objectStatus "@baseboard_fab2_lib.baseboard_fab2(sch_1):sata6g_p7_tx_c_dn" )
			)
			( signal "SATA6G_P7_TX_C_DP"
				( objectStatus "@baseboard_fab2_lib.baseboard_fab2(sch_1):sata6g_p7_tx_c_dp" )
			)
			( signal "SGPIO_PCH_SATA_CLOCK_R"
				( objectStatus "@baseboard_fab2_lib.baseboard_fab2(sch_1):sgpio_pch_sata_clock_r" )
			)
			( signal "SGPIO_PCH_SATA_DOUT0_R"
				( objectStatus "@baseboard_fab2_lib.baseboard_fab2(sch_1):sgpio_pch_sata_dout0_r" )
			)
			( signal "SGPIO_PCH_SATA_LOAD_R"
				( objectStatus "@baseboard_fab2_lib.baseboard_fab2(sch_1):sgpio_pch_sata_load_r" )
			)
			( signal "TP_FM_QAT_CBL_PRSNT0_R_N"
				( objectStatus "@baseboard_fab2_lib.baseboard_fab2(sch_1):tp_fm_qat_cbl_prsnt0_r_n" )
			)
			( signal "TP_FM_QAT_CBL_PRSNT1_N_R"
				( objectStatus "@baseboard_fab2_lib.baseboard_fab2(sch_1):tp_fm_qat_cbl_prsnt1_n_r" )
			)
			( signal "TP_SGPIO_SATA_CLOCK1_R"
				( objectStatus "@baseboard_fab2_lib.baseboard_fab2(sch_1):tp_sgpio_sata_clock1_r" )
			)
			( signal "TP_SGPIO_SATA_DATA1_R"
				( objectStatus "@baseboard_fab2_lib.baseboard_fab2(sch_1):tp_sgpio_sata_data1_r" )
			)
			( signal "TP_SGPIO_SATA_LOAD1_R"
				( objectStatus "@baseboard_fab2_lib.baseboard_fab2(sch_1):tp_sgpio_sata_load1_r" )
			)
			( signal "PD_SATA2_CONTROLLER_TYPE"
				( objectStatus "@baseboard_fab2_lib.baseboard_fab2(sch_1):pd_sata2_controller_type" )
			)
			( signal "PU_DATAIN1_SATA_2"
				( objectStatus "@baseboard_fab2_lib.baseboard_fab2(sch_1):pu_datain1_sata_2" )
			)
			( signal "SATA6G_P10_RX_C_DN"
				( objectStatus "@baseboard_fab2_lib.baseboard_fab2(sch_1):sata6g_p10_rx_c_dn" )
			)
			( signal "SATA6G_P10_RX_C_DP"
				( objectStatus "@baseboard_fab2_lib.baseboard_fab2(sch_1):sata6g_p10_rx_c_dp" )
			)
			( signal "SATA6G_P10_TX_C_DN"
				( objectStatus "@baseboard_fab2_lib.baseboard_fab2(sch_1):sata6g_p10_tx_c_dn" )
			)
			( signal "SATA6G_P10_TX_C_DP"
				( objectStatus "@baseboard_fab2_lib.baseboard_fab2(sch_1):sata6g_p10_tx_c_dp" )
			)
			( signal "SATA6G_P11_RX_C_DN"
				( objectStatus "@baseboard_fab2_lib.baseboard_fab2(sch_1):sata6g_p11_rx_c_dn" )
			)
			( signal "SATA6G_P11_RX_C_DP"
				( objectStatus "@baseboard_fab2_lib.baseboard_fab2(sch_1):sata6g_p11_rx_c_dp" )
			)
			( signal "SATA6G_P11_TX_C_DN"
				( objectStatus "@baseboard_fab2_lib.baseboard_fab2(sch_1):sata6g_p11_tx_c_dn" )
			)
			( signal "SATA6G_P11_TX_C_DP"
				( objectStatus "@baseboard_fab2_lib.baseboard_fab2(sch_1):sata6g_p11_tx_c_dp" )
			)
			( signal "SATA6G_P8_RX_C_DN"
				( objectStatus "@baseboard_fab2_lib.baseboard_fab2(sch_1):sata6g_p8_rx_c_dn" )
			)
			( signal "SATA6G_P8_RX_C_DP"
				( objectStatus "@baseboard_fab2_lib.baseboard_fab2(sch_1):sata6g_p8_rx_c_dp" )
			)
			( signal "SATA6G_P8_TX_C_DN"
				( objectStatus "@baseboard_fab2_lib.baseboard_fab2(sch_1):sata6g_p8_tx_c_dn" )
			)
			( signal "SATA6G_P8_TX_C_DP"
				( objectStatus "@baseboard_fab2_lib.baseboard_fab2(sch_1):sata6g_p8_tx_c_dp" )
			)
			( signal "SATA6G_P9_RX_C_DN"
				( objectStatus "@baseboard_fab2_lib.baseboard_fab2(sch_1):sata6g_p9_rx_c_dn" )
			)
			( signal "SATA6G_P9_RX_C_DP"
				( objectStatus "@baseboard_fab2_lib.baseboard_fab2(sch_1):sata6g_p9_rx_c_dp" )
			)
			( signal "SATA6G_P9_TX_C_DN"
				( objectStatus "@baseboard_fab2_lib.baseboard_fab2(sch_1):sata6g_p9_tx_c_dn" )
			)
			( signal "SATA6G_P9_TX_C_DP"
				( objectStatus "@baseboard_fab2_lib.baseboard_fab2(sch_1):sata6g_p9_tx_c_dp" )
			)
			( signal "SGPIO_PCH_SSATA_CLOCK_R"
				( objectStatus "@baseboard_fab2_lib.baseboard_fab2(sch_1):sgpio_pch_ssata_clock_r" )
			)
			( signal "SGPIO_PCH_SSATA_DOUT0_R"
				( objectStatus "@baseboard_fab2_lib.baseboard_fab2(sch_1):sgpio_pch_ssata_dout0_r" )
			)
			( signal "SGPIO_PCH_SSATA_LOAD_R"
				( objectStatus "@baseboard_fab2_lib.baseboard_fab2(sch_1):sgpio_pch_ssata_load_r" )
			)
			( signal "TP_FM_QAT_CBL_PRSNT2_N"
				( objectStatus "@baseboard_fab2_lib.baseboard_fab2(sch_1):tp_fm_qat_cbl_prsnt2_n" )
			)
			( signal "FM_BEEP_LED_P"
				( objectStatus "@baseboard_fab2_lib.baseboard_fab2(sch_1):fm_beep_led_p" )
			)
			( signal "FM_PWR_BTN_R_N"
				( objectStatus "@baseboard_fab2_lib.baseboard_fab2(sch_1):fm_pwr_btn_r_n" )
			)
			( signal "FM_SPEAKER_PCH_N"
				( objectStatus "@baseboard_fab2_lib.baseboard_fab2(sch_1):fm_speaker_pch_n" )
			)
			( signal "FP_ID_LED_P5V_STBY_N"
				( objectStatus "@baseboard_fab2_lib.baseboard_fab2(sch_1):fp_id_led_p5v_stby_n" )
			)
			( signal "FP_ID_LED_XOR_R"
				( objectStatus "@baseboard_fab2_lib.baseboard_fab2(sch_1):fp_id_led_xor_r" )
			)
			( signal "FP_PWR_BTN_BUF1_N"
				( objectStatus "@baseboard_fab2_lib.baseboard_fab2(sch_1):fp_pwr_btn_buf1_n" )
			)
			( signal "FP_PWR_BTN_R1_N"
				( objectStatus "@baseboard_fab2_lib.baseboard_fab2(sch_1):fp_pwr_btn_r1_n" )
			)
			( signal "FP_PWR_BTN_R_N"
				( objectStatus "@baseboard_fab2_lib.baseboard_fab2(sch_1):fp_pwr_btn_r_n" )
			)
			( signal "FP_RST_BTN_BUF1_N"
				( objectStatus "@baseboard_fab2_lib.baseboard_fab2(sch_1):fp_rst_btn_buf1_n" )
			)
			( signal "FP_RST_BTN_R_N"
				( objectStatus "@baseboard_fab2_lib.baseboard_fab2(sch_1):fp_rst_btn_r_n" )
			)
			( signal "PWRGD_P3V3"
				( objectStatus "@baseboard_fab2_lib.baseboard_fab2(sch_1):pwrgd_p3v3" )
			)
			( signal "PWRGD_P3V3_R"
				( objectStatus "@baseboard_fab2_lib.baseboard_fab2(sch_1):pwrgd_p3v3_r" )
			)
			( signal "RST_SYSTEM_BTN_BUF_N"
				( objectStatus "@baseboard_fab2_lib.baseboard_fab2(sch_1):rst_system_btn_buf_n" )
			)
			( signal "P5V_USB"
				( attribute "VOLTAGE" "5V"
					( Units "uVoltage" "V" 1.000000)
					( Status sAliasFlattened )
					( Origin gFrontEnd )
				)
				( objectStatus "@baseboard_fab2_lib.baseboard_fab2(sch_1):p5v_usb" )
			)
			( signal "TP_USB_ESD_AC2"
				( objectStatus "@baseboard_fab2_lib.baseboard_fab2(sch_1):tp_usb_esd_ac2" )
			)
			( signal "TP_USB_ESD_AC3"
				( objectStatus "@baseboard_fab2_lib.baseboard_fab2(sch_1):tp_usb_esd_ac3" )
			)
			( signal "TP_USB_ESD_OUT2"
				( objectStatus "@baseboard_fab2_lib.baseboard_fab2(sch_1):tp_usb_esd_out2" )
			)
			( signal "TP_USB_ESD_OUT3"
				( objectStatus "@baseboard_fab2_lib.baseboard_fab2(sch_1):tp_usb_esd_out3" )
			)
			( signal "USB2_P01_ESD_DN"
				( objectStatus "@baseboard_fab2_lib.baseboard_fab2(sch_1):usb2_p01_esd_dn" )
			)
			( signal "USB2_P01_ESD_DP"
				( objectStatus "@baseboard_fab2_lib.baseboard_fab2(sch_1):usb2_p01_esd_dp" )
			)
			( signal "FM_BMC_FAULT_LED"
				( objectStatus "@baseboard_fab2_lib.baseboard_fab2(sch_1):fm_bmc_fault_led" )
			)
			( signal "FM_RED_LED_ANODE"
				( objectStatus "@baseboard_fab2_lib.baseboard_fab2(sch_1):fm_red_led_anode" )
			)
			( signal "FM_RED_LED_CATHODE"
				( objectStatus "@baseboard_fab2_lib.baseboard_fab2(sch_1):fm_red_led_cathode" )
			)
			( signal "FP_LED_HDD_ACTIVITY_AND_N"
				( objectStatus "@baseboard_fab2_lib.baseboard_fab2(sch_1):fp_led_hdd_activity_and_n" )
			)
			( signal "FP_LED_HDD_ACTIVITY_AND_R_N"
				( objectStatus "@baseboard_fab2_lib.baseboard_fab2(sch_1):fp_led_hdd_activity_and_r_n" )
			)
			( signal "LED_P5V_STBY"
				( objectStatus "@baseboard_fab2_lib.baseboard_fab2(sch_1):led_p5v_stby" )
			)
			( signal "LED_SAS_ACT_R_N"
				( objectStatus "@baseboard_fab2_lib.baseboard_fab2(sch_1):led_sas_act_r_n" )
			)
			( signal "LED_SATA_ACT_R_N"
				( objectStatus "@baseboard_fab2_lib.baseboard_fab2(sch_1):led_sata_act_r_n" )
			)
			( signal "FAN_PWM_OUT_SYS0_R1"
				( objectStatus "@baseboard_fab2_lib.baseboard_fab2(sch_1):fan_pwm_out_sys0_r1" )
			)
			( signal "FAN_TACH0_R"
				( objectStatus "@baseboard_fab2_lib.baseboard_fab2(sch_1):fan_tach0_r" )
			)
			( signal "FAN_TACH1_R"
				( objectStatus "@baseboard_fab2_lib.baseboard_fab2(sch_1):fan_tach1_r" )
			)
			( signal "FAN_TACH2_R"
				( objectStatus "@baseboard_fab2_lib.baseboard_fab2(sch_1):fan_tach2_r" )
			)
			( signal "FAN_TACH3_R"
				( objectStatus "@baseboard_fab2_lib.baseboard_fab2(sch_1):fan_tach3_r" )
			)
			( signal "FM_CTNR_PS_ON_R"
				( objectStatus "@baseboard_fab2_lib.baseboard_fab2(sch_1):fm_ctnr_ps_on_r" )
			)
			( signal "FM_MATED_IN_D1_N"
				( objectStatus "@baseboard_fab2_lib.baseboard_fab2(sch_1):fm_mated_in_d1_n" )
			)
			( signal "FM_MATED_IN_D2_N"
				( objectStatus "@baseboard_fab2_lib.baseboard_fab2(sch_1):fm_mated_in_d2_n" )
			)
			( signal "FM_MATED_IN_N"
				( objectStatus "@baseboard_fab2_lib.baseboard_fab2(sch_1):fm_mated_in_n" )
			)
			( signal "FM_P12V_HOTSWAP0_EN"
				( objectStatus "@baseboard_fab2_lib.baseboard_fab2(sch_1):fm_p12v_hotswap0_en" )
			)
			( signal "FM_PS_EN"
				( objectStatus "@baseboard_fab2_lib.baseboard_fab2(sch_1):fm_ps_en" )
			)
			( signal "IRQ_SML1_PMBUS_ALERT_R_N"
				( objectStatus "@baseboard_fab2_lib.baseboard_fab2(sch_1):irq_sml1_pmbus_alert_r_n" )
			)
			( signal "P12V_PSU"
				( attribute "VOLTAGE" "12.0"
					( Units "uVoltage" "V" 1.000000)
					( Status sAliasFlattened )
					( Origin gFrontEnd )
				)
				( objectStatus "@baseboard_fab2_lib.baseboard_fab2(sch_1):p12v_psu" )
			)
			( signal "P3E_CPU1_PE3_MP_C_TXN<0>"
				( objectStatus "@baseboard_fab2_lib.baseboard_fab2(sch_1):p3e_cpu1_pe3_mp_c_txn(0)" )
			)
			( signal "P3E_CPU1_PE3_MP_C_TXN<1>"
				( objectStatus "@baseboard_fab2_lib.baseboard_fab2(sch_1):p3e_cpu1_pe3_mp_c_txn(1)" )
			)
			( signal "P3E_CPU1_PE3_MP_C_TXN<2>"
				( objectStatus "@baseboard_fab2_lib.baseboard_fab2(sch_1):p3e_cpu1_pe3_mp_c_txn(2)" )
			)
			( signal "P3E_CPU1_PE3_MP_C_TXN<3>"
				( objectStatus "@baseboard_fab2_lib.baseboard_fab2(sch_1):p3e_cpu1_pe3_mp_c_txn(3)" )
			)
			( signal "P3E_CPU1_PE3_MP_C_TXN<4>"
				( objectStatus "@baseboard_fab2_lib.baseboard_fab2(sch_1):p3e_cpu1_pe3_mp_c_txn(4)" )
			)
			( signal "P3E_CPU1_PE3_MP_C_TXN<5>"
				( objectStatus "@baseboard_fab2_lib.baseboard_fab2(sch_1):p3e_cpu1_pe3_mp_c_txn(5)" )
			)
			( signal "P3E_CPU1_PE3_MP_C_TXN<6>"
				( objectStatus "@baseboard_fab2_lib.baseboard_fab2(sch_1):p3e_cpu1_pe3_mp_c_txn(6)" )
			)
			( signal "P3E_CPU1_PE3_MP_C_TXN<7>"
				( objectStatus "@baseboard_fab2_lib.baseboard_fab2(sch_1):p3e_cpu1_pe3_mp_c_txn(7)" )
			)
			( signal "P3E_CPU1_PE3_MP_C_TXP<0>"
				( objectStatus "@baseboard_fab2_lib.baseboard_fab2(sch_1):p3e_cpu1_pe3_mp_c_txp(0)" )
			)
			( signal "P3E_CPU1_PE3_MP_C_TXP<1>"
				( objectStatus "@baseboard_fab2_lib.baseboard_fab2(sch_1):p3e_cpu1_pe3_mp_c_txp(1)" )
			)
			( signal "P3E_CPU1_PE3_MP_C_TXP<2>"
				( objectStatus "@baseboard_fab2_lib.baseboard_fab2(sch_1):p3e_cpu1_pe3_mp_c_txp(2)" )
			)
			( signal "P3E_CPU1_PE3_MP_C_TXP<3>"
				( objectStatus "@baseboard_fab2_lib.baseboard_fab2(sch_1):p3e_cpu1_pe3_mp_c_txp(3)" )
			)
			( signal "P3E_CPU1_PE3_MP_C_TXP<4>"
				( objectStatus "@baseboard_fab2_lib.baseboard_fab2(sch_1):p3e_cpu1_pe3_mp_c_txp(4)" )
			)
			( signal "P3E_CPU1_PE3_MP_C_TXP<5>"
				( objectStatus "@baseboard_fab2_lib.baseboard_fab2(sch_1):p3e_cpu1_pe3_mp_c_txp(5)" )
			)
			( signal "P3E_CPU1_PE3_MP_C_TXP<6>"
				( objectStatus "@baseboard_fab2_lib.baseboard_fab2(sch_1):p3e_cpu1_pe3_mp_c_txp(6)" )
			)
			( signal "P3E_CPU1_PE3_MP_C_TXP<7>"
				( objectStatus "@baseboard_fab2_lib.baseboard_fab2(sch_1):p3e_cpu1_pe3_mp_c_txp(7)" )
			)
			( signal "PWRGD_P12V_HSC_DLY"
				( objectStatus "@baseboard_fab2_lib.baseboard_fab2(sch_1):pwrgd_p12v_hsc_dly" )
			)
			( signal "RST_PCIE_MIDPLANE_N"
				( objectStatus "@baseboard_fab2_lib.baseboard_fab2(sch_1):rst_pcie_midplane_n" )
			)
			( signal "SPA_MID_DBG_RX_R"
				( objectStatus "@baseboard_fab2_lib.baseboard_fab2(sch_1):spa_mid_dbg_rx_r" )
			)
			( signal "SPA_MID_DBG_TX_R"
				( objectStatus "@baseboard_fab2_lib.baseboard_fab2(sch_1):spa_mid_dbg_tx_r" )
			)
			( signal "P3E_CPU1_PE3_MP_C_TXN<8>"
				( objectStatus "@baseboard_fab2_lib.baseboard_fab2(sch_1):p3e_cpu1_pe3_mp_c_txn(8)" )
			)
			( signal "P3E_CPU1_PE3_MP_C_TXN<9>"
				( objectStatus "@baseboard_fab2_lib.baseboard_fab2(sch_1):p3e_cpu1_pe3_mp_c_txn(9)" )
			)
			( signal "P3E_CPU1_PE3_MP_C_TXN<10>"
				( objectStatus "@baseboard_fab2_lib.baseboard_fab2(sch_1):p3e_cpu1_pe3_mp_c_txn(10)" )
			)
			( signal "P3E_CPU1_PE3_MP_C_TXN<11>"
				( objectStatus "@baseboard_fab2_lib.baseboard_fab2(sch_1):p3e_cpu1_pe3_mp_c_txn(11)" )
			)
			( signal "P3E_CPU1_PE3_MP_C_TXN<12>"
				( objectStatus "@baseboard_fab2_lib.baseboard_fab2(sch_1):p3e_cpu1_pe3_mp_c_txn(12)" )
			)
			( signal "P3E_CPU1_PE3_MP_C_TXN<13>"
				( objectStatus "@baseboard_fab2_lib.baseboard_fab2(sch_1):p3e_cpu1_pe3_mp_c_txn(13)" )
			)
			( signal "P3E_CPU1_PE3_MP_C_TXN<14>"
				( objectStatus "@baseboard_fab2_lib.baseboard_fab2(sch_1):p3e_cpu1_pe3_mp_c_txn(14)" )
			)
			( signal "P3E_CPU1_PE3_MP_C_TXN<15>"
				( objectStatus "@baseboard_fab2_lib.baseboard_fab2(sch_1):p3e_cpu1_pe3_mp_c_txn(15)" )
			)
			( signal "P3E_CPU1_PE3_MP_C_TXP<8>"
				( objectStatus "@baseboard_fab2_lib.baseboard_fab2(sch_1):p3e_cpu1_pe3_mp_c_txp(8)" )
			)
			( signal "P3E_CPU1_PE3_MP_C_TXP<9>"
				( objectStatus "@baseboard_fab2_lib.baseboard_fab2(sch_1):p3e_cpu1_pe3_mp_c_txp(9)" )
			)
			( signal "P3E_CPU1_PE3_MP_C_TXP<10>"
				( objectStatus "@baseboard_fab2_lib.baseboard_fab2(sch_1):p3e_cpu1_pe3_mp_c_txp(10)" )
			)
			( signal "P3E_CPU1_PE3_MP_C_TXP<11>"
				( objectStatus "@baseboard_fab2_lib.baseboard_fab2(sch_1):p3e_cpu1_pe3_mp_c_txp(11)" )
			)
			( signal "P3E_CPU1_PE3_MP_C_TXP<12>"
				( objectStatus "@baseboard_fab2_lib.baseboard_fab2(sch_1):p3e_cpu1_pe3_mp_c_txp(12)" )
			)
			( signal "P3E_CPU1_PE3_MP_C_TXP<13>"
				( objectStatus "@baseboard_fab2_lib.baseboard_fab2(sch_1):p3e_cpu1_pe3_mp_c_txp(13)" )
			)
			( signal "P3E_CPU1_PE3_MP_C_TXP<14>"
				( objectStatus "@baseboard_fab2_lib.baseboard_fab2(sch_1):p3e_cpu1_pe3_mp_c_txp(14)" )
			)
			( signal "P3E_CPU1_PE3_MP_C_TXP<15>"
				( objectStatus "@baseboard_fab2_lib.baseboard_fab2(sch_1):p3e_cpu1_pe3_mp_c_txp(15)" )
			)
			( signal "TP_FM_WAKE_N"
				( objectStatus "@baseboard_fab2_lib.baseboard_fab2(sch_1):tp_fm_wake_n" )
			)
			( signal "TP_IOA5"
				( objectStatus "@baseboard_fab2_lib.baseboard_fab2(sch_1):tp_ioa5" )
			)
			( signal "TP_IOE4"
				( objectStatus "@baseboard_fab2_lib.baseboard_fab2(sch_1):tp_ioe4" )
			)
			( signal "TP_IOF4"
				( objectStatus "@baseboard_fab2_lib.baseboard_fab2(sch_1):tp_iof4" )
			)
			( signal "TP_IOG3"
				( objectStatus "@baseboard_fab2_lib.baseboard_fab2(sch_1):tp_iog3" )
			)
			( signal "TP_IOH3"
				( objectStatus "@baseboard_fab2_lib.baseboard_fab2(sch_1):tp_ioh3" )
			)
			( signal "TP_IOH4"
				( objectStatus "@baseboard_fab2_lib.baseboard_fab2(sch_1):tp_ioh4" )
			)
			( signal "TP_IOI4"
				( objectStatus "@baseboard_fab2_lib.baseboard_fab2(sch_1):tp_ioi4" )
			)
			( signal "FM_PI7C9X1172_A0"
				( objectStatus "@baseboard_fab2_lib.baseboard_fab2(sch_1):fm_pi7c9x1172_a0" )
			)
			( signal "FM_PI7C9X1172_A1"
				( objectStatus "@baseboard_fab2_lib.baseboard_fab2(sch_1):fm_pi7c9x1172_a1" )
			)
			( signal "NC_PI7C9X1172_1"
				( objectStatus "@baseboard_fab2_lib.baseboard_fab2(sch_1):nc_pi7c9x1172_1" )
			)
			( signal "NC_PI7C9X1172_8"
				( objectStatus "@baseboard_fab2_lib.baseboard_fab2(sch_1):nc_pi7c9x1172_8" )
			)
			( signal "PU_PI7C9X1172_I2C_SPI_N"
				( objectStatus "@baseboard_fab2_lib.baseboard_fab2(sch_1):pu_pi7c9x1172_i2c_spi_n" )
			)
			( signal "SP1_HOST_BRIDGE_UART_RX"
				( objectStatus "@baseboard_fab2_lib.baseboard_fab2(sch_1):sp1_host_bridge_uart_rx" )
			)
			( signal "SP1_HOST_BRIDGE_UART_TX"
				( objectStatus "@baseboard_fab2_lib.baseboard_fab2(sch_1):sp1_host_bridge_uart_tx" )
			)
			( signal "TP_GPIO0_DSRB_N"
				( objectStatus "@baseboard_fab2_lib.baseboard_fab2(sch_1):tp_gpio0_dsrb_n" )
			)
			( signal "TP_GPIO1_DTRB_N"
				( objectStatus "@baseboard_fab2_lib.baseboard_fab2(sch_1):tp_gpio1_dtrb_n" )
			)
			( signal "TP_GPIO2_CDB_N"
				( objectStatus "@baseboard_fab2_lib.baseboard_fab2(sch_1):tp_gpio2_cdb_n" )
			)
			( signal "TP_GPIO3_RIB_N"
				( objectStatus "@baseboard_fab2_lib.baseboard_fab2(sch_1):tp_gpio3_rib_n" )
			)
			( signal "TP_GPIO4_DSRA_N"
				( objectStatus "@baseboard_fab2_lib.baseboard_fab2(sch_1):tp_gpio4_dsra_n" )
			)
			( signal "TP_GPIO5_DTRA_N"
				( objectStatus "@baseboard_fab2_lib.baseboard_fab2(sch_1):tp_gpio5_dtra_n" )
			)
			( signal "TP_GPIO6_CDA_N"
				( objectStatus "@baseboard_fab2_lib.baseboard_fab2(sch_1):tp_gpio6_cda_n" )
			)
			( signal "TP_GPIO7_RIA_N"
				( objectStatus "@baseboard_fab2_lib.baseboard_fab2(sch_1):tp_gpio7_ria_n" )
			)
			( signal "TP_PI7C9X1172_EN485_N"
				( objectStatus "@baseboard_fab2_lib.baseboard_fab2(sch_1):tp_pi7c9x1172_en485_n" )
			)
			( signal "TP_PI7C9X1172_ENIR_N"
				( objectStatus "@baseboard_fab2_lib.baseboard_fab2(sch_1):tp_pi7c9x1172_enir_n" )
			)
			( signal "TP_PI7C9X1172_RTSA_N"
				( objectStatus "@baseboard_fab2_lib.baseboard_fab2(sch_1):tp_pi7c9x1172_rtsa_n" )
			)
			( signal "TP_PI7C9X1172_RTSB_N"
				( objectStatus "@baseboard_fab2_lib.baseboard_fab2(sch_1):tp_pi7c9x1172_rtsb_n" )
			)
			( signal "TP_PI7C9X1172_SO"
				( objectStatus "@baseboard_fab2_lib.baseboard_fab2(sch_1):tp_pi7c9x1172_so" )
			)
			( signal "UART_BRIDGE_RXD5"
				( objectStatus "@baseboard_fab2_lib.baseboard_fab2(sch_1):uart_bridge_rxd5" )
			)
			( signal "UART_BRIDGE_TXD5"
				( objectStatus "@baseboard_fab2_lib.baseboard_fab2(sch_1):uart_bridge_txd5" )
			)
			( signal "XTAL_24MHZ_IN_R"
				( objectStatus "@baseboard_fab2_lib.baseboard_fab2(sch_1):xtal_24mhz_in_r" )
			)
			( signal "XTAL_24MHZ_OUT_R"
				( objectStatus "@baseboard_fab2_lib.baseboard_fab2(sch_1):xtal_24mhz_out_r" )
			)
			( signal "XTAL_24MHZ_PI7C9X1172_IN"
				( objectStatus "@baseboard_fab2_lib.baseboard_fab2(sch_1):xtal_24mhz_pi7c9x1172_in" )
			)
			( signal "XTAL_24MHZ_PI7C9X1172_OUT"
				( objectStatus "@baseboard_fab2_lib.baseboard_fab2(sch_1):xtal_24mhz_pi7c9x1172_out" )
			)
			( signal "IRQ_SPI_TPM_N_R"
				( objectStatus "@baseboard_fab2_lib.baseboard_fab2(sch_1):irq_spi_tpm_n_r" )
			)
			( signal "SPI_PCH_TPM_CLK_R"
				( objectStatus "@baseboard_fab2_lib.baseboard_fab2(sch_1):spi_pch_tpm_clk_r" )
			)
			( signal "SPI_PCH_TPM_CS_R_N"
				( objectStatus "@baseboard_fab2_lib.baseboard_fab2(sch_1):spi_pch_tpm_cs_r_n" )
			)
			( signal "SPI_PCH_TPM_MISO_R"
				( objectStatus "@baseboard_fab2_lib.baseboard_fab2(sch_1):spi_pch_tpm_miso_r" )
			)
			( signal "SPI_PCH_TPM_MOSI_R"
				( objectStatus "@baseboard_fab2_lib.baseboard_fab2(sch_1):spi_pch_tpm_mosi_r" )
			)
			( signal "FM_M2_DET_LVC3"
				( objectStatus "@baseboard_fab2_lib.baseboard_fab2(sch_1):fm_m2_det_lvc3" )
			)
			( signal "FM_M2_SSD_PEDET"
				( objectStatus "@baseboard_fab2_lib.baseboard_fab2(sch_1):fm_m2_ssd_pedet" )
			)
			( signal "NC_M2<0>"
				( objectStatus "@baseboard_fab2_lib.baseboard_fab2(sch_1):nc_m2(0)" )
			)
			( signal "NC_M2<1>"
				( objectStatus "@baseboard_fab2_lib.baseboard_fab2(sch_1):nc_m2(1)" )
			)
			( signal "NC_M2<2>"
				( objectStatus "@baseboard_fab2_lib.baseboard_fab2(sch_1):nc_m2(2)" )
			)
			( signal "NC_M2<3>"
				( objectStatus "@baseboard_fab2_lib.baseboard_fab2(sch_1):nc_m2(3)" )
			)
			( signal "NC_M2<4>"
				( objectStatus "@baseboard_fab2_lib.baseboard_fab2(sch_1):nc_m2(4)" )
			)
			( signal "NC_M2<5>"
				( objectStatus "@baseboard_fab2_lib.baseboard_fab2(sch_1):nc_m2(5)" )
			)
			( signal "NC_M2<6>"
				( objectStatus "@baseboard_fab2_lib.baseboard_fab2(sch_1):nc_m2(6)" )
			)
			( signal "NC_M2<7>"
				( objectStatus "@baseboard_fab2_lib.baseboard_fab2(sch_1):nc_m2(7)" )
			)
			( signal "NC_M2<8>"
				( objectStatus "@baseboard_fab2_lib.baseboard_fab2(sch_1):nc_m2(8)" )
			)
			( signal "NC_M2<9>"
				( objectStatus "@baseboard_fab2_lib.baseboard_fab2(sch_1):nc_m2(9)" )
			)
			( signal "NC_M2<10>"
				( objectStatus "@baseboard_fab2_lib.baseboard_fab2(sch_1):nc_m2(10)" )
			)
			( signal "NC_M2<11>"
				( objectStatus "@baseboard_fab2_lib.baseboard_fab2(sch_1):nc_m2(11)" )
			)
			( signal "NC_M2<12>"
				( objectStatus "@baseboard_fab2_lib.baseboard_fab2(sch_1):nc_m2(12)" )
			)
			( signal "NC_M2<13>"
				( objectStatus "@baseboard_fab2_lib.baseboard_fab2(sch_1):nc_m2(13)" )
			)
			( signal "NC_M2<14>"
				( objectStatus "@baseboard_fab2_lib.baseboard_fab2(sch_1):nc_m2(14)" )
			)
			( signal "NC_M2<15>"
				( objectStatus "@baseboard_fab2_lib.baseboard_fab2(sch_1):nc_m2(15)" )
			)
			( signal "NC_M2<16>"
				( objectStatus "@baseboard_fab2_lib.baseboard_fab2(sch_1):nc_m2(16)" )
			)
			( signal "NC_M2<17>"
				( objectStatus "@baseboard_fab2_lib.baseboard_fab2(sch_1):nc_m2(17)" )
			)
			( signal "NC_M2<18>"
				( objectStatus "@baseboard_fab2_lib.baseboard_fab2(sch_1):nc_m2(18)" )
			)
			( signal "P3E_PCH_M2_SATA6G_RX_R_DN"
				( objectStatus "@baseboard_fab2_lib.baseboard_fab2(sch_1):p3e_pch_m2_sata6g_rx_r_dn" )
			)
			( signal "P3E_PCH_M2_SATA6G_RX_R_DP"
				( objectStatus "@baseboard_fab2_lib.baseboard_fab2(sch_1):p3e_pch_m2_sata6g_rx_r_dp" )
			)
			( signal "P3E_PCH_M2_SATA6G_TX_R_DN"
				( objectStatus "@baseboard_fab2_lib.baseboard_fab2(sch_1):p3e_pch_m2_sata6g_tx_r_dn" )
			)
			( signal "P3E_PCH_M2_SATA6G_TX_R_DP"
				( objectStatus "@baseboard_fab2_lib.baseboard_fab2(sch_1):p3e_pch_m2_sata6g_tx_r_dp" )
			)
			( signal "P3E_PCH_M2_TX_C_DN<1>"
				( objectStatus "@baseboard_fab2_lib.baseboard_fab2(sch_1):p3e_pch_m2_tx_c_dn(1)" )
			)
			( signal "P3E_PCH_M2_TX_C_DN<2>"
				( objectStatus "@baseboard_fab2_lib.baseboard_fab2(sch_1):p3e_pch_m2_tx_c_dn(2)" )
			)
			( signal "P3E_PCH_M2_TX_C_DN<3>"
				( objectStatus "@baseboard_fab2_lib.baseboard_fab2(sch_1):p3e_pch_m2_tx_c_dn(3)" )
			)
			( signal "P3E_PCH_M2_TX_C_DP<1>"
				( objectStatus "@baseboard_fab2_lib.baseboard_fab2(sch_1):p3e_pch_m2_tx_c_dp(1)" )
			)
			( signal "P3E_PCH_M2_TX_C_DP<2>"
				( objectStatus "@baseboard_fab2_lib.baseboard_fab2(sch_1):p3e_pch_m2_tx_c_dp(2)" )
			)
			( signal "P3E_PCH_M2_TX_C_DP<3>"
				( objectStatus "@baseboard_fab2_lib.baseboard_fab2(sch_1):p3e_pch_m2_tx_c_dp(3)" )
			)
			( signal "PU_M2_CLK_REQ_N"
				( objectStatus "@baseboard_fab2_lib.baseboard_fab2(sch_1):pu_m2_clk_req_n" )
			)
			( signal "RST_PCIE_M2_DEV_N"
				( objectStatus "@baseboard_fab2_lib.baseboard_fab2(sch_1):rst_pcie_m2_dev_n" )
			)
			( signal "TP_LED_M2_ACT_N"
				( objectStatus "@baseboard_fab2_lib.baseboard_fab2(sch_1):tp_led_m2_act_n" )
			)
			( signal "TP_M2_32M_SUSCLK"
				( objectStatus "@baseboard_fab2_lib.baseboard_fab2(sch_1):tp_m2_32m_susclk" )
			)
			( signal "TP_M2_DEVSLP"
				( objectStatus "@baseboard_fab2_lib.baseboard_fab2(sch_1):tp_m2_devslp" )
			)
			( signal "FM_MEZZA_PRSNT1_N"
				( objectStatus "@baseboard_fab2_lib.baseboard_fab2(sch_1):fm_mezza_prsnt1_n" )
			)
			( signal "RMII_BMC_OCP_CRSDV_R"
				( objectStatus "@baseboard_fab2_lib.baseboard_fab2(sch_1):rmii_bmc_ocp_crsdv_r" )
			)
			( signal "RMII_BMC_OCP_RXD0_R"
				( objectStatus "@baseboard_fab2_lib.baseboard_fab2(sch_1):rmii_bmc_ocp_rxd0_r" )
			)
			( signal "RMII_BMC_OCP_RXD1_R"
				( objectStatus "@baseboard_fab2_lib.baseboard_fab2(sch_1):rmii_bmc_ocp_rxd1_r" )
			)
			( signal "RMII_BMC_OCP_RXER_R"
				( objectStatus "@baseboard_fab2_lib.baseboard_fab2(sch_1):rmii_bmc_ocp_rxer_r" )
			)
			( signal "RST_PCIE_CPU_DEV0_N"
				( objectStatus "@baseboard_fab2_lib.baseboard_fab2(sch_1):rst_pcie_cpu_dev0_n" )
			)
			( signal "RST_PCIE_CPU_DEV0_R_N"
				( objectStatus "@baseboard_fab2_lib.baseboard_fab2(sch_1):rst_pcie_cpu_dev0_r_n" )
			)
			( signal "FM_MEZZ_PRSNTB1_N"
				( objectStatus "@baseboard_fab2_lib.baseboard_fab2(sch_1):fm_mezz_prsntb1_n" )
			)
			( signal "RST_PCIE_CPU_DEV1_N"
				( objectStatus "@baseboard_fab2_lib.baseboard_fab2(sch_1):rst_pcie_cpu_dev1_n" )
			)
			( signal "RST_PCIE_CPU_DEV1_R_N"
				( objectStatus "@baseboard_fab2_lib.baseboard_fab2(sch_1):rst_pcie_cpu_dev1_r_n" )
			)
			( signal "RST_PCIE_CPU_DEV2_N"
				( objectStatus "@baseboard_fab2_lib.baseboard_fab2(sch_1):rst_pcie_cpu_dev2_n" )
			)
			( signal "RST_PCIE_CPU_DEV2_R_N"
				( objectStatus "@baseboard_fab2_lib.baseboard_fab2(sch_1):rst_pcie_cpu_dev2_r_n" )
			)
			( signal "RST_PCIE_CPU_DEV3_N"
				( objectStatus "@baseboard_fab2_lib.baseboard_fab2(sch_1):rst_pcie_cpu_dev3_n" )
			)
			( signal "RST_PCIE_CPU_DEV3_R_N"
				( objectStatus "@baseboard_fab2_lib.baseboard_fab2(sch_1):rst_pcie_cpu_dev3_r_n" )
			)
			( signal "TP_RSVD_B1"
				( objectStatus "@baseboard_fab2_lib.baseboard_fab2(sch_1):tp_rsvd_b1" )
			)
			( signal "KR_P0_OCP_RX_DN"
				( objectStatus "@baseboard_fab2_lib.baseboard_fab2(sch_1):kr_p0_ocp_rx_dn" )
			)
			( signal "KR_P0_OCP_RX_DP"
				( objectStatus "@baseboard_fab2_lib.baseboard_fab2(sch_1):kr_p0_ocp_rx_dp" )
			)
			( signal "KR_P1_OCP_RX_DN"
				( objectStatus "@baseboard_fab2_lib.baseboard_fab2(sch_1):kr_p1_ocp_rx_dn" )
			)
			( signal "KR_P1_OCP_RX_DP"
				( objectStatus "@baseboard_fab2_lib.baseboard_fab2(sch_1):kr_p1_ocp_rx_dp" )
			)
			( signal "KR_P2_OCP_RX_DN"
				( objectStatus "@baseboard_fab2_lib.baseboard_fab2(sch_1):kr_p2_ocp_rx_dn" )
			)
			( signal "KR_P2_OCP_RX_DP"
				( objectStatus "@baseboard_fab2_lib.baseboard_fab2(sch_1):kr_p2_ocp_rx_dp" )
			)
			( signal "KR_P3_OCP_RX_DN"
				( objectStatus "@baseboard_fab2_lib.baseboard_fab2(sch_1):kr_p3_ocp_rx_dn" )
			)
			( signal "KR_P3_OCP_RX_DP"
				( objectStatus "@baseboard_fab2_lib.baseboard_fab2(sch_1):kr_p3_ocp_rx_dp" )
			)
			( signal "TP_EXT_MDIO_I2C_SEL"
				( objectStatus "@baseboard_fab2_lib.baseboard_fab2(sch_1):tp_ext_mdio_i2c_sel" )
			)
			( signal "TP_RSVD<0>"
				( objectStatus "@baseboard_fab2_lib.baseboard_fab2(sch_1):tp_rsvd(0)" )
			)
			( signal "TP_SHARED_KR_MDC_0"
				( objectStatus "@baseboard_fab2_lib.baseboard_fab2(sch_1):tp_shared_kr_mdc_0" )
			)
			( signal "TP_SHARED_KR_MDIO_0"
				( objectStatus "@baseboard_fab2_lib.baseboard_fab2(sch_1):tp_shared_kr_mdio_0" )
			)
			( signal "FM_JTAG_PLD_EN_DEBUG"
				( objectStatus "@baseboard_fab2_lib.baseboard_fab2(sch_1):fm_jtag_pld_en_debug" )
			)
			( signal "JTAG_PLD_TCK"
				( objectStatus "@baseboard_fab2_lib.baseboard_fab2(sch_1):jtag_pld_tck" )
			)
			( signal "JTAG_PLD_TDI"
				( objectStatus "@baseboard_fab2_lib.baseboard_fab2(sch_1):jtag_pld_tdi" )
			)
			( signal "JTAG_PLD_TDO"
				( objectStatus "@baseboard_fab2_lib.baseboard_fab2(sch_1):jtag_pld_tdo" )
			)
			( signal "JTAG_PLD_TMS"
				( objectStatus "@baseboard_fab2_lib.baseboard_fab2(sch_1):jtag_pld_tms" )
			)
			( signal "JTAG_TCK"
				( objectStatus "@baseboard_fab2_lib.baseboard_fab2(sch_1):jtag_tck" )
			)
			( signal "JTAG_TCK_R"
				( objectStatus "@baseboard_fab2_lib.baseboard_fab2(sch_1):jtag_tck_r" )
			)
			( signal "JTAG_TDI"
				( objectStatus "@baseboard_fab2_lib.baseboard_fab2(sch_1):jtag_tdi" )
			)
			( signal "JTAG_TDI_R"
				( objectStatus "@baseboard_fab2_lib.baseboard_fab2(sch_1):jtag_tdi_r" )
			)
			( signal "JTAG_TDO"
				( objectStatus "@baseboard_fab2_lib.baseboard_fab2(sch_1):jtag_tdo" )
			)
			( signal "JTAG_TDO_R"
				( objectStatus "@baseboard_fab2_lib.baseboard_fab2(sch_1):jtag_tdo_r" )
			)
			( signal "JTAG_TMS"
				( objectStatus "@baseboard_fab2_lib.baseboard_fab2(sch_1):jtag_tms" )
			)
			( signal "JTAG_TMS_R"
				( objectStatus "@baseboard_fab2_lib.baseboard_fab2(sch_1):jtag_tms_r" )
			)
			( signal "JTAG_TRST_N"
				( objectStatus "@baseboard_fab2_lib.baseboard_fab2(sch_1):jtag_trst_n" )
			)
			( signal "P3V3_STBY_PLD_D"
				( attribute "VOLTAGE" "3.3"
					( Units "uVoltage" "V" 1.000000)
					( Status sAliasFlattened )
					( Origin gFrontEnd )
				)
				( objectStatus "@baseboard_fab2_lib.baseboard_fab2(sch_1):p3v3_stby_pld_d" )
			)
			( signal "FM_MEM_EVENT_FUNC"
				( objectStatus "@baseboard_fab2_lib.baseboard_fab2(sch_1):fm_mem_event_func" )
			)
			( signal "FM_PVCCIO_CPU0_EN"
				( objectStatus "@baseboard_fab2_lib.baseboard_fab2(sch_1):fm_pvccio_cpu0_en" )
			)
			( signal "FM_PVCCIO_CPU1_EN"
				( objectStatus "@baseboard_fab2_lib.baseboard_fab2(sch_1):fm_pvccio_cpu1_en" )
			)
			( signal "FM_PVCCIOMCP_CPU0_EN"
				( objectStatus "@baseboard_fab2_lib.baseboard_fab2(sch_1):fm_pvcciomcp_cpu0_en" )
			)
			( signal "FM_PVCCIOMCP_CPU1_EN"
				( objectStatus "@baseboard_fab2_lib.baseboard_fab2(sch_1):fm_pvcciomcp_cpu1_en" )
			)
			( signal "FM_PVCCMCP_CPU0_EN"
				( objectStatus "@baseboard_fab2_lib.baseboard_fab2(sch_1):fm_pvccmcp_cpu0_en" )
			)
			( signal "FM_PVCCMCP_CPU1_EN"
				( objectStatus "@baseboard_fab2_lib.baseboard_fab2(sch_1):fm_pvccmcp_cpu1_en" )
			)
			( signal "PU_RST_PERST_BIT0"
				( objectStatus "@baseboard_fab2_lib.baseboard_fab2(sch_1):pu_rst_perst_bit0" )
			)
			( signal "PWRGD_P5V"
				( objectStatus "@baseboard_fab2_lib.baseboard_fab2(sch_1):pwrgd_p5v" )
			)
			( signal "PWRGD_PVCCIN_CPU1"
				( objectStatus "@baseboard_fab2_lib.baseboard_fab2(sch_1):pwrgd_pvccin_cpu1" )
			)
			( signal "PWRGD_PVCCIOMCP_CPU0"
				( objectStatus "@baseboard_fab2_lib.baseboard_fab2(sch_1):pwrgd_pvcciomcp_cpu0" )
			)
			( signal "PWRGD_PVCCIOMCP_CPU1"
				( objectStatus "@baseboard_fab2_lib.baseboard_fab2(sch_1):pwrgd_pvcciomcp_cpu1" )
			)
			( signal "PWRGD_PVCCMCP_CPU0"
				( objectStatus "@baseboard_fab2_lib.baseboard_fab2(sch_1):pwrgd_pvccmcp_cpu0" )
			)
			( signal "PWRGD_PVCCMCP_CPU1"
				( objectStatus "@baseboard_fab2_lib.baseboard_fab2(sch_1):pwrgd_pvccmcp_cpu1" )
			)
			( signal "PWRGD_PVNN_P1V05_PCH"
				( objectStatus "@baseboard_fab2_lib.baseboard_fab2(sch_1):pwrgd_pvnn_p1v05_pch" )
			)
			( signal "PWRGD_PVPP_DEF"
				( objectStatus "@baseboard_fab2_lib.baseboard_fab2(sch_1):pwrgd_pvpp_def" )
			)
			( signal "PWRGD_PVPP_GHJ"
				( objectStatus "@baseboard_fab2_lib.baseboard_fab2(sch_1):pwrgd_pvpp_ghj" )
			)
			( signal "PWRGD_PVPP_KLM"
				( objectStatus "@baseboard_fab2_lib.baseboard_fab2(sch_1):pwrgd_pvpp_klm" )
			)
			( signal "PWRGD_PVSA_CPU0"
				( objectStatus "@baseboard_fab2_lib.baseboard_fab2(sch_1):pwrgd_pvsa_cpu0" )
			)
			( signal "PWRGD_PVSA_CPU1"
				( objectStatus "@baseboard_fab2_lib.baseboard_fab2(sch_1):pwrgd_pvsa_cpu1" )
			)
			( signal "PWRGD_PVTT_CPU1"
				( objectStatus "@baseboard_fab2_lib.baseboard_fab2(sch_1):pwrgd_pvtt_cpu1" )
			)
			( signal "RST_CPU0_LVC3_R1_N"
				( objectStatus "@baseboard_fab2_lib.baseboard_fab2(sch_1):rst_cpu0_lvc3_r1_n" )
			)
			( signal "RST_CPU1_LVC3_R1_N"
				( objectStatus "@baseboard_fab2_lib.baseboard_fab2(sch_1):rst_cpu1_lvc3_r1_n" )
			)
			( signal "RST_RSMRST_R_N"
				( objectStatus "@baseboard_fab2_lib.baseboard_fab2(sch_1):rst_rsmrst_r_n" )
			)
			( signal "TP_CPLD1_PB11B_PCLKC2_0"
				( objectStatus "@baseboard_fab2_lib.baseboard_fab2(sch_1):tp_cpld1_pb11b_pclkc2_0" )
			)
			( signal "TP_CPLD1_PB16A_PCLKT2_1"
				( objectStatus "@baseboard_fab2_lib.baseboard_fab2(sch_1):tp_cpld1_pb16a_pclkt2_1" )
			)
			( signal "TP_CPLD1_PB16B_PCLKC2_1"
				( objectStatus "@baseboard_fab2_lib.baseboard_fab2(sch_1):tp_cpld1_pb16b_pclkc2_1" )
			)
			( signal "TP_CPLD1_PB25B_SI_SISPI"
				( objectStatus "@baseboard_fab2_lib.baseboard_fab2(sch_1):tp_cpld1_pb25b_si_sispi" )
			)
			( signal "TP_CPLD1_PB5A_CSSPIN"
				( objectStatus "@baseboard_fab2_lib.baseboard_fab2(sch_1):tp_cpld1_pb5a_csspin" )
			)
			( signal "TP_CPLD1_PB8A_MCLK_CCLK"
				( objectStatus "@baseboard_fab2_lib.baseboard_fab2(sch_1):tp_cpld1_pb8a_mclk_cclk" )
			)
			( signal "TP_CPLD1_PB8B_SO_SPISO"
				( objectStatus "@baseboard_fab2_lib.baseboard_fab2(sch_1):tp_cpld1_pb8b_so_spiso" )
			)
			( signal "TP_CPLD1_PB8D"
				( objectStatus "@baseboard_fab2_lib.baseboard_fab2(sch_1):tp_cpld1_pb8d" )
			)
			( signal "TP_CPLD1_PL11A"
				( objectStatus "@baseboard_fab2_lib.baseboard_fab2(sch_1):tp_cpld1_pl11a" )
			)
			( signal "TP_CPLD1_PL1A_L_GPLLT_FB"
				( objectStatus "@baseboard_fab2_lib.baseboard_fab2(sch_1):tp_cpld1_pl1a_l_gpllt_fb" )
			)
			( signal "TP_CPLD1_PL1B_L_GPLLC_FB"
				( objectStatus "@baseboard_fab2_lib.baseboard_fab2(sch_1):tp_cpld1_pl1b_l_gpllc_fb" )
			)
			( signal "TP_CPLD1_PL2B_L_GPLLC_IN"
				( objectStatus "@baseboard_fab2_lib.baseboard_fab2(sch_1):tp_cpld1_pl2b_l_gpllc_in" )
			)
			( signal "TP_CPLD1_PL7D_PCLKT4_0"
				( objectStatus "@baseboard_fab2_lib.baseboard_fab2(sch_1):tp_cpld1_pl7d_pclkt4_0" )
			)
			( signal "FM_ADR_SMI_GPIO_R_N"
				( objectStatus "@baseboard_fab2_lib.baseboard_fab2(sch_1):fm_adr_smi_gpio_r_n" )
			)
			( signal "FM_P12V_MAIN_SW_EN"
				( objectStatus "@baseboard_fab2_lib.baseboard_fab2(sch_1):fm_p12v_main_sw_en" )
			)
			( signal "FM_P1V8MCP_CPU0_EN"
				( objectStatus "@baseboard_fab2_lib.baseboard_fab2(sch_1):fm_p1v8mcp_cpu0_en" )
			)
			( signal "FM_P1V8MCP_CPU1_EN"
				( objectStatus "@baseboard_fab2_lib.baseboard_fab2(sch_1):fm_p1v8mcp_cpu1_en" )
			)
			( signal "FM_P3V3_CPLD_EN"
				( objectStatus "@baseboard_fab2_lib.baseboard_fab2(sch_1):fm_p3v3_cpld_en" )
			)
			( signal "FM_PLD_DEBUG_MODE_N"
				( objectStatus "@baseboard_fab2_lib.baseboard_fab2(sch_1):fm_pld_debug_mode_n" )
			)
			( signal "FM_PVCCIN_PVCCSA_CPU0_EN_LVC1"
				( objectStatus "@baseboard_fab2_lib.baseboard_fab2(sch_1):fm_pvccin_pvccsa_cpu0_en_lvc1" )
			)
			( signal "FM_PVCCIN_PVCCSA_CPU1_EN_LVC1"
				( objectStatus "@baseboard_fab2_lib.baseboard_fab2(sch_1):fm_pvccin_pvccsa_cpu1_en_lvc1" )
			)
			( signal "FM_PVDDQ_ABC_EN"
				( objectStatus "@baseboard_fab2_lib.baseboard_fab2(sch_1):fm_pvddq_abc_en" )
			)
			( signal "FM_PVDDQ_DEF_EN"
				( objectStatus "@baseboard_fab2_lib.baseboard_fab2(sch_1):fm_pvddq_def_en" )
			)
			( signal "FM_PVDDQ_GHJ_EN"
				( objectStatus "@baseboard_fab2_lib.baseboard_fab2(sch_1):fm_pvddq_ghj_en" )
			)
			( signal "FM_PVDDQ_KLM_EN"
				( objectStatus "@baseboard_fab2_lib.baseboard_fab2(sch_1):fm_pvddq_klm_en" )
			)
			( signal "FM_PVPP_CPU0_EN"
				( objectStatus "@baseboard_fab2_lib.baseboard_fab2(sch_1):fm_pvpp_cpu0_en" )
			)
			( signal "FM_PVPP_CPU1_EN"
				( objectStatus "@baseboard_fab2_lib.baseboard_fab2(sch_1):fm_pvpp_cpu1_en" )
			)
			( signal "FM_UV_ADR_TRIGGER_N"
				( objectStatus "@baseboard_fab2_lib.baseboard_fab2(sch_1):fm_uv_adr_trigger_n" )
			)
			( signal "PU_FAB2_MARKER_CPLD"
				( objectStatus "@baseboard_fab2_lib.baseboard_fab2(sch_1):pu_fab2_marker_cpld" )
			)
			( signal "PU_RST_PERST_BIT1"
				( objectStatus "@baseboard_fab2_lib.baseboard_fab2(sch_1):pu_rst_perst_bit1" )
			)
			( signal "PU_THERMTRIP_FORCE_N"
				( objectStatus "@baseboard_fab2_lib.baseboard_fab2(sch_1):pu_thermtrip_force_n" )
			)
			( signal "PWRGD_P12V_MAIN"
				( objectStatus "@baseboard_fab2_lib.baseboard_fab2(sch_1):pwrgd_p12v_main" )
			)
			( signal "PWRGD_P1V26_BMC_STBY"
				( objectStatus "@baseboard_fab2_lib.baseboard_fab2(sch_1):pwrgd_p1v26_bmc_stby" )
			)
			( signal "PWRGD_P1V8MCP_CPU0"
				( objectStatus "@baseboard_fab2_lib.baseboard_fab2(sch_1):pwrgd_p1v8mcp_cpu0" )
			)
			( signal "PWRGD_P1V8MCP_CPU1"
				( objectStatus "@baseboard_fab2_lib.baseboard_fab2(sch_1):pwrgd_p1v8mcp_cpu1" )
			)
			( signal "PWRGD_PVCCIO_CPU1"
				( objectStatus "@baseboard_fab2_lib.baseboard_fab2(sch_1):pwrgd_pvccio_cpu1" )
			)
			( signal "PWRGD_PVTT_CPU0"
				( objectStatus "@baseboard_fab2_lib.baseboard_fab2(sch_1):pwrgd_pvtt_cpu0" )
			)
			( signal "SGPIO_BMC_DIN_R"
				( objectStatus "@baseboard_fab2_lib.baseboard_fab2(sch_1):sgpio_bmc_din_r" )
			)
			( signal "TP_CPLD1_PR10C"
				( objectStatus "@baseboard_fab2_lib.baseboard_fab2(sch_1):tp_cpld1_pr10c" )
			)
			( signal "TP_CPLD1_PR11B"
				( objectStatus "@baseboard_fab2_lib.baseboard_fab2(sch_1):tp_cpld1_pr11b" )
			)
			( signal "TP_CPLD1_PR12D"
				( objectStatus "@baseboard_fab2_lib.baseboard_fab2(sch_1):tp_cpld1_pr12d" )
			)
			( signal "TP_CPLD1_PR7A_PCLKT1_0"
				( objectStatus "@baseboard_fab2_lib.baseboard_fab2(sch_1):tp_cpld1_pr7a_pclkt1_0" )
			)
			( signal "TP_CPLD1_PR7B_PCLKC1_0"
				( objectStatus "@baseboard_fab2_lib.baseboard_fab2(sch_1):tp_cpld1_pr7b_pclkc1_0" )
			)
			( signal "TP_CPLD1_PR7C"
				( objectStatus "@baseboard_fab2_lib.baseboard_fab2(sch_1):tp_cpld1_pr7c" )
			)
			( signal "TP_CPLD1_PR7D"
				( objectStatus "@baseboard_fab2_lib.baseboard_fab2(sch_1):tp_cpld1_pr7d" )
			)
			( signal "TP_CPLD1_PR9A"
				( objectStatus "@baseboard_fab2_lib.baseboard_fab2(sch_1):tp_cpld1_pr9a" )
			)
			( signal "TP_CPLD1_PR9C"
				( objectStatus "@baseboard_fab2_lib.baseboard_fab2(sch_1):tp_cpld1_pr9c" )
			)
			( signal "TP_CPLD1_PR9D"
				( objectStatus "@baseboard_fab2_lib.baseboard_fab2(sch_1):tp_cpld1_pr9d" )
			)
			( signal "TP_CPLD1_PT11A"
				( objectStatus "@baseboard_fab2_lib.baseboard_fab2(sch_1):tp_cpld1_pt11a" )
			)
			( signal "TP_CPLD1_PT11B"
				( objectStatus "@baseboard_fab2_lib.baseboard_fab2(sch_1):tp_cpld1_pt11b" )
			)
			( signal "TP_CPLD1_PT13A"
				( objectStatus "@baseboard_fab2_lib.baseboard_fab2(sch_1):tp_cpld1_pt13a" )
			)
			( signal "TP_CPLD1_PT16B"
				( objectStatus "@baseboard_fab2_lib.baseboard_fab2(sch_1):tp_cpld1_pt16b" )
			)
			( signal "TP_CPLD1_PT17B_PCLKC0_1"
				( objectStatus "@baseboard_fab2_lib.baseboard_fab2(sch_1):tp_cpld1_pt17b_pclkc0_1" )
			)
			( signal "TP_CPLD1_PT17C"
				( objectStatus "@baseboard_fab2_lib.baseboard_fab2(sch_1):tp_cpld1_pt17c" )
			)
			( signal "TP_CPLD1_PT19D"
				( objectStatus "@baseboard_fab2_lib.baseboard_fab2(sch_1):tp_cpld1_pt19d" )
			)
			( signal "TP_CPLD1_PT20A"
				( objectStatus "@baseboard_fab2_lib.baseboard_fab2(sch_1):tp_cpld1_pt20a" )
			)
			( signal "TP_CPLD1_PT20B"
				( objectStatus "@baseboard_fab2_lib.baseboard_fab2(sch_1):tp_cpld1_pt20b" )
			)
			( signal "TP_CPLD1_PT20D_PROGRAMN"
				( objectStatus "@baseboard_fab2_lib.baseboard_fab2(sch_1):tp_cpld1_pt20d_programn" )
			)
			( signal "TP_CPLD1_PT22C"
				( objectStatus "@baseboard_fab2_lib.baseboard_fab2(sch_1):tp_cpld1_pt22c" )
			)
			( signal "TP_CPLD1_PT22D"
				( objectStatus "@baseboard_fab2_lib.baseboard_fab2(sch_1):tp_cpld1_pt22d" )
			)
			( signal "TP_CPLD1_PT24B"
				( objectStatus "@baseboard_fab2_lib.baseboard_fab2(sch_1):tp_cpld1_pt24b" )
			)
			( signal "TP_CPLD1_PT24C_INITN"
				( objectStatus "@baseboard_fab2_lib.baseboard_fab2(sch_1):tp_cpld1_pt24c_initn" )
			)
			( signal "TP_CPLD1_PT24D_DONE"
				( objectStatus "@baseboard_fab2_lib.baseboard_fab2(sch_1):tp_cpld1_pt24d_done" )
			)
			( signal "NC_CPLD1"
				( objectStatus "@baseboard_fab2_lib.baseboard_fab2(sch_1):nc_cpld1" )
			)
			( signal "VR_PVCCIOMCP_CPU1_XADDR1"
				( objectStatus "@baseboard_fab2_lib.baseboard_fab2(sch_1):vr_pvcciomcp_cpu1_xaddr1" )
			)
			( signal "VR_PVCCMCP_CPU1_XADDR2"
				( objectStatus "@baseboard_fab2_lib.baseboard_fab2(sch_1):vr_pvccmcp_cpu1_xaddr2" )
			)
			( signal "VR_PVCCIOMCP_CPU0_XADDR1"
				( objectStatus "@baseboard_fab2_lib.baseboard_fab2(sch_1):vr_pvcciomcp_cpu0_xaddr1" )
			)
			( signal "VR_PVCCMCP_CPU0_XADDR2"
				( objectStatus "@baseboard_fab2_lib.baseboard_fab2(sch_1):vr_pvccmcp_cpu0_xaddr2" )
			)
			( signal "A_ADM1085_CEXT"
				( objectStatus "@baseboard_fab2_lib.baseboard_fab2(sch_1):a_adm1085_cext" )
			)
			( signal "A_PG_P12V_MAIN"
				( objectStatus "@baseboard_fab2_lib.baseboard_fab2(sch_1):a_pg_p12v_main" )
			)
			( signal "A_PG_P5V"
				( objectStatus "@baseboard_fab2_lib.baseboard_fab2(sch_1):a_pg_p5v" )
			)
			( signal "P3V_BAT_SOURCE"
				( attribute "VOLTAGE" "+3 V"
					( Units "uVoltage" "V" 1.000000)
					( Status sAliasFlattened )
					( Origin gFrontEnd )
				)
				( objectStatus "@baseboard_fab2_lib.baseboard_fab2(sch_1):p3v_bat_source" )
			)
			( signal "PWRGD_P12V_HSC"
				( objectStatus "@baseboard_fab2_lib.baseboard_fab2(sch_1):pwrgd_p12v_hsc" )
			)
			( signal "PWRGD_P12V_HSC_DLY_R"
				( objectStatus "@baseboard_fab2_lib.baseboard_fab2(sch_1):pwrgd_p12v_hsc_dly_r" )
			)
			( signal "PWRGD_P12V_MAIN_R"
				( objectStatus "@baseboard_fab2_lib.baseboard_fab2(sch_1):pwrgd_p12v_main_r" )
			)
			( signal "PWRGD_P3V3_R1"
				( objectStatus "@baseboard_fab2_lib.baseboard_fab2(sch_1):pwrgd_p3v3_r1" )
			)
			( signal "PWRGD_P5V_N"
				( objectStatus "@baseboard_fab2_lib.baseboard_fab2(sch_1):pwrgd_p5v_n" )
			)
			( signal "PWRGD_P5V_R"
				( objectStatus "@baseboard_fab2_lib.baseboard_fab2(sch_1):pwrgd_p5v_r" )
			)
			( signal "VSENSE_P12V_ADM1085"
				( objectStatus "@baseboard_fab2_lib.baseboard_fab2(sch_1):vsense_p12v_adm1085" )
			)
			( signal "VR_PVDDQ_ABC_AIINSEN"
				( objectStatus "@baseboard_fab2_lib.baseboard_fab2(sch_1):vr_pvddq_abc_aiinsen" )
			)
			( signal "VR_PVDDQ_ABC_AIINSEN_R"
				( objectStatus "@baseboard_fab2_lib.baseboard_fab2(sch_1):vr_pvddq_abc_aiinsen_r" )
			)
			( signal "VR_PVDDQ_DEF_AIINSEN"
				( objectStatus "@baseboard_fab2_lib.baseboard_fab2(sch_1):vr_pvddq_def_aiinsen" )
			)
			( signal "VR_PVDDQ_DEF_AIINSEN_R"
				( objectStatus "@baseboard_fab2_lib.baseboard_fab2(sch_1):vr_pvddq_def_aiinsen_r" )
			)
			( signal "VR_PVDDQ_GHJ_AIINSEN"
				( objectStatus "@baseboard_fab2_lib.baseboard_fab2(sch_1):vr_pvddq_ghj_aiinsen" )
			)
			( signal "VR_PVDDQ_GHJ_AIINSEN_R"
				( objectStatus "@baseboard_fab2_lib.baseboard_fab2(sch_1):vr_pvddq_ghj_aiinsen_r" )
			)
			( signal "VR_PVDDQ_KLM_AIINSEN"
				( objectStatus "@baseboard_fab2_lib.baseboard_fab2(sch_1):vr_pvddq_klm_aiinsen" )
			)
			( signal "VR_PVDDQ_KLM_AIINSEN_R"
				( objectStatus "@baseboard_fab2_lib.baseboard_fab2(sch_1):vr_pvddq_klm_aiinsen_r" )
			)
			( signal "P12V_FAN_SWITCH_G"
				( attribute "VOLTAGE" "+5V"
					( Units "uVoltage" "V" 1.000000)
					( Status sAliasFlattened )
					( Origin gFrontEnd )
				)
				( objectStatus "@baseboard_fab2_lib.baseboard_fab2(sch_1):p12v_fan_switch_g" )
			)
			( signal "P12V_SWITCH_G"
				( attribute "VOLTAGE" "+3.3V"
					( Units "uVoltage" "V" 1.000000)
					( Status sAliasFlattened )
					( Origin gFrontEnd )
				)
				( objectStatus "@baseboard_fab2_lib.baseboard_fab2(sch_1):p12v_switch_g" )
			)
			( signal "P3V3_SWITCH_G"
				( attribute "VOLTAGE" "3.3"
					( Units "uVoltage" "V" 1.000000)
					( Status sAliasFlattened )
					( Origin gFrontEnd )
				)
				( objectStatus "@baseboard_fab2_lib.baseboard_fab2(sch_1):p3v3_switch_g" )
			)
			( signal "P5V_SWITCH_G"
				( attribute "VOLTAGE" "+5V"
					( Units "uVoltage" "V" 1.000000)
					( Status sAliasFlattened )
					( Origin gFrontEnd )
				)
				( objectStatus "@baseboard_fab2_lib.baseboard_fab2(sch_1):p5v_switch_g" )
			)
			( signal "TP_SLG55021_P12V_FAN_8"
				( objectStatus "@baseboard_fab2_lib.baseboard_fab2(sch_1):tp_slg55021_p12v_fan_8" )
			)
			( signal "TP_SLG55021_P12V_MAIN_8"
				( objectStatus "@baseboard_fab2_lib.baseboard_fab2(sch_1):tp_slg55021_p12v_main_8" )
			)
			( signal "TP_SLG55021_P3V3_8"
				( objectStatus "@baseboard_fab2_lib.baseboard_fab2(sch_1):tp_slg55021_p3v3_8" )
			)
			( signal "TP_SLG55021_P5V_8"
				( objectStatus "@baseboard_fab2_lib.baseboard_fab2(sch_1):tp_slg55021_p5v_8" )
			)
			( signal "A_HSC_CSOUT"
				( objectStatus "@baseboard_fab2_lib.baseboard_fab2(sch_1):a_hsc_csout" )
			)
			( signal "A_HSC_GATE"
				( objectStatus "@baseboard_fab2_lib.baseboard_fab2(sch_1):a_hsc_gate" )
			)
			( signal "A_HSC_HIGH_EN"
				( objectStatus "@baseboard_fab2_lib.baseboard_fab2(sch_1):a_hsc_high_en" )
			)
			( signal "A_HSC_HSN"
				( objectStatus "@baseboard_fab2_lib.baseboard_fab2(sch_1):a_hsc_hsn" )
			)
			( signal "A_HSC_HSP"
				( objectStatus "@baseboard_fab2_lib.baseboard_fab2(sch_1):a_hsc_hsp" )
			)
			( signal "A_HSC_ISET"
				( objectStatus "@baseboard_fab2_lib.baseboard_fab2(sch_1):a_hsc_iset" )
			)
			( signal "A_HSC_ISET_S"
				( objectStatus "@baseboard_fab2_lib.baseboard_fab2(sch_1):a_hsc_iset_s" )
			)
			( signal "A_HSC_ISET_S2"
				( objectStatus "@baseboard_fab2_lib.baseboard_fab2(sch_1):a_hsc_iset_s2" )
			)
			( signal "A_HSC_ISTART"
				( objectStatus "@baseboard_fab2_lib.baseboard_fab2(sch_1):a_hsc_istart" )
			)
			( signal "A_HSC_LOW_EN"
				( objectStatus "@baseboard_fab2_lib.baseboard_fab2(sch_1):a_hsc_low_en" )
			)
			( signal "A_HSC_MON"
				( objectStatus "@baseboard_fab2_lib.baseboard_fab2(sch_1):a_hsc_mon" )
			)
			( signal "A_HSC_MOP"
				( objectStatus "@baseboard_fab2_lib.baseboard_fab2(sch_1):a_hsc_mop" )
			)
			( signal "A_HSC_OCP_SEL"
				( objectStatus "@baseboard_fab2_lib.baseboard_fab2(sch_1):a_hsc_ocp_sel" )
			)
			( signal "A_HSC_OV"
				( objectStatus "@baseboard_fab2_lib.baseboard_fab2(sch_1):a_hsc_ov" )
			)
			( signal "A_HSC_PSET"
				( objectStatus "@baseboard_fab2_lib.baseboard_fab2(sch_1):a_hsc_pset" )
			)
			( signal "A_HSC_PWGIN"
				( objectStatus "@baseboard_fab2_lib.baseboard_fab2(sch_1):a_hsc_pwgin" )
			)
			( signal "A_HSC_TEMP"
				( objectStatus "@baseboard_fab2_lib.baseboard_fab2(sch_1):a_hsc_temp" )
			)
			( signal "A_HSC_TIMER"
				( objectStatus "@baseboard_fab2_lib.baseboard_fab2(sch_1):a_hsc_timer" )
			)
			( signal "A_HSC_UV"
				( objectStatus "@baseboard_fab2_lib.baseboard_fab2(sch_1):a_hsc_uv" )
			)
			( signal "A_HSC_VCAP"
				( objectStatus "@baseboard_fab2_lib.baseboard_fab2(sch_1):a_hsc_vcap" )
			)
			( signal "A_HSC_VOUT"
				( objectStatus "@baseboard_fab2_lib.baseboard_fab2(sch_1):a_hsc_vout" )
			)
			( signal "AGND_HSC"
				( attribute "VOLTAGE" "0"
					( Units "uVoltage" "V" 1.000000)
					( Status sAliasFlattened )
					( Origin gFrontEnd )
				)
				( objectStatus "@baseboard_fab2_lib.baseboard_fab2(sch_1):agnd_hsc" )
			)
			( signal "FM_P12V_HSC_ADR1"
				( objectStatus "@baseboard_fab2_lib.baseboard_fab2(sch_1):fm_p12v_hsc_adr1" )
			)
			( signal "FM_P12V_HSC_ADR2"
				( objectStatus "@baseboard_fab2_lib.baseboard_fab2(sch_1):fm_p12v_hsc_adr2" )
			)
			( signal "IRQ_HSC_FAULT_R_N"
				( objectStatus "@baseboard_fab2_lib.baseboard_fab2(sch_1):irq_hsc_fault_r_n" )
			)
			( signal "P12V_HSC_VCC"
				( attribute "VOLTAGE" "+12V"
					( Units "uVoltage" "V" 1.000000)
					( Status sAliasFlattened )
					( Origin gFrontEnd )
				)
				( objectStatus "@baseboard_fab2_lib.baseboard_fab2(sch_1):p12v_hsc_vcc" )
			)
			( signal "PD_HSC_RETRY_N"
				( objectStatus "@baseboard_fab2_lib.baseboard_fab2(sch_1):pd_hsc_retry_n" )
			)
			( signal "PWRGD_P12V_R"
				( objectStatus "@baseboard_fab2_lib.baseboard_fab2(sch_1):pwrgd_p12v_r" )
			)
			( signal "SMB_3V3SB_HSC_SCL_R"
				( objectStatus "@baseboard_fab2_lib.baseboard_fab2(sch_1):smb_3v3sb_hsc_scl_r" )
			)
			( signal "SMB_3V3SB_HSC_SDA_R"
				( objectStatus "@baseboard_fab2_lib.baseboard_fab2(sch_1):smb_3v3sb_hsc_sda_r" )
			)
			( signal "TP_HSC_ALERT2_N"
				( objectStatus "@baseboard_fab2_lib.baseboard_fab2(sch_1):tp_hsc_alert2_n" )
			)
			( signal "TP_HSC_MCLK"
				( objectStatus "@baseboard_fab2_lib.baseboard_fab2(sch_1):tp_hsc_mclk" )
			)
			( signal "TP_HSC_MDAT"
				( objectStatus "@baseboard_fab2_lib.baseboard_fab2(sch_1):tp_hsc_mdat" )
			)
			( signal "TP_HSC_SPISSN"
				( objectStatus "@baseboard_fab2_lib.baseboard_fab2(sch_1):tp_hsc_spissn" )
			)
			( signal "A_HSC_C"
				( objectStatus "@baseboard_fab2_lib.baseboard_fab2(sch_1):a_hsc_c" )
			)
			( signal "A_HSC_GATE1_R"
				( objectStatus "@baseboard_fab2_lib.baseboard_fab2(sch_1):a_hsc_gate1_r" )
			)
			( signal "A_HSC_GATE2_R"
				( objectStatus "@baseboard_fab2_lib.baseboard_fab2(sch_1):a_hsc_gate2_r" )
			)
			( signal "A_HSC_GATE3_R"
				( objectStatus "@baseboard_fab2_lib.baseboard_fab2(sch_1):a_hsc_gate3_r" )
			)
			( signal "A_HSC_HIGH"
				( objectStatus "@baseboard_fab2_lib.baseboard_fab2(sch_1):a_hsc_high" )
			)
			( signal "A_HSC_INAP"
				( objectStatus "@baseboard_fab2_lib.baseboard_fab2(sch_1):a_hsc_inap" )
			)
			( signal "A_HSC_LOW"
				( objectStatus "@baseboard_fab2_lib.baseboard_fab2(sch_1):a_hsc_low" )
			)
			( signal "A_HSC_LOW_DRAIN"
				( objectStatus "@baseboard_fab2_lib.baseboard_fab2(sch_1):a_hsc_low_drain" )
			)
			( signal "A_HSC_LOW_GATE"
				( objectStatus "@baseboard_fab2_lib.baseboard_fab2(sch_1):a_hsc_low_gate" )
			)
			( signal "A_HSC_TIMER_R"
				( objectStatus "@baseboard_fab2_lib.baseboard_fab2(sch_1):a_hsc_timer_r" )
			)
			( signal "A_P12V_STBY_ADR_TRIGGER"
				( objectStatus "@baseboard_fab2_lib.baseboard_fab2(sch_1):a_p12v_stby_adr_trigger" )
			)
			( signal "A_P12V_STBY_FP_TRIGGER"
				( objectStatus "@baseboard_fab2_lib.baseboard_fab2(sch_1):a_p12v_stby_fp_trigger" )
			)
			( signal "A_P12V_STBY_FPH_GATE"
				( objectStatus "@baseboard_fab2_lib.baseboard_fab2(sch_1):a_p12v_stby_fph_gate" )
			)
			( signal "FM_OC_DETECT_EN"
				( objectStatus "@baseboard_fab2_lib.baseboard_fab2(sch_1):fm_oc_detect_en" )
			)
			( signal "P12V_HSC_SENN0"
				( attribute "VOLTAGE" "+12V"
					( Units "uVoltage" "V" 1.000000)
					( Status sAliasFlattened )
					( Origin gFrontEnd )
				)
				( objectStatus "@baseboard_fab2_lib.baseboard_fab2(sch_1):p12v_hsc_senn0" )
			)
			( signal "P12V_HSC_SENN1"
				( attribute "VOLTAGE" "+12V"
					( Units "uVoltage" "V" 1.000000)
					( Status sAliasFlattened )
					( Origin gFrontEnd )
				)
				( objectStatus "@baseboard_fab2_lib.baseboard_fab2(sch_1):p12v_hsc_senn1" )
			)
			( signal "P12V_HSC_SENP0"
				( attribute "VOLTAGE" "+12V"
					( Units "uVoltage" "V" 1.000000)
					( Status sAliasFlattened )
					( Origin gFrontEnd )
				)
				( objectStatus "@baseboard_fab2_lib.baseboard_fab2(sch_1):p12v_hsc_senp0" )
			)
			( signal "P12V_HSC_SENP1"
				( attribute "VOLTAGE" "+12V"
					( Units "uVoltage" "V" 1.000000)
					( Status sAliasFlattened )
					( Origin gFrontEnd )
				)
				( objectStatus "@baseboard_fab2_lib.baseboard_fab2(sch_1):p12v_hsc_senp1" )
			)
			( signal "P12V_MB0_SW"
				( attribute "VOLTAGE" "+12V"
					( Units "uVoltage" "V" 1.000000)
					( Status sAliasFlattened )
					( Origin gFrontEnd )
				)
				( objectStatus "@baseboard_fab2_lib.baseboard_fab2(sch_1):p12v_mb0_sw" )
			)
			( signal "A_TSENSE_PVCCIN_CPU0"
				( objectStatus "@baseboard_fab2_lib.baseboard_fab2(sch_1):a_tsense_pvccin_cpu0" )
			)
			( signal "A_TSENSE_PVSA_CPU0"
				( objectStatus "@baseboard_fab2_lib.baseboard_fab2(sch_1):a_tsense_pvsa_cpu0" )
			)
			( signal "IRQ_PVCCIN_CPU0_VRHOT_LVC3_R_N"
				( objectStatus "@baseboard_fab2_lib.baseboard_fab2(sch_1):irq_pvccin_cpu0_vrhot_lvc3_r_n" )
			)
			( signal "ISENSE_PVCCIN_CPU0_PH1_IMON"
				( objectStatus "@baseboard_fab2_lib.baseboard_fab2(sch_1):isense_pvccin_cpu0_ph1_imon" )
			)
			( signal "ISENSE_PVCCIN_CPU0_PH2_IMON"
				( objectStatus "@baseboard_fab2_lib.baseboard_fab2(sch_1):isense_pvccin_cpu0_ph2_imon" )
			)
			( signal "ISENSE_PVCCIN_CPU0_PH3_IMON"
				( objectStatus "@baseboard_fab2_lib.baseboard_fab2(sch_1):isense_pvccin_cpu0_ph3_imon" )
			)
			( signal "ISENSE_PVCCIN_CPU0_PH4_IMON"
				( objectStatus "@baseboard_fab2_lib.baseboard_fab2(sch_1):isense_pvccin_cpu0_ph4_imon" )
			)
			( signal "ISENSE_PVCCIN_CPU0_PH5_IMON"
				( objectStatus "@baseboard_fab2_lib.baseboard_fab2(sch_1):isense_pvccin_cpu0_ph5_imon" )
			)
			( signal "ISENSE_PVSA_CPU0_IMON"
				( objectStatus "@baseboard_fab2_lib.baseboard_fab2(sch_1):isense_pvsa_cpu0_imon" )
			)
			( signal "PU_VR_PVCCIN_CPU0_FLT1_SMBALT_N"
				( objectStatus "@baseboard_fab2_lib.baseboard_fab2(sch_1):pu_vr_pvccin_cpu0_flt1_smbalt_n_imon" )
			)
			( signal "PU_VR_PVCCIN_CPU0_IMON"
				( objectStatus "@baseboard_fab2_lib.baseboard_fab2(sch_1):pu_vr_pvccin_cpu0_imon" )
			)
			( signal "PVCCIN_PVSA_CPU0_IINSEN"
				( attribute "VOLTAGE" "+3.3V"
					( Units "uVoltage" "V" 1.000000)
					( Status sAliasFlattened )
					( Origin gFrontEnd )
				)
				( objectStatus "@baseboard_fab2_lib.baseboard_fab2(sch_1):pvccin_pvsa_cpu0_iinsen" )
			)
			( signal "PWRGD_PVSA_CPU0_R"
				( objectStatus "@baseboard_fab2_lib.baseboard_fab2(sch_1):pwrgd_pvsa_cpu0_r" )
			)
			( signal "SMB_VR_SCL_R"
				( objectStatus "@baseboard_fab2_lib.baseboard_fab2(sch_1):smb_vr_scl_r" )
			)
			( signal "SMB_VR_SDA_R"
				( objectStatus "@baseboard_fab2_lib.baseboard_fab2(sch_1):smb_vr_sda_r" )
			)
			( signal "SVID_VALERT_VCCIN_CPU0"
				( objectStatus "@baseboard_fab2_lib.baseboard_fab2(sch_1):svid_valert_vccin_cpu0" )
			)
			( signal "SVID_VCLK_PVCCIN_CPU0"
				( objectStatus "@baseboard_fab2_lib.baseboard_fab2(sch_1):svid_vclk_pvccin_cpu0" )
			)
			( signal "SVID_VDIO_PVCCIN_CPU0"
				( objectStatus "@baseboard_fab2_lib.baseboard_fab2(sch_1):svid_vdio_pvccin_cpu0" )
			)
			( signal "TP_PVCCIN_CPU0_AIREF6"
				( objectStatus "@baseboard_fab2_lib.baseboard_fab2(sch_1):tp_pvccin_cpu0_airef6" )
			)
			( signal "TP_PVCCIN_CPU0_AISEN6"
				( objectStatus "@baseboard_fab2_lib.baseboard_fab2(sch_1):tp_pvccin_cpu0_aisen6" )
			)
			( signal "TP_PVCCIN_CPU0_APWM6"
				( objectStatus "@baseboard_fab2_lib.baseboard_fab2(sch_1):tp_pvccin_cpu0_apwm6" )
			)
			( signal "TP_PVCCIN_CPU0_FAULT1_20"
				( objectStatus "@baseboard_fab2_lib.baseboard_fab2(sch_1):tp_pvccin_cpu0_fault1_20" )
			)
			( signal "TP_PVCCIN_CPU0_GP1"
				( objectStatus "@baseboard_fab2_lib.baseboard_fab2(sch_1):tp_pvccin_cpu0_gp1" )
			)
			( signal "TP_PVCCIN_CPU0_RESET"
				( objectStatus "@baseboard_fab2_lib.baseboard_fab2(sch_1):tp_pvccin_cpu0_reset" )
			)
			( signal "VR_FET_SW_P12V_STBY_PVCCIN_CPU0"
				( objectStatus "@baseboard_fab2_lib.baseboard_fab2(sch_1):vr_fet_sw_p12v_stby_pvccin_cpu0" )
			)
			( signal "VR_PVCCIN_CPU0_AIREF1"
				( objectStatus "@baseboard_fab2_lib.baseboard_fab2(sch_1):vr_pvccin_cpu0_airef1" )
			)
			( signal "VR_PVCCIN_CPU0_AIREF2"
				( objectStatus "@baseboard_fab2_lib.baseboard_fab2(sch_1):vr_pvccin_cpu0_airef2" )
			)
			( signal "VR_PVCCIN_CPU0_AIREF3"
				( objectStatus "@baseboard_fab2_lib.baseboard_fab2(sch_1):vr_pvccin_cpu0_airef3" )
			)
			( signal "VR_PVCCIN_CPU0_AIREF4"
				( objectStatus "@baseboard_fab2_lib.baseboard_fab2(sch_1):vr_pvccin_cpu0_airef4" )
			)
			( signal "VR_PVCCIN_CPU0_AIREF5"
				( objectStatus "@baseboard_fab2_lib.baseboard_fab2(sch_1):vr_pvccin_cpu0_airef5" )
			)
			( signal "VR_PVCCIN_CPU0_AVINSEN"
				( attribute "VOLTAGE" "0.8"
					( Units "uVoltage" "V" 1.000000)
					( Status sAliasFlattened )
					( Origin gFrontEnd )
				)
				( objectStatus "@baseboard_fab2_lib.baseboard_fab2(sch_1):vr_pvccin_cpu0_avinsen" )
			)
			( signal "VR_PVCCIN_CPU0_PWM1"
				( attribute "VOLTAGE" "3.6"
					( Units "uVoltage" "V" 1.000000)
					( Status sAliasFlattened )
					( Origin gFrontEnd )
				)
				( objectStatus "@baseboard_fab2_lib.baseboard_fab2(sch_1):vr_pvccin_cpu0_pwm1" )
			)
			( signal "VR_PVCCIN_CPU0_PWM2"
				( attribute "VOLTAGE" "3.6"
					( Units "uVoltage" "V" 1.000000)
					( Status sAliasFlattened )
					( Origin gFrontEnd )
				)
				( objectStatus "@baseboard_fab2_lib.baseboard_fab2(sch_1):vr_pvccin_cpu0_pwm2" )
			)
			( signal "VR_PVCCIN_CPU0_PWM3"
				( attribute "VOLTAGE" "3.6"
					( Units "uVoltage" "V" 1.000000)
					( Status sAliasFlattened )
					( Origin gFrontEnd )
				)
				( objectStatus "@baseboard_fab2_lib.baseboard_fab2(sch_1):vr_pvccin_cpu0_pwm3" )
			)
			( signal "VR_PVCCIN_CPU0_PWM4"
				( attribute "VOLTAGE" "3.6"
					( Units "uVoltage" "V" 1.000000)
					( Status sAliasFlattened )
					( Origin gFrontEnd )
				)
				( objectStatus "@baseboard_fab2_lib.baseboard_fab2(sch_1):vr_pvccin_cpu0_pwm4" )
			)
			( signal "VR_PVCCIN_CPU0_PWM5"
				( attribute "VOLTAGE" "3.6"
					( Units "uVoltage" "V" 1.000000)
					( Status sAliasFlattened )
					( Origin gFrontEnd )
				)
				( objectStatus "@baseboard_fab2_lib.baseboard_fab2(sch_1):vr_pvccin_cpu0_pwm5" )
			)
			( signal "VR_PVCCIN_CPU0_VD12"
				( objectStatus "@baseboard_fab2_lib.baseboard_fab2(sch_1):vr_pvccin_cpu0_vd12" )
			)
			( signal "VR_PVCCIN_CPU0_VDD"
				( attribute "VOLTAGE" "3.3"
					( Units "uVoltage" "V" 1.000000)
					( Status sAliasFlattened )
					( Origin gFrontEnd )
				)
				( objectStatus "@baseboard_fab2_lib.baseboard_fab2(sch_1):vr_pvccin_cpu0_vdd" )
			)
			( signal "VR_PVCCIN_CPU0_VREN"
				( attribute "VOLTAGE" "3.3"
					( Units "uVoltage" "V" 1.000000)
					( Status sAliasFlattened )
					( Origin gFrontEnd )
				)
				( objectStatus "@baseboard_fab2_lib.baseboard_fab2(sch_1):vr_pvccin_cpu0_vren" )
			)
			( signal "VR_PVCCIN_CPU0_XADDR1"
				( attribute "VOLTAGE" "3.3"
					( Units "uVoltage" "V" 1.000000)
					( Status sAliasFlattened )
					( Origin gFrontEnd )
				)
				( objectStatus "@baseboard_fab2_lib.baseboard_fab2(sch_1):vr_pvccin_cpu0_xaddr1" )
			)
			( signal "VR_PVCCIN_CPU0_XADDR2"
				( attribute "VOLTAGE" "3.3"
					( Units "uVoltage" "V" 1.000000)
					( Status sAliasFlattened )
					( Origin gFrontEnd )
				)
				( objectStatus "@baseboard_fab2_lib.baseboard_fab2(sch_1):vr_pvccin_cpu0_xaddr2" )
			)
			( signal "VR_PVSA_CPU0_BIREF1"
				( objectStatus "@baseboard_fab2_lib.baseboard_fab2(sch_1):vr_pvsa_cpu0_biref1" )
			)
			( signal "VR_PVSA_CPU0_PWM"
				( objectStatus "@baseboard_fab2_lib.baseboard_fab2(sch_1):vr_pvsa_cpu0_pwm" )
			)
			( signal "VR_VRRDY_PVCCIN_CPU0"
				( attribute "VOLTAGE" "3.3"
					( Units "uVoltage" "V" 1.000000)
					( Status sAliasFlattened )
					( Origin gFrontEnd )
				)
				( objectStatus "@baseboard_fab2_lib.baseboard_fab2(sch_1):vr_vrrdy_pvccin_cpu0" )
			)
			( signal "VSENSE_PVCCIN_CPU0_AVSP"
				( objectStatus "@baseboard_fab2_lib.baseboard_fab2(sch_1):vsense_pvccin_cpu0_avsp" )
			)
			( signal "VSENSE_PVCCIN_CPU0_N"
				( objectStatus "@baseboard_fab2_lib.baseboard_fab2(sch_1):vsense_pvccin_cpu0_n" )
			)
			( signal "VSENSE_PVCCIN_CPU0_P"
				( objectStatus "@baseboard_fab2_lib.baseboard_fab2(sch_1):vsense_pvccin_cpu0_p" )
			)
			( signal "VSENSE_PVSA_CPU0_BVSP"
				( objectStatus "@baseboard_fab2_lib.baseboard_fab2(sch_1):vsense_pvsa_cpu0_bvsp" )
			)
			( signal "VSENSE_PVSA_CPU0_N"
				( objectStatus "@baseboard_fab2_lib.baseboard_fab2(sch_1):vsense_pvsa_cpu0_n" )
			)
			( signal "VSENSE_PVSA_CPU0_P"
				( objectStatus "@baseboard_fab2_lib.baseboard_fab2(sch_1):vsense_pvsa_cpu0_p" )
			)
			( signal "NC_PVCCIN_CPU0_PH1_P31"
				( objectStatus "@baseboard_fab2_lib.baseboard_fab2(sch_1):nc_pvccin_cpu0_ph1_p31" )
			)
			( signal "NC_PVCCIN_CPU0_PH2_P31"
				( objectStatus "@baseboard_fab2_lib.baseboard_fab2(sch_1):nc_pvccin_cpu0_ph2_p31" )
			)
			( signal "TP_PVCCIN_CPU0_PH1_GL_0"
				( objectStatus "@baseboard_fab2_lib.baseboard_fab2(sch_1):tp_pvccin_cpu0_ph1_gl_0" )
			)
			( signal "TP_PVCCIN_CPU0_PH1_GL_1"
				( objectStatus "@baseboard_fab2_lib.baseboard_fab2(sch_1):tp_pvccin_cpu0_ph1_gl_1" )
			)
			( signal "TP_PVCCIN_CPU0_PH2_GL_0"
				( objectStatus "@baseboard_fab2_lib.baseboard_fab2(sch_1):tp_pvccin_cpu0_ph2_gl_0" )
			)
			( signal "TP_PVCCIN_CPU0_PH2_GL_1"
				( objectStatus "@baseboard_fab2_lib.baseboard_fab2(sch_1):tp_pvccin_cpu0_ph2_gl_1" )
			)
			( signal "VR_PVCCIN_CPU0_PH1_BOOT"
				( objectStatus "@baseboard_fab2_lib.baseboard_fab2(sch_1):vr_pvccin_cpu0_ph1_boot" )
			)
			( signal "UNNAMED_202_3D01R5F-GP_I75_2"
				( objectStatus "@baseboard_fab2_lib.baseboard_fab2(sch_1):\unnamed_202_3d01r5f-gp_i75_2\" )
			)
			( signal "VR_PVCCIN_CPU0_PH1_OCSET"
				( objectStatus "@baseboard_fab2_lib.baseboard_fab2(sch_1):vr_pvccin_cpu0_ph1_ocset" )
			)
			( signal "VR_PVCCIN_CPU0_PH1_PHASE"
				( attribute "VOLTAGE" "5"
					( Units "uVoltage" "V" 1.000000)
					( Status sAliasFlattened )
					( Origin gFrontEnd )
				)
				( objectStatus "@baseboard_fab2_lib.baseboard_fab2(sch_1):vr_pvccin_cpu0_ph1_phase" )
			)
			( signal "VR_PVCCIN_CPU0_PH1_VCIN"
				( attribute "VOLTAGE" "5"
					( Units "uVoltage" "V" 1.000000)
					( Status sAliasFlattened )
					( Origin gFrontEnd )
				)
				( objectStatus "@baseboard_fab2_lib.baseboard_fab2(sch_1):vr_pvccin_cpu0_ph1_vcin" )
			)
			( signal "VR_PVCCIN_CPU0_PH2_BOOT"
				( attribute "VOLTAGE" "5"
					( Units "uVoltage" "V" 1.000000)
					( Origin gFrontEnd )
				)
				( objectStatus "@baseboard_fab2_lib.baseboard_fab2(sch_1):vr_pvccin_cpu0_ph2_boot" )
			)
			( signal "UNNAMED_209_3D01R5F-GP_I66_2"
				( objectStatus "@baseboard_fab2_lib.baseboard_fab2(sch_1):\unnamed_209_3d01r5f-gp_i66_2\" )
			)
			( signal "VR_PVCCIN_CPU0_PH2_OCSET"
				( attribute "VOLTAGE" "3.6"
					( Units "uVoltage" "V" 1.000000)
					( Status sAliasFlattened )
					( Origin gFrontEnd )
				)
				( objectStatus "@baseboard_fab2_lib.baseboard_fab2(sch_1):vr_pvccin_cpu0_ph2_ocset" )
			)
			( signal "VR_PVCCIN_CPU0_PH2_PHASE"
				( attribute "VOLTAGE" "5"
					( Units "uVoltage" "V" 1.000000)
					( Status sAliasFlattened )
					( Origin gFrontEnd )
				)
				( objectStatus "@baseboard_fab2_lib.baseboard_fab2(sch_1):vr_pvccin_cpu0_ph2_phase" )
			)
			( signal "VR_PVCCIN_CPU0_PH2_VCIN"
				( attribute "VOLTAGE" "5"
					( Units "uVoltage" "V" 1.000000)
					( Status sAliasFlattened )
					( Origin gFrontEnd )
				)
				( objectStatus "@baseboard_fab2_lib.baseboard_fab2(sch_1):vr_pvccin_cpu0_ph2_vcin" )
			)
			( signal "VR_PVCCIN_CPU0_PHASE1"
				( attribute "VOLTAGE" "5"
					( Units "uVoltage" "V" 1.000000)
					( Status sAliasFlattened )
					( Origin gFrontEnd )
				)
				( objectStatus "@baseboard_fab2_lib.baseboard_fab2(sch_1):vr_pvccin_cpu0_phase1" )
			)
			( signal "VR_PVCCIN_CPU0_PHASE2"
				( attribute "VOLTAGE" "5"
					( Units "uVoltage" "V" 1.000000)
					( Status sAliasFlattened )
					( Origin gFrontEnd )
				)
				( objectStatus "@baseboard_fab2_lib.baseboard_fab2(sch_1):vr_pvccin_cpu0_phase2" )
			)
			( signal "NC_PVCCIN_CPU0_PH3_P31"
				( objectStatus "@baseboard_fab2_lib.baseboard_fab2(sch_1):nc_pvccin_cpu0_ph3_p31" )
			)
			( signal "NC_PVCCIN_CPU0_PH4_P31"
				( objectStatus "@baseboard_fab2_lib.baseboard_fab2(sch_1):nc_pvccin_cpu0_ph4_p31" )
			)
			( signal "TP_PVCCIN_CPU0_PH3_GL_0"
				( objectStatus "@baseboard_fab2_lib.baseboard_fab2(sch_1):tp_pvccin_cpu0_ph3_gl_0" )
			)
			( signal "TP_PVCCIN_CPU0_PH3_GL_1"
				( objectStatus "@baseboard_fab2_lib.baseboard_fab2(sch_1):tp_pvccin_cpu0_ph3_gl_1" )
			)
			( signal "TP_PVCCIN_CPU0_PH4_GL_0"
				( objectStatus "@baseboard_fab2_lib.baseboard_fab2(sch_1):tp_pvccin_cpu0_ph4_gl_0" )
			)
			( signal "TP_PVCCIN_CPU0_PH4_GL_1"
				( objectStatus "@baseboard_fab2_lib.baseboard_fab2(sch_1):tp_pvccin_cpu0_ph4_gl_1" )
			)
			( signal "VR_PVCCIN_CPU0_PH3_BOOT"
				( objectStatus "@baseboard_fab2_lib.baseboard_fab2(sch_1):vr_pvccin_cpu0_ph3_boot" )
			)
			( signal "UNNAMED_219_3D01R5F-GP_I123_2"
				( objectStatus "@baseboard_fab2_lib.baseboard_fab2(sch_1):\unnamed_219_3d01r5f-gp_i123_2\" )
			)
			( signal "VR_PVCCIN_CPU0_PH3_OCSET"
				( attribute "VOLTAGE" "3.6"
					( Units "uVoltage" "V" 1.000000)
					( Status sAliasFlattened )
					( Origin gFrontEnd )
				)
				( objectStatus "@baseboard_fab2_lib.baseboard_fab2(sch_1):vr_pvccin_cpu0_ph3_ocset" )
			)
			( signal "VR_PVCCIN_CPU0_PH3_PHASE"
				( attribute "VOLTAGE" "5"
					( Units "uVoltage" "V" 1.000000)
					( Status sAliasFlattened )
					( Origin gFrontEnd )
				)
				( objectStatus "@baseboard_fab2_lib.baseboard_fab2(sch_1):vr_pvccin_cpu0_ph3_phase" )
			)
			( signal "VR_PVCCIN_CPU0_PH3_VCIN"
				( objectStatus "@baseboard_fab2_lib.baseboard_fab2(sch_1):vr_pvccin_cpu0_ph3_vcin" )
			)
			( signal "VR_PVCCIN_CPU0_PH4_BOOT"
				( objectStatus "@baseboard_fab2_lib.baseboard_fab2(sch_1):vr_pvccin_cpu0_ph4_boot" )
			)
			( signal "UNNAMED_216_3D01R5F-GP_I114_2"
				( objectStatus "@baseboard_fab2_lib.baseboard_fab2(sch_1):\unnamed_216_3d01r5f-gp_i114_2\" )
			)
			( signal "VR_PVCCIN_CPU0_PH4_OCSET"
				( attribute "VOLTAGE" "3.6"
					( Units "uVoltage" "V" 1.000000)
					( Status sAliasFlattened )
					( Origin gFrontEnd )
				)
				( objectStatus "@baseboard_fab2_lib.baseboard_fab2(sch_1):vr_pvccin_cpu0_ph4_ocset" )
			)
			( signal "VR_PVCCIN_CPU0_PH4_PHASE"
				( attribute "VOLTAGE" "5"
					( Units "uVoltage" "V" 1.000000)
					( Status sAliasFlattened )
					( Origin gFrontEnd )
				)
				( objectStatus "@baseboard_fab2_lib.baseboard_fab2(sch_1):vr_pvccin_cpu0_ph4_phase" )
			)
			( signal "VR_PVCCIN_CPU0_PH4_VCIN"
				( attribute "VOLTAGE" "5"
					( Units "uVoltage" "V" 1.000000)
					( Status sAliasFlattened )
					( Origin gFrontEnd )
				)
				( objectStatus "@baseboard_fab2_lib.baseboard_fab2(sch_1):vr_pvccin_cpu0_ph4_vcin" )
			)
			( signal "VR_PVCCIN_CPU0_PHASE3"
				( attribute "VOLTAGE" "5"
					( Units "uVoltage" "V" 1.000000)
					( Status sAliasFlattened )
					( Origin gFrontEnd )
				)
				( objectStatus "@baseboard_fab2_lib.baseboard_fab2(sch_1):vr_pvccin_cpu0_phase3" )
			)
			( signal "VR_PVCCIN_CPU0_PHASE4"
				( attribute "VOLTAGE" "5"
					( Units "uVoltage" "V" 1.000000)
					( Status sAliasFlattened )
					( Origin gFrontEnd )
				)
				( objectStatus "@baseboard_fab2_lib.baseboard_fab2(sch_1):vr_pvccin_cpu0_phase4" )
			)
			( signal "NC_PVCCIN_CPU0_PH5_P31"
				( objectStatus "@baseboard_fab2_lib.baseboard_fab2(sch_1):nc_pvccin_cpu0_ph5_p31" )
			)
			( signal "TP_PVCCIN_CPU0_PH5_GL_0"
				( objectStatus "@baseboard_fab2_lib.baseboard_fab2(sch_1):tp_pvccin_cpu0_ph5_gl_0" )
			)
			( signal "TP_PVCCIN_CPU0_PH5_GL_1"
				( objectStatus "@baseboard_fab2_lib.baseboard_fab2(sch_1):tp_pvccin_cpu0_ph5_gl_1" )
			)
			( signal "VR_FET_SW_P12V_PVCCIN_CPU0_R"
				( objectStatus "@baseboard_fab2_lib.baseboard_fab2(sch_1):vr_fet_sw_p12v_pvccin_cpu0_r" )
			)
			( signal "VR_PVCCIN_CPU0_PH5_BOOT"
				( objectStatus "@baseboard_fab2_lib.baseboard_fab2(sch_1):vr_pvccin_cpu0_ph5_boot" )
			)
			( signal "UNNAMED_202_3D01R5F-GP_I83_2"
				( objectStatus "@baseboard_fab2_lib.baseboard_fab2(sch_1):\unnamed_202_3d01r5f-gp_i83_2\" )
			)
			( signal "VR_PVCCIN_CPU0_PH5_OCSET"
				( attribute "VOLTAGE" "3.6"
					( Units "uVoltage" "V" 1.000000)
					( Status sAliasFlattened )
					( Origin gFrontEnd )
				)
				( objectStatus "@baseboard_fab2_lib.baseboard_fab2(sch_1):vr_pvccin_cpu0_ph5_ocset" )
			)
			( signal "VR_PVCCIN_CPU0_PH5_PHASE"
				( attribute "VOLTAGE" "5"
					( Units "uVoltage" "V" 1.000000)
					( Status sAliasFlattened )
					( Origin gFrontEnd )
				)
				( objectStatus "@baseboard_fab2_lib.baseboard_fab2(sch_1):vr_pvccin_cpu0_ph5_phase" )
			)
			( signal "VR_PVCCIN_CPU0_PH5_VCIN"
				( attribute "VOLTAGE" "5"
					( Units "uVoltage" "V" 1.000000)
					( Status sAliasFlattened )
					( Origin gFrontEnd )
				)
				( objectStatus "@baseboard_fab2_lib.baseboard_fab2(sch_1):vr_pvccin_cpu0_ph5_vcin" )
			)
			( signal "VR_PVCCIN_CPU0_PHASE5"
				( attribute "VOLTAGE" "5"
					( Units "uVoltage" "V" 1.000000)
					( Status sAliasFlattened )
					( Origin gFrontEnd )
				)
				( objectStatus "@baseboard_fab2_lib.baseboard_fab2(sch_1):vr_pvccin_cpu0_phase5" )
			)
			( signal "NC_PVSA_CPU0_P31"
				( objectStatus "@baseboard_fab2_lib.baseboard_fab2(sch_1):nc_pvsa_cpu0_p31" )
			)
			( signal "TP_PVSA_CPU0_GL_0"
				( objectStatus "@baseboard_fab2_lib.baseboard_fab2(sch_1):tp_pvsa_cpu0_gl_0" )
			)
			( signal "TP_PVSA_CPU0_GL_1"
				( objectStatus "@baseboard_fab2_lib.baseboard_fab2(sch_1):tp_pvsa_cpu0_gl_1" )
			)
			( signal "VR_PVSA_CPU0_BOOT"
				( objectStatus "@baseboard_fab2_lib.baseboard_fab2(sch_1):vr_pvsa_cpu0_boot" )
			)
			( signal "UNNAMED_236_3D01R5F-GP_I137_2"
				( objectStatus "@baseboard_fab2_lib.baseboard_fab2(sch_1):\unnamed_236_3d01r5f-gp_i137_2\" )
			)
			( signal "VR_PVSA_CPU0_OCSET"
				( objectStatus "@baseboard_fab2_lib.baseboard_fab2(sch_1):vr_pvsa_cpu0_ocset" )
			)
			( signal "VR_PVSA_CPU0_PHASE"
				( attribute "VOLTAGE" "5"
					( Units "uVoltage" "V" 1.000000)
					( Status sAliasFlattened )
					( Origin gFrontEnd )
				)
				( objectStatus "@baseboard_fab2_lib.baseboard_fab2(sch_1):vr_pvsa_cpu0_phase" )
			)
			( signal "VR_PVSA_CPU0_PHASE_SW"
				( attribute "VOLTAGE" "5"
					( Units "uVoltage" "V" 1.000000)
					( Status sAliasFlattened )
					( Origin gFrontEnd )
				)
				( objectStatus "@baseboard_fab2_lib.baseboard_fab2(sch_1):vr_pvsa_cpu0_phase_sw" )
			)
			( signal "VR_PVSA_CPU0_VCIN"
				( attribute "VOLTAGE" "5"
					( Units "uVoltage" "V" 1.000000)
					( Status sAliasFlattened )
					( Origin gFrontEnd )
				)
				( objectStatus "@baseboard_fab2_lib.baseboard_fab2(sch_1):vr_pvsa_cpu0_vcin" )
			)
			( signal "A_TSENSE_PVCCIN_CPU1"
				( attribute "VOLTAGE" "3.6"
					( Units "uVoltage" "V" 1.000000)
					( Status sAliasFlattened )
					( Origin gFrontEnd )
				)
				( objectStatus "@baseboard_fab2_lib.baseboard_fab2(sch_1):a_tsense_pvccin_cpu1" )
			)
			( signal "A_TSENSE_PVSA_CPU1"
				( objectStatus "@baseboard_fab2_lib.baseboard_fab2(sch_1):a_tsense_pvsa_cpu1" )
			)
			( signal "IRQ_PVCCIN_CPU1_VRHOT_LVC3_R_N"
				( objectStatus "@baseboard_fab2_lib.baseboard_fab2(sch_1):irq_pvccin_cpu1_vrhot_lvc3_r_n" )
			)
			( signal "ISENSE_PVCCIN_CPU1_PH1_IMON"
				( objectStatus "@baseboard_fab2_lib.baseboard_fab2(sch_1):isense_pvccin_cpu1_ph1_imon" )
			)
			( signal "ISENSE_PVCCIN_CPU1_PH2_IMON"
				( objectStatus "@baseboard_fab2_lib.baseboard_fab2(sch_1):isense_pvccin_cpu1_ph2_imon" )
			)
			( signal "ISENSE_PVCCIN_CPU1_PH3_IMON"
				( objectStatus "@baseboard_fab2_lib.baseboard_fab2(sch_1):isense_pvccin_cpu1_ph3_imon" )
			)
			( signal "ISENSE_PVCCIN_CPU1_PH4_IMON"
				( objectStatus "@baseboard_fab2_lib.baseboard_fab2(sch_1):isense_pvccin_cpu1_ph4_imon" )
			)
			( signal "ISENSE_PVCCIN_CPU1_PH5_IMON"
				( objectStatus "@baseboard_fab2_lib.baseboard_fab2(sch_1):isense_pvccin_cpu1_ph5_imon" )
			)
			( signal "ISENSE_PVSA_CPU1_IMON"
				( objectStatus "@baseboard_fab2_lib.baseboard_fab2(sch_1):isense_pvsa_cpu1_imon" )
			)
			( signal "PU_VR_PVCCIN_CPU1_FLT1_SMBALT_N"
				( objectStatus "@baseboard_fab2_lib.baseboard_fab2(sch_1):pu_vr_pvccin_cpu1_flt1_smbalt_n_imon" )
			)
			( signal "PU_VR_PVCCIN_CPU1_IMON"
				( objectStatus "@baseboard_fab2_lib.baseboard_fab2(sch_1):pu_vr_pvccin_cpu1_imon" )
			)
			( signal "PVCCIN_PVSA_CPU1_IINSEN"
				( attribute "VOLTAGE" "+1.5V"
					( Units "uVoltage" "V" 1.000000)
					( Status sAliasFlattened )
					( Origin gFrontEnd )
				)
				( objectStatus "@baseboard_fab2_lib.baseboard_fab2(sch_1):pvccin_pvsa_cpu1_iinsen" )
			)
			( signal "PWRGD_PVSA_CPU1_R"
				( objectStatus "@baseboard_fab2_lib.baseboard_fab2(sch_1):pwrgd_pvsa_cpu1_r" )
			)
			( signal "SMB_VR_SCL_R1"
				( objectStatus "@baseboard_fab2_lib.baseboard_fab2(sch_1):smb_vr_scl_r1" )
			)
			( signal "SMB_VR_SDA_R1"
				( objectStatus "@baseboard_fab2_lib.baseboard_fab2(sch_1):smb_vr_sda_r1" )
			)
			( signal "SVID_VALERT_VCCIN_CPU1"
				( objectStatus "@baseboard_fab2_lib.baseboard_fab2(sch_1):svid_valert_vccin_cpu1" )
			)
			( signal "SVID_VCLK_PVCCIN_CPU1"
				( objectStatus "@baseboard_fab2_lib.baseboard_fab2(sch_1):svid_vclk_pvccin_cpu1" )
			)
			( signal "SVID_VDIO_PVCCIN_CPU1"
				( objectStatus "@baseboard_fab2_lib.baseboard_fab2(sch_1):svid_vdio_pvccin_cpu1" )
			)
			( signal "TP_PVCCIN_CPU1_AIREF6"
				( objectStatus "@baseboard_fab2_lib.baseboard_fab2(sch_1):tp_pvccin_cpu1_airef6" )
			)
			( signal "TP_PVCCIN_CPU1_AISEN6"
				( objectStatus "@baseboard_fab2_lib.baseboard_fab2(sch_1):tp_pvccin_cpu1_aisen6" )
			)
			( signal "TP_PVCCIN_CPU1_APWM6"
				( objectStatus "@baseboard_fab2_lib.baseboard_fab2(sch_1):tp_pvccin_cpu1_apwm6" )
			)
			( signal "TP_PVCCIN_CPU1_FAULT1_20"
				( objectStatus "@baseboard_fab2_lib.baseboard_fab2(sch_1):tp_pvccin_cpu1_fault1_20" )
			)
			( signal "TP_PVCCIN_CPU1_GP1"
				( objectStatus "@baseboard_fab2_lib.baseboard_fab2(sch_1):tp_pvccin_cpu1_gp1" )
			)
			( signal "TP_PVCCIN_CPU1_RESET_N"
				( objectStatus "@baseboard_fab2_lib.baseboard_fab2(sch_1):tp_pvccin_cpu1_reset_n" )
			)
			( signal "VR_FET_SW_P12V_STBY_PVCCIN_CPU1"
				( attribute "VOLTAGE" "12"
					( Units "uVoltage" "V" 1.000000)
					( Status sAliasFlattened )
					( Origin gFrontEnd )
				)
				( objectStatus "@baseboard_fab2_lib.baseboard_fab2(sch_1):vr_fet_sw_p12v_stby_pvccin_cpu1" )
			)
			( signal "VR_PVCCIN_CPU1_AIREF1"
				( objectStatus "@baseboard_fab2_lib.baseboard_fab2(sch_1):vr_pvccin_cpu1_airef1" )
			)
			( signal "VR_PVCCIN_CPU1_AIREF2"
				( objectStatus "@baseboard_fab2_lib.baseboard_fab2(sch_1):vr_pvccin_cpu1_airef2" )
			)
			( signal "VR_PVCCIN_CPU1_AIREF3"
				( objectStatus "@baseboard_fab2_lib.baseboard_fab2(sch_1):vr_pvccin_cpu1_airef3" )
			)
			( signal "VR_PVCCIN_CPU1_AIREF4"
				( objectStatus "@baseboard_fab2_lib.baseboard_fab2(sch_1):vr_pvccin_cpu1_airef4" )
			)
			( signal "VR_PVCCIN_CPU1_AIREF5"
				( objectStatus "@baseboard_fab2_lib.baseboard_fab2(sch_1):vr_pvccin_cpu1_airef5" )
			)
			( signal "VR_PVCCIN_CPU1_AVINSEN"
				( attribute "VOLTAGE" "0.8"
					( Units "uVoltage" "V" 1.000000)
					( Status sAliasFlattened )
					( Origin gFrontEnd )
				)
				( objectStatus "@baseboard_fab2_lib.baseboard_fab2(sch_1):vr_pvccin_cpu1_avinsen" )
			)
			( signal "VR_PVCCIN_CPU1_PWM1"
				( attribute "VOLTAGE" "3.6"
					( Units "uVoltage" "V" 1.000000)
					( Status sAliasFlattened )
					( Origin gFrontEnd )
				)
				( objectStatus "@baseboard_fab2_lib.baseboard_fab2(sch_1):vr_pvccin_cpu1_pwm1" )
			)
			( signal "VR_PVCCIN_CPU1_PWM2"
				( attribute "VOLTAGE" "3.6"
					( Units "uVoltage" "V" 1.000000)
					( Status sAliasFlattened )
					( Origin gFrontEnd )
				)
				( objectStatus "@baseboard_fab2_lib.baseboard_fab2(sch_1):vr_pvccin_cpu1_pwm2" )
			)
			( signal "VR_PVCCIN_CPU1_PWM3"
				( attribute "VOLTAGE" "3.6"
					( Units "uVoltage" "V" 1.000000)
					( Status sAliasFlattened )
					( Origin gFrontEnd )
				)
				( objectStatus "@baseboard_fab2_lib.baseboard_fab2(sch_1):vr_pvccin_cpu1_pwm3" )
			)
			( signal "VR_PVCCIN_CPU1_PWM4"
				( attribute "VOLTAGE" "3.6"
					( Units "uVoltage" "V" 1.000000)
					( Status sAliasFlattened )
					( Origin gFrontEnd )
				)
				( objectStatus "@baseboard_fab2_lib.baseboard_fab2(sch_1):vr_pvccin_cpu1_pwm4" )
			)
			( signal "VR_PVCCIN_CPU1_PWM5"
				( attribute "VOLTAGE" "3.6"
					( Units "uVoltage" "V" 1.000000)
					( Status sAliasFlattened )
					( Origin gFrontEnd )
				)
				( objectStatus "@baseboard_fab2_lib.baseboard_fab2(sch_1):vr_pvccin_cpu1_pwm5" )
			)
			( signal "VR_PVCCIN_CPU1_VD12"
				( objectStatus "@baseboard_fab2_lib.baseboard_fab2(sch_1):vr_pvccin_cpu1_vd12" )
			)
			( signal "VR_PVCCIN_CPU1_VDD"
				( attribute "VOLTAGE" "3.3"
					( Units "uVoltage" "V" 1.000000)
					( Status sAliasFlattened )
					( Origin gFrontEnd )
				)
				( objectStatus "@baseboard_fab2_lib.baseboard_fab2(sch_1):vr_pvccin_cpu1_vdd" )
			)
			( signal "VR_PVCCIN_CPU1_VREN"
				( attribute "VOLTAGE" "3.3"
					( Units "uVoltage" "V" 1.000000)
					( Status sAliasFlattened )
					( Origin gFrontEnd )
				)
				( objectStatus "@baseboard_fab2_lib.baseboard_fab2(sch_1):vr_pvccin_cpu1_vren" )
			)
			( signal "VR_PVCCIN_CPU1_XADDR1"
				( attribute "VOLTAGE" "3.3"
					( Units "uVoltage" "V" 1.000000)
					( Status sAliasFlattened )
					( Origin gFrontEnd )
				)
				( objectStatus "@baseboard_fab2_lib.baseboard_fab2(sch_1):vr_pvccin_cpu1_xaddr1" )
			)
			( signal "VR_PVCCIN_CPU1_XADDR2"
				( attribute "VOLTAGE" "3.3"
					( Units "uVoltage" "V" 1.000000)
					( Status sAliasFlattened )
					( Origin gFrontEnd )
				)
				( objectStatus "@baseboard_fab2_lib.baseboard_fab2(sch_1):vr_pvccin_cpu1_xaddr2" )
			)
			( signal "VR_PVSA_CPU1_BIREF1"
				( objectStatus "@baseboard_fab2_lib.baseboard_fab2(sch_1):vr_pvsa_cpu1_biref1" )
			)
			( signal "VR_PVSA_CPU1_PWM"
				( attribute "VOLTAGE" "3.6"
					( Units "uVoltage" "V" 1.000000)
					( Status sAliasFlattened )
					( Origin gFrontEnd )
				)
				( objectStatus "@baseboard_fab2_lib.baseboard_fab2(sch_1):vr_pvsa_cpu1_pwm" )
			)
			( signal "VR_VRRDY_PVCCIN_CPU1"
				( objectStatus "@baseboard_fab2_lib.baseboard_fab2(sch_1):vr_vrrdy_pvccin_cpu1" )
			)
			( signal "VSENSE_PVCCIN_CPU1_AVSP"
				( objectStatus "@baseboard_fab2_lib.baseboard_fab2(sch_1):vsense_pvccin_cpu1_avsp" )
			)
			( signal "VSENSE_PVCCIN_CPU1_N"
				( objectStatus "@baseboard_fab2_lib.baseboard_fab2(sch_1):vsense_pvccin_cpu1_n" )
			)
			( signal "VSENSE_PVCCIN_CPU1_P"
				( objectStatus "@baseboard_fab2_lib.baseboard_fab2(sch_1):vsense_pvccin_cpu1_p" )
			)
			( signal "VSENSE_PVSA_CPU1_BVSP"
				( objectStatus "@baseboard_fab2_lib.baseboard_fab2(sch_1):vsense_pvsa_cpu1_bvsp" )
			)
			( signal "VSENSE_PVSA_CPU1_N"
				( objectStatus "@baseboard_fab2_lib.baseboard_fab2(sch_1):vsense_pvsa_cpu1_n" )
			)
			( signal "VSENSE_PVSA_CPU1_P"
				( objectStatus "@baseboard_fab2_lib.baseboard_fab2(sch_1):vsense_pvsa_cpu1_p" )
			)
			( signal "NC_PVCCIN_CPU1_PH1_P31"
				( objectStatus "@baseboard_fab2_lib.baseboard_fab2(sch_1):nc_pvccin_cpu1_ph1_p31" )
			)
			( signal "NC_PVCCIN_CPU1_PH2_P31"
				( objectStatus "@baseboard_fab2_lib.baseboard_fab2(sch_1):nc_pvccin_cpu1_ph2_p31" )
			)
			( signal "TP_PVCCINC_CPU1_PH1_GL_0"
				( objectStatus "@baseboard_fab2_lib.baseboard_fab2(sch_1):tp_pvccinc_cpu1_ph1_gl_0" )
			)
			( signal "TP_PVCCINC_CPU1_PH1_GL_1"
				( objectStatus "@baseboard_fab2_lib.baseboard_fab2(sch_1):tp_pvccinc_cpu1_ph1_gl_1" )
			)
			( signal "TP_PVCCINC_CPU1_PH2_GL_0"
				( objectStatus "@baseboard_fab2_lib.baseboard_fab2(sch_1):tp_pvccinc_cpu1_ph2_gl_0" )
			)
			( signal "TP_PVCCINC_CPU1_PH2_GL_1"
				( objectStatus "@baseboard_fab2_lib.baseboard_fab2(sch_1):tp_pvccinc_cpu1_ph2_gl_1" )
			)
			( signal "VR_PVCCIN_CPU1_PH1_BOOT"
				( objectStatus "@baseboard_fab2_lib.baseboard_fab2(sch_1):vr_pvccin_cpu1_ph1_boot" )
			)
			( signal "UNNAMED_204_3D01R5F-GP_I91_2"
				( objectStatus "@baseboard_fab2_lib.baseboard_fab2(sch_1):\unnamed_204_3d01r5f-gp_i91_2\" )
			)
			( signal "VR_PVCCIN_CPU1_PH1_OCSET"
				( objectStatus "@baseboard_fab2_lib.baseboard_fab2(sch_1):vr_pvccin_cpu1_ph1_ocset" )
			)
			( signal "VR_PVCCIN_CPU1_PH1_PHASE"
				( attribute "VOLTAGE" "5"
					( Units "uVoltage" "V" 1.000000)
					( Status sAliasFlattened )
					( Origin gFrontEnd )
				)
				( objectStatus "@baseboard_fab2_lib.baseboard_fab2(sch_1):vr_pvccin_cpu1_ph1_phase" )
			)
			( signal "VR_PVCCIN_CPU1_PH1_VCIN"
				( attribute "VOLTAGE" "5"
					( Units "uVoltage" "V" 1.000000)
					( Status sAliasFlattened )
					( Origin gFrontEnd )
				)
				( objectStatus "@baseboard_fab2_lib.baseboard_fab2(sch_1):vr_pvccin_cpu1_ph1_vcin" )
			)
			( signal "VR_PVCCIN_CPU1_PH2_BOOT"
				( objectStatus "@baseboard_fab2_lib.baseboard_fab2(sch_1):vr_pvccin_cpu1_ph2_boot" )
			)
			( signal "VR_PVCCIN_CPU1_PH2_OCSET"
				( objectStatus "@baseboard_fab2_lib.baseboard_fab2(sch_1):vr_pvccin_cpu1_ph2_ocset" )
			)
			( signal "VR_PVCCIN_CPU1_PH2_PHASE"
				( attribute "VOLTAGE" "5"
					( Units "uVoltage" "V" 1.000000)
					( Status sAliasFlattened )
					( Origin gFrontEnd )
				)
				( objectStatus "@baseboard_fab2_lib.baseboard_fab2(sch_1):vr_pvccin_cpu1_ph2_phase" )
			)
			( signal "VR_PVCCIN_CPU1_PH2_VCIN"
				( attribute "VOLTAGE" "5"
					( Units "uVoltage" "V" 1.000000)
					( Status sAliasFlattened )
					( Origin gFrontEnd )
				)
				( objectStatus "@baseboard_fab2_lib.baseboard_fab2(sch_1):vr_pvccin_cpu1_ph2_vcin" )
			)
			( signal "VR_PVCCIN_CPU1_PHASE1"
				( attribute "VOLTAGE" "5"
					( Units "uVoltage" "V" 1.000000)
					( Status sAliasFlattened )
					( Origin gFrontEnd )
				)
				( objectStatus "@baseboard_fab2_lib.baseboard_fab2(sch_1):vr_pvccin_cpu1_phase1" )
			)
			( signal "VR_PVCCIN_CPU1_PHASE2"
				( attribute "VOLTAGE" "5"
					( Units "uVoltage" "V" 1.000000)
					( Status sAliasFlattened )
					( Origin gFrontEnd )
				)
				( objectStatus "@baseboard_fab2_lib.baseboard_fab2(sch_1):vr_pvccin_cpu1_phase2" )
			)
			( signal "NC_PVCCIN_CPU1_PH3_P31"
				( objectStatus "@baseboard_fab2_lib.baseboard_fab2(sch_1):nc_pvccin_cpu1_ph3_p31" )
			)
			( signal "NC_PVCCIN_CPU1_PH4_P31"
				( objectStatus "@baseboard_fab2_lib.baseboard_fab2(sch_1):nc_pvccin_cpu1_ph4_p31" )
			)
			( signal "TP_PVCCIN_CPU1_PH3_GL_0"
				( objectStatus "@baseboard_fab2_lib.baseboard_fab2(sch_1):tp_pvccin_cpu1_ph3_gl_0" )
			)
			( signal "TP_PVCCIN_CPU1_PH3_GL_1"
				( objectStatus "@baseboard_fab2_lib.baseboard_fab2(sch_1):tp_pvccin_cpu1_ph3_gl_1" )
			)
			( signal "TP_PVCCIN_CPU1_PH4_GL_0"
				( objectStatus "@baseboard_fab2_lib.baseboard_fab2(sch_1):tp_pvccin_cpu1_ph4_gl_0" )
			)
			( signal "TP_PVCCIN_CPU1_PH4_GL_1"
				( objectStatus "@baseboard_fab2_lib.baseboard_fab2(sch_1):tp_pvccin_cpu1_ph4_gl_1" )
			)
			( signal "VR_PVCCIN_CPU1_PH3_BOOT"
				( objectStatus "@baseboard_fab2_lib.baseboard_fab2(sch_1):vr_pvccin_cpu1_ph3_boot" )
			)
			( signal "VR_PVCCIN_CPU1_PH3_OCSET"
				( objectStatus "@baseboard_fab2_lib.baseboard_fab2(sch_1):vr_pvccin_cpu1_ph3_ocset" )
			)
			( signal "VR_PVCCIN_CPU1_PH3_PHASE"
				( objectStatus "@baseboard_fab2_lib.baseboard_fab2(sch_1):vr_pvccin_cpu1_ph3_phase" )
			)
			( signal "VR_PVCCIN_CPU1_PH3_VCIN"
				( attribute "VOLTAGE" "5"
					( Units "uVoltage" "V" 1.000000)
					( Status sAliasFlattened )
					( Origin gFrontEnd )
				)
				( objectStatus "@baseboard_fab2_lib.baseboard_fab2(sch_1):vr_pvccin_cpu1_ph3_vcin" )
			)
			( signal "VR_PVCCIN_CPU1_PH4_BOOT"
				( objectStatus "@baseboard_fab2_lib.baseboard_fab2(sch_1):vr_pvccin_cpu1_ph4_boot" )
			)
			( signal "VR_PVCCIN_CPU1_PH4_OCSET"
				( objectStatus "@baseboard_fab2_lib.baseboard_fab2(sch_1):vr_pvccin_cpu1_ph4_ocset" )
			)
			( signal "VR_PVCCIN_CPU1_PH4_PHASE"
				( attribute "VOLTAGE" "5"
					( Units "uVoltage" "V" 1.000000)
					( Status sAliasFlattened )
					( Origin gFrontEnd )
				)
				( objectStatus "@baseboard_fab2_lib.baseboard_fab2(sch_1):vr_pvccin_cpu1_ph4_phase" )
			)
			( signal "VR_PVCCIN_CPU1_PH4_VCIN"
				( attribute "VOLTAGE" "5"
					( Units "uVoltage" "V" 1.000000)
					( Status sAliasFlattened )
					( Origin gFrontEnd )
				)
				( objectStatus "@baseboard_fab2_lib.baseboard_fab2(sch_1):vr_pvccin_cpu1_ph4_vcin" )
			)
			( signal "VR_PVCCIN_CPU1_PHASE3"
				( attribute "VOLTAGE" "5"
					( Units "uVoltage" "V" 1.000000)
					( Status sAliasFlattened )
					( Origin gFrontEnd )
				)
				( objectStatus "@baseboard_fab2_lib.baseboard_fab2(sch_1):vr_pvccin_cpu1_phase3" )
			)
			( signal "VR_PVCCIN_CPU1_PHASE4"
				( attribute "VOLTAGE" "5"
					( Units "uVoltage" "V" 1.000000)
					( Status sAliasFlattened )
					( Origin gFrontEnd )
				)
				( objectStatus "@baseboard_fab2_lib.baseboard_fab2(sch_1):vr_pvccin_cpu1_phase4" )
			)
			( signal "NC_PVCCIN_CPU1_PH5_P31"
				( objectStatus "@baseboard_fab2_lib.baseboard_fab2(sch_1):nc_pvccin_cpu1_ph5_p31" )
			)
			( signal "TP_PVCCIN_CPU1_PH5_GL_0"
				( objectStatus "@baseboard_fab2_lib.baseboard_fab2(sch_1):tp_pvccin_cpu1_ph5_gl_0" )
			)
			( signal "TP_PVCCIN_CPU1_PH5_GL_1"
				( objectStatus "@baseboard_fab2_lib.baseboard_fab2(sch_1):tp_pvccin_cpu1_ph5_gl_1" )
			)
			( signal "VR_FET_SW_P12V_PVCCIN_CPU1_R"
				( objectStatus "@baseboard_fab2_lib.baseboard_fab2(sch_1):vr_fet_sw_p12v_pvccin_cpu1_r" )
			)
			( signal "VR_PVCCIN_CPU1_PH5_BOOT"
				( objectStatus "@baseboard_fab2_lib.baseboard_fab2(sch_1):vr_pvccin_cpu1_ph5_boot" )
			)
			( signal "UNNAMED_207_3D01R5F-GP_I85_2"
				( objectStatus "@baseboard_fab2_lib.baseboard_fab2(sch_1):\unnamed_207_3d01r5f-gp_i85_2\" )
			)
			( signal "VR_PVCCIN_CPU1_PH5_OCSET"
				( objectStatus "@baseboard_fab2_lib.baseboard_fab2(sch_1):vr_pvccin_cpu1_ph5_ocset" )
			)
			( signal "VR_PVCCIN_CPU1_PH5_PHASE"
				( attribute "VOLTAGE" "5"
					( Units "uVoltage" "V" 1.000000)
					( Status sAliasFlattened )
					( Origin gFrontEnd )
				)
				( objectStatus "@baseboard_fab2_lib.baseboard_fab2(sch_1):vr_pvccin_cpu1_ph5_phase" )
			)
			( signal "VR_PVCCIN_CPU1_PH5_VCIN"
				( attribute "VOLTAGE" "5"
					( Units "uVoltage" "V" 1.000000)
					( Status sAliasFlattened )
					( Origin gFrontEnd )
				)
				( objectStatus "@baseboard_fab2_lib.baseboard_fab2(sch_1):vr_pvccin_cpu1_ph5_vcin" )
			)
			( signal "VR_PVCCIN_CPU1_PHASE5"
				( attribute "VOLTAGE" "5"
					( Units "uVoltage" "V" 1.000000)
					( Status sAliasFlattened )
					( Origin gFrontEnd )
				)
				( objectStatus "@baseboard_fab2_lib.baseboard_fab2(sch_1):vr_pvccin_cpu1_phase5" )
			)
			( signal "NC_PVSA_CPU1_P31"
				( objectStatus "@baseboard_fab2_lib.baseboard_fab2(sch_1):nc_pvsa_cpu1_p31" )
			)
			( signal "TP_PVSA_CPU1_GL_0"
				( objectStatus "@baseboard_fab2_lib.baseboard_fab2(sch_1):tp_pvsa_cpu1_gl_0" )
			)
			( signal "TP_PVSA_CPU1_GL_1"
				( objectStatus "@baseboard_fab2_lib.baseboard_fab2(sch_1):tp_pvsa_cpu1_gl_1" )
			)
			( signal "VR_PVSA_CPU1_BOOT"
				( objectStatus "@baseboard_fab2_lib.baseboard_fab2(sch_1):vr_pvsa_cpu1_boot" )
			)
			( signal "UNNAMED_214_3D01R5F-GP_I132_2"
				( objectStatus "@baseboard_fab2_lib.baseboard_fab2(sch_1):\unnamed_214_3d01r5f-gp_i132_2\" )
			)
			( signal "VR_PVSA_CPU1_OCSET"
				( objectStatus "@baseboard_fab2_lib.baseboard_fab2(sch_1):vr_pvsa_cpu1_ocset" )
			)
			( signal "VR_PVSA_CPU1_PHASE"
				( attribute "VOLTAGE" "5"
					( Units "uVoltage" "V" 1.000000)
					( Status sAliasFlattened )
					( Origin gFrontEnd )
				)
				( objectStatus "@baseboard_fab2_lib.baseboard_fab2(sch_1):vr_pvsa_cpu1_phase" )
			)
			( signal "VR_PVSA_CPU1_PHASE_SW"
				( attribute "VOLTAGE" "5"
					( Units "uVoltage" "V" 1.000000)
					( Status sAliasFlattened )
					( Origin gFrontEnd )
				)
				( objectStatus "@baseboard_fab2_lib.baseboard_fab2(sch_1):vr_pvsa_cpu1_phase_sw" )
			)
			( signal "VR_PVSA_CPU1_VCIN"
				( attribute "VOLTAGE" "5"
					( Units "uVoltage" "V" 1.000000)
					( Status sAliasFlattened )
					( Origin gFrontEnd )
				)
				( objectStatus "@baseboard_fab2_lib.baseboard_fab2(sch_1):vr_pvsa_cpu1_vcin" )
			)
			( signal "A_TSENSE_PVCCIO_CPU0"
				( attribute "VOLTAGE" "3.6"
					( Units "uVoltage" "V" 1.000000)
					( Status sAliasFlattened )
					( Origin gFrontEnd )
				)
				( objectStatus "@baseboard_fab2_lib.baseboard_fab2(sch_1):a_tsense_pvccio_cpu0" )
			)
			( signal "IRQ_PVCCIO_CPU0_VRHOT_N"
				( objectStatus "@baseboard_fab2_lib.baseboard_fab2(sch_1):irq_pvccio_cpu0_vrhot_n" )
			)
			( signal "ISENSE_PVCCIO_CPU0_PH1_IMON"
				( objectStatus "@baseboard_fab2_lib.baseboard_fab2(sch_1):isense_pvccio_cpu0_ph1_imon" )
			)
			( signal "NC_PVCCIO_CPU0_DNC0"
				( objectStatus "@baseboard_fab2_lib.baseboard_fab2(sch_1):nc_pvccio_cpu0_dnc0" )
			)
			( signal "NC_PVCCIO_CPU0_DNC1"
				( objectStatus "@baseboard_fab2_lib.baseboard_fab2(sch_1):nc_pvccio_cpu0_dnc1" )
			)
			( signal "NC_PVCCIO_CPU0_DNC2"
				( objectStatus "@baseboard_fab2_lib.baseboard_fab2(sch_1):nc_pvccio_cpu0_dnc2" )
			)
			( signal "NC_PVCCIO_CPU0_DNC3"
				( objectStatus "@baseboard_fab2_lib.baseboard_fab2(sch_1):nc_pvccio_cpu0_dnc3" )
			)
			( signal "NC_PVCCIO_CPU0_DNC4"
				( objectStatus "@baseboard_fab2_lib.baseboard_fab2(sch_1):nc_pvccio_cpu0_dnc4" )
			)
			( signal "PU_VR_PVCCIO_CPU0_FAULT1"
				( objectStatus "@baseboard_fab2_lib.baseboard_fab2(sch_1):pu_vr_pvccio_cpu0_fault1" )
			)
			( signal "PWRGD_PVCCIO_CPU0_R"
				( objectStatus "@baseboard_fab2_lib.baseboard_fab2(sch_1):pwrgd_pvccio_cpu0_r" )
			)
			( signal "SMB_VR_SCL_PVCCIO_CPU0"
				( objectStatus "@baseboard_fab2_lib.baseboard_fab2(sch_1):smb_vr_scl_pvccio_cpu0" )
			)
			( signal "SMB_VR_SDA_PVCCIO_CPU0"
				( objectStatus "@baseboard_fab2_lib.baseboard_fab2(sch_1):smb_vr_sda_pvccio_cpu0" )
			)
			( signal "SVID_ALERT_PVCCIO_CPU0"
				( objectStatus "@baseboard_fab2_lib.baseboard_fab2(sch_1):svid_alert_pvccio_cpu0" )
			)
			( signal "SVID_CLK_PVCCIO_CPU0"
				( objectStatus "@baseboard_fab2_lib.baseboard_fab2(sch_1):svid_clk_pvccio_cpu0" )
			)
			( signal "SVID_VDIO_PVCCIO_CPU0"
				( objectStatus "@baseboard_fab2_lib.baseboard_fab2(sch_1):svid_vdio_pvccio_cpu0" )
			)
			( signal "TP_PVCCIO_CPU0_BIREF1"
				( objectStatus "@baseboard_fab2_lib.baseboard_fab2(sch_1):tp_pvccio_cpu0_biref1" )
			)
			( signal "TP_PVCCIO_CPU0_BPWM1"
				( objectStatus "@baseboard_fab2_lib.baseboard_fab2(sch_1):tp_pvccio_cpu0_bpwm1" )
			)
			( signal "TP_PVCCIO_CPU0_BTSEN"
				( objectStatus "@baseboard_fab2_lib.baseboard_fab2(sch_1):tp_pvccio_cpu0_btsen" )
			)
			( signal "TP_PVCCIO_CPU0_BVREF"
				( objectStatus "@baseboard_fab2_lib.baseboard_fab2(sch_1):tp_pvccio_cpu0_bvref" )
			)
			( signal "TP_PVCCIO_CPU0_BVSEN"
				( objectStatus "@baseboard_fab2_lib.baseboard_fab2(sch_1):tp_pvccio_cpu0_bvsen" )
			)
			( signal "TP_PVCCIO_CPU0_PINALRT_N"
				( objectStatus "@baseboard_fab2_lib.baseboard_fab2(sch_1):tp_pvccio_cpu0_pinalrt_n" )
			)
			( signal "TP_PVCCIO_CPU0_RESET_N"
				( objectStatus "@baseboard_fab2_lib.baseboard_fab2(sch_1):tp_pvccio_cpu0_reset_n" )
			)
			( signal "TP_VR_PVCCIO_CPU0_AIINSEN"
				( objectStatus "@baseboard_fab2_lib.baseboard_fab2(sch_1):tp_vr_pvccio_cpu0_aiinsen" )
			)
			( signal "TP_VR_PVCCIO_CPU0_MP0"
				( objectStatus "@baseboard_fab2_lib.baseboard_fab2(sch_1):tp_vr_pvccio_cpu0_mp0" )
			)
			( signal "TP_VR_PVCCIO_CPU0_MP1"
				( objectStatus "@baseboard_fab2_lib.baseboard_fab2(sch_1):tp_vr_pvccio_cpu0_mp1" )
			)
			( signal "TP_VR_PVCCIO_CPU0_MP2"
				( objectStatus "@baseboard_fab2_lib.baseboard_fab2(sch_1):tp_vr_pvccio_cpu0_mp2" )
			)
			( signal "TP_VR_PVCCIO_CPU0_MP3"
				( objectStatus "@baseboard_fab2_lib.baseboard_fab2(sch_1):tp_vr_pvccio_cpu0_mp3" )
			)
			( signal "VR_FET_SW_P12V_STBY_PVCCIO_CPU0"
				( attribute "VOLTAGE" "12"
					( Units "uVoltage" "V" 1.000000)
					( Status sAliasFlattened )
					( Origin gFrontEnd )
				)
				( objectStatus "@baseboard_fab2_lib.baseboard_fab2(sch_1):vr_fet_sw_p12v_stby_pvccio_cpu0" )
			)
			( signal "VR_PVCCIO_CPU0_AIREF1"
				( objectStatus "@baseboard_fab2_lib.baseboard_fab2(sch_1):vr_pvccio_cpu0_airef1" )
			)
			( signal "VR_PVCCIO_CPU0_AVSP"
				( attribute "VOLTAGE" "2"
					( Units "uVoltage" "V" 1.000000)
					( Status sAliasFlattened )
					( Origin gFrontEnd )
				)
				( objectStatus "@baseboard_fab2_lib.baseboard_fab2(sch_1):vr_pvccio_cpu0_avsp" )
			)
			( signal "VR_PVCCIO_CPU0_EN"
				( objectStatus "@baseboard_fab2_lib.baseboard_fab2(sch_1):vr_pvccio_cpu0_en" )
			)
			( signal "VR_PVCCIO_CPU0_PWM1"
				( attribute "VOLTAGE" "3.3"
					( Units "uVoltage" "V" 1.000000)
					( Status sAliasFlattened )
					( Origin gFrontEnd )
				)
				( objectStatus "@baseboard_fab2_lib.baseboard_fab2(sch_1):vr_pvccio_cpu0_pwm1" )
			)
			( signal "VR_PVCCIO_CPU0_VD12"
				( objectStatus "@baseboard_fab2_lib.baseboard_fab2(sch_1):vr_pvccio_cpu0_vd12" )
			)
			( signal "VR_PVCCIO_CPU0_VDD"
				( objectStatus "@baseboard_fab2_lib.baseboard_fab2(sch_1):vr_pvccio_cpu0_vdd" )
			)
			( signal "VR_PVCCIO_CPU0_VINSEN"
				( attribute "VOLTAGE" "0.8"
					( Units "uVoltage" "V" 1.000000)
					( Status sAliasFlattened )
					( Origin gFrontEnd )
				)
				( objectStatus "@baseboard_fab2_lib.baseboard_fab2(sch_1):vr_pvccio_cpu0_vinsen" )
			)
			( signal "VR_PVCCIO_CPU0_XADDR1"
				( attribute "VOLTAGE" "3.3"
					( Units "uVoltage" "V" 1.000000)
					( Status sAliasFlattened )
					( Origin gFrontEnd )
				)
				( objectStatus "@baseboard_fab2_lib.baseboard_fab2(sch_1):vr_pvccio_cpu0_xaddr1" )
			)
			( signal "VR_PVCCIO_CPU0_XADDR2"
				( attribute "VOLTAGE" "3.3V"
					( Units "uVoltage" "V" 1.000000)
					( Status sAliasFlattened )
					( Origin gFrontEnd )
				)
				( objectStatus "@baseboard_fab2_lib.baseboard_fab2(sch_1):vr_pvccio_cpu0_xaddr2" )
			)
			( signal "VSENSE_PVCCIO_CPU0_AVSN"
				( objectStatus "@baseboard_fab2_lib.baseboard_fab2(sch_1):vsense_pvccio_cpu0_avsn" )
			)
			( signal "VSENSE_PVCCIO_CPU0_AVSP"
				( objectStatus "@baseboard_fab2_lib.baseboard_fab2(sch_1):vsense_pvccio_cpu0_avsp" )
			)
			( signal "NC_PVCCIO_CPU0_PH1_P31"
				( objectStatus "@baseboard_fab2_lib.baseboard_fab2(sch_1):nc_pvccio_cpu0_ph1_p31" )
			)
			( signal "TP_PVCCIO_CPU0_GL_0"
				( objectStatus "@baseboard_fab2_lib.baseboard_fab2(sch_1):tp_pvccio_cpu0_gl_0" )
			)
			( signal "TP_PVCCIO_CPU0_GL_1"
				( objectStatus "@baseboard_fab2_lib.baseboard_fab2(sch_1):tp_pvccio_cpu0_gl_1" )
			)
			( signal "VR_PVCCIO_CPU0_OCSET"
				( objectStatus "@baseboard_fab2_lib.baseboard_fab2(sch_1):vr_pvccio_cpu0_ocset" )
			)
			( signal "VR_PVCCIO_CPU0_PH1_BOOT"
				( objectStatus "@baseboard_fab2_lib.baseboard_fab2(sch_1):vr_pvccio_cpu0_ph1_boot" )
			)
			( signal "UNNAMED_207_3D01R5F-GP_I76_2"
				( objectStatus "@baseboard_fab2_lib.baseboard_fab2(sch_1):\unnamed_207_3d01r5f-gp_i76_2\" )
			)
			( signal "VR_PVCCIO_CPU0_PH1_PHASE"
				( attribute "VOLTAGE" "5"
					( Units "uVoltage" "V" 1.000000)
					( Status sAliasFlattened )
					( Origin gFrontEnd )
				)
				( objectStatus "@baseboard_fab2_lib.baseboard_fab2(sch_1):vr_pvccio_cpu0_ph1_phase" )
			)
			( signal "VR_PVCCIO_CPU0_PH1_SW"
				( attribute "VOLTAGE" "5"
					( Units "uVoltage" "V" 1.000000)
					( Status sAliasFlattened )
					( Origin gFrontEnd )
				)
				( objectStatus "@baseboard_fab2_lib.baseboard_fab2(sch_1):vr_pvccio_cpu0_ph1_sw" )
			)
			( signal "VR_PVCCIO_CPU0_PH1_VCIN"
				( attribute "VOLTAGE" "5"
					( Units "uVoltage" "V" 1.000000)
					( Status sAliasFlattened )
					( Origin gFrontEnd )
				)
				( objectStatus "@baseboard_fab2_lib.baseboard_fab2(sch_1):vr_pvccio_cpu0_ph1_vcin" )
			)
			( signal "A_TSENSE_PVCCIO_CPU1"
				( objectStatus "@baseboard_fab2_lib.baseboard_fab2(sch_1):a_tsense_pvccio_cpu1" )
			)
			( signal "IRQ_PVCCIO_CPU1_VRHOT_N"
				( objectStatus "@baseboard_fab2_lib.baseboard_fab2(sch_1):irq_pvccio_cpu1_vrhot_n" )
			)
			( signal "ISENSE_PVCCIO_CPU1_PH1_IMON"
				( objectStatus "@baseboard_fab2_lib.baseboard_fab2(sch_1):isense_pvccio_cpu1_ph1_imon" )
			)
			( signal "NC_PVCCIO_CPU1_DNC0"
				( objectStatus "@baseboard_fab2_lib.baseboard_fab2(sch_1):nc_pvccio_cpu1_dnc0" )
			)
			( signal "NC_PVCCIO_CPU1_DNC1"
				( objectStatus "@baseboard_fab2_lib.baseboard_fab2(sch_1):nc_pvccio_cpu1_dnc1" )
			)
			( signal "NC_PVCCIO_CPU1_DNC2"
				( objectStatus "@baseboard_fab2_lib.baseboard_fab2(sch_1):nc_pvccio_cpu1_dnc2" )
			)
			( signal "NC_PVCCIO_CPU1_DNC3"
				( objectStatus "@baseboard_fab2_lib.baseboard_fab2(sch_1):nc_pvccio_cpu1_dnc3" )
			)
			( signal "NC_PVCCIO_CPU1_DNC4"
				( objectStatus "@baseboard_fab2_lib.baseboard_fab2(sch_1):nc_pvccio_cpu1_dnc4" )
			)
			( signal "PU_VR_PVCCIO_CPU1_FAULT1"
				( objectStatus "@baseboard_fab2_lib.baseboard_fab2(sch_1):pu_vr_pvccio_cpu1_fault1" )
			)
			( signal "PWRGD_PVCCIO_CPU1_R"
				( objectStatus "@baseboard_fab2_lib.baseboard_fab2(sch_1):pwrgd_pvccio_cpu1_r" )
			)
			( signal "SMB_VR_SCL_PVCCIO_CPU1"
				( objectStatus "@baseboard_fab2_lib.baseboard_fab2(sch_1):smb_vr_scl_pvccio_cpu1" )
			)
			( signal "SMB_VR_SDA_PVCCIO_CPU1"
				( objectStatus "@baseboard_fab2_lib.baseboard_fab2(sch_1):smb_vr_sda_pvccio_cpu1" )
			)
			( signal "SVID_ALERT_PVCCIO_CPU1"
				( objectStatus "@baseboard_fab2_lib.baseboard_fab2(sch_1):svid_alert_pvccio_cpu1" )
			)
			( signal "SVID_CLK_PVCCIO_CPU1"
				( objectStatus "@baseboard_fab2_lib.baseboard_fab2(sch_1):svid_clk_pvccio_cpu1" )
			)
			( signal "SVID_VDIO_PVCCIO_CPU1"
				( objectStatus "@baseboard_fab2_lib.baseboard_fab2(sch_1):svid_vdio_pvccio_cpu1" )
			)
			( signal "TP_PVCCIO_CPU1_BIREF1"
				( objectStatus "@baseboard_fab2_lib.baseboard_fab2(sch_1):tp_pvccio_cpu1_biref1" )
			)
			( signal "TP_PVCCIO_CPU1_BPWM1"
				( objectStatus "@baseboard_fab2_lib.baseboard_fab2(sch_1):tp_pvccio_cpu1_bpwm1" )
			)
			( signal "TP_PVCCIO_CPU1_BTSEN"
				( objectStatus "@baseboard_fab2_lib.baseboard_fab2(sch_1):tp_pvccio_cpu1_btsen" )
			)
			( signal "TP_PVCCIO_CPU1_BVREF"
				( objectStatus "@baseboard_fab2_lib.baseboard_fab2(sch_1):tp_pvccio_cpu1_bvref" )
			)
			( signal "TP_PVCCIO_CPU1_BVSEN"
				( objectStatus "@baseboard_fab2_lib.baseboard_fab2(sch_1):tp_pvccio_cpu1_bvsen" )
			)
			( signal "TP_PVCCIO_CPU1_PINALRT_N"
				( objectStatus "@baseboard_fab2_lib.baseboard_fab2(sch_1):tp_pvccio_cpu1_pinalrt_n" )
			)
			( signal "TP_PVCCIO_CPU1_RESET_N"
				( objectStatus "@baseboard_fab2_lib.baseboard_fab2(sch_1):tp_pvccio_cpu1_reset_n" )
			)
			( signal "TP_VR_PVCCIO_CPU1_AIINSEN"
				( objectStatus "@baseboard_fab2_lib.baseboard_fab2(sch_1):tp_vr_pvccio_cpu1_aiinsen" )
			)
			( signal "TP_VR_PVCCIO_CPU1_MP0"
				( objectStatus "@baseboard_fab2_lib.baseboard_fab2(sch_1):tp_vr_pvccio_cpu1_mp0" )
			)
			( signal "TP_VR_PVCCIO_CPU1_MP1"
				( objectStatus "@baseboard_fab2_lib.baseboard_fab2(sch_1):tp_vr_pvccio_cpu1_mp1" )
			)
			( signal "TP_VR_PVCCIO_CPU1_MP2"
				( objectStatus "@baseboard_fab2_lib.baseboard_fab2(sch_1):tp_vr_pvccio_cpu1_mp2" )
			)
			( signal "TP_VR_PVCCIO_CPU1_MP3"
				( objectStatus "@baseboard_fab2_lib.baseboard_fab2(sch_1):tp_vr_pvccio_cpu1_mp3" )
			)
			( signal "VR_PVCCIO_CPU1_AIREF1"
				( objectStatus "@baseboard_fab2_lib.baseboard_fab2(sch_1):vr_pvccio_cpu1_airef1" )
			)
			( signal "VR_PVCCIO_CPU1_AVSP"
				( attribute "VOLTAGE" "1.05"
					( Units "uVoltage" "V" 1.000000)
					( Status sAliasFlattened )
					( Origin gFrontEnd )
				)
				( objectStatus "@baseboard_fab2_lib.baseboard_fab2(sch_1):vr_pvccio_cpu1_avsp" )
			)
			( signal "VR_PVCCIO_CPU1_EN"
				( attribute "VOLTAGE" "3.3"
					( Units "uVoltage" "V" 1.000000)
					( Status sAliasFlattened )
					( Origin gFrontEnd )
				)
				( objectStatus "@baseboard_fab2_lib.baseboard_fab2(sch_1):vr_pvccio_cpu1_en" )
			)
			( signal "VR_PVCCIO_CPU1_PWM1"
				( attribute "VOLTAGE" "3.6"
					( Units "uVoltage" "V" 1.000000)
					( Status sAliasFlattened )
					( Origin gFrontEnd )
				)
				( objectStatus "@baseboard_fab2_lib.baseboard_fab2(sch_1):vr_pvccio_cpu1_pwm1" )
			)
			( signal "VR_PVCCIO_CPU1_VD12"
				( objectStatus "@baseboard_fab2_lib.baseboard_fab2(sch_1):vr_pvccio_cpu1_vd12" )
			)
			( signal "VR_PVCCIO_CPU1_VDD"
				( attribute "VOLTAGE" "3.3"
					( Units "uVoltage" "V" 1.000000)
					( Status sAliasFlattened )
					( Origin gFrontEnd )
				)
				( objectStatus "@baseboard_fab2_lib.baseboard_fab2(sch_1):vr_pvccio_cpu1_vdd" )
			)
			( signal "VR_PVCCIO_CPU1_VINSEN"
				( objectStatus "@baseboard_fab2_lib.baseboard_fab2(sch_1):vr_pvccio_cpu1_vinsen" )
			)
			( signal "VR_PVCCIO_CPU1_XADDR1"
				( attribute "VOLTAGE" "3.3"
					( Units "uVoltage" "V" 1.000000)
					( Status sAliasFlattened )
					( Origin gFrontEnd )
				)
				( objectStatus "@baseboard_fab2_lib.baseboard_fab2(sch_1):vr_pvccio_cpu1_xaddr1" )
			)
			( signal "VR_PVCCIO_CPU1_XADDR2"
				( attribute "VOLTAGE" "3.3"
					( Units "uVoltage" "V" 1.000000)
					( Status sAliasFlattened )
					( Origin gFrontEnd )
				)
				( objectStatus "@baseboard_fab2_lib.baseboard_fab2(sch_1):vr_pvccio_cpu1_xaddr2" )
			)
			( signal "VSENSE_PVCCIO_CPU1_AVSN"
				( objectStatus "@baseboard_fab2_lib.baseboard_fab2(sch_1):vsense_pvccio_cpu1_avsn" )
			)
			( signal "VSENSE_PVCCIO_CPU1_AVSP"
				( objectStatus "@baseboard_fab2_lib.baseboard_fab2(sch_1):vsense_pvccio_cpu1_avsp" )
			)
			( signal "NC_PVCCIO_CPU1_PH1_P31"
				( objectStatus "@baseboard_fab2_lib.baseboard_fab2(sch_1):nc_pvccio_cpu1_ph1_p31" )
			)
			( signal "TP_PVCCIO_CPU1_GL_0"
				( objectStatus "@baseboard_fab2_lib.baseboard_fab2(sch_1):tp_pvccio_cpu1_gl_0" )
			)
			( signal "TP_PVCCIO_CPU1_GL_1"
				( objectStatus "@baseboard_fab2_lib.baseboard_fab2(sch_1):tp_pvccio_cpu1_gl_1" )
			)
			( signal "VR_PVCCIO_CPU1_OCSET"
				( objectStatus "@baseboard_fab2_lib.baseboard_fab2(sch_1):vr_pvccio_cpu1_ocset" )
			)
			( signal "VR_PVCCIO_CPU1_PH1_BOOT"
				( objectStatus "@baseboard_fab2_lib.baseboard_fab2(sch_1):vr_pvccio_cpu1_ph1_boot" )
			)
			( signal "VR_PVCCIO_CPU1_PH1_PHASE"
				( objectStatus "@baseboard_fab2_lib.baseboard_fab2(sch_1):vr_pvccio_cpu1_ph1_phase" )
			)
			( signal "VR_PVCCIO_CPU1_PH1_SW"
				( objectStatus "@baseboard_fab2_lib.baseboard_fab2(sch_1):vr_pvccio_cpu1_ph1_sw" )
			)
			( signal "VR_PVCCIO_CPU1_PH1_VCIN"
				( objectStatus "@baseboard_fab2_lib.baseboard_fab2(sch_1):vr_pvccio_cpu1_ph1_vcin" )
			)
			( signal "A_TSENSE_PVDDQ_ABC"
				( objectStatus "@baseboard_fab2_lib.baseboard_fab2(sch_1):a_tsense_pvddq_abc" )
			)
			( signal "IRQ_PVDDQ_ABC_VRHOT_LVT3_R_N"
				( objectStatus "@baseboard_fab2_lib.baseboard_fab2(sch_1):irq_pvddq_abc_vrhot_lvt3_r_n" )
			)
			( signal "ISENSE_PVDDQ_ABC_PH1_IMON"
				( objectStatus "@baseboard_fab2_lib.baseboard_fab2(sch_1):isense_pvddq_abc_ph1_imon" )
			)
			( signal "ISENSE_PVDDQ_ABC_PH2_IMON"
				( objectStatus "@baseboard_fab2_lib.baseboard_fab2(sch_1):isense_pvddq_abc_ph2_imon" )
			)
			( signal "NC_PVDDQ_ABC_DNC0"
				( objectStatus "@baseboard_fab2_lib.baseboard_fab2(sch_1):nc_pvddq_abc_dnc0" )
			)
			( signal "NC_PVDDQ_ABC_DNC1"
				( objectStatus "@baseboard_fab2_lib.baseboard_fab2(sch_1):nc_pvddq_abc_dnc1" )
			)
			( signal "PU_VR_PVDDQ_ABC_FAULT1"
				( objectStatus "@baseboard_fab2_lib.baseboard_fab2(sch_1):pu_vr_pvddq_abc_fault1" )
			)
			( signal "PWRGD_PVDDQ_ABC"
				( objectStatus "@baseboard_fab2_lib.baseboard_fab2(sch_1):pwrgd_pvddq_abc" )
			)
			( signal "PWRGD_PVDDQ_ABC_R"
				( objectStatus "@baseboard_fab2_lib.baseboard_fab2(sch_1):pwrgd_pvddq_abc_r" )
			)
			( signal "SMB_VR_SCL_VDDQ_ABC"
				( objectStatus "@baseboard_fab2_lib.baseboard_fab2(sch_1):smb_vr_scl_vddq_abc" )
			)
			( signal "SMB_VR_SDA_VDDQ_ABC"
				( objectStatus "@baseboard_fab2_lib.baseboard_fab2(sch_1):smb_vr_sda_vddq_abc" )
			)
			( signal "SVID_ALERT_PVDDQ_ABC"
				( objectStatus "@baseboard_fab2_lib.baseboard_fab2(sch_1):svid_alert_pvddq_abc" )
			)
			( signal "SVID_CLK_PVDDQ_ABC"
				( objectStatus "@baseboard_fab2_lib.baseboard_fab2(sch_1):svid_clk_pvddq_abc" )
			)
			( signal "SVID_VDIO_PVDDQ_ABC"
				( objectStatus "@baseboard_fab2_lib.baseboard_fab2(sch_1):svid_vdio_pvddq_abc" )
			)
			( signal "TP_PVDDQ_ABC_BPWM1"
				( objectStatus "@baseboard_fab2_lib.baseboard_fab2(sch_1):tp_pvddq_abc_bpwm1" )
			)
			( signal "TP_PVDDQ_ABC_BREF1"
				( objectStatus "@baseboard_fab2_lib.baseboard_fab2(sch_1):tp_pvddq_abc_bref1" )
			)
			( signal "TP_PVDDQ_ABC_BTSEN"
				( objectStatus "@baseboard_fab2_lib.baseboard_fab2(sch_1):tp_pvddq_abc_btsen" )
			)
			( signal "TP_PVDDQ_ABC_BVREF"
				( objectStatus "@baseboard_fab2_lib.baseboard_fab2(sch_1):tp_pvddq_abc_bvref" )
			)
			( signal "TP_PVDDQ_ABC_BVSEN"
				( objectStatus "@baseboard_fab2_lib.baseboard_fab2(sch_1):tp_pvddq_abc_bvsen" )
			)
			( signal "TP_PVDDQ_ABC_MP1"
				( objectStatus "@baseboard_fab2_lib.baseboard_fab2(sch_1):tp_pvddq_abc_mp1" )
			)
			( signal "TP_PVDDQ_ABC_MP2"
				( objectStatus "@baseboard_fab2_lib.baseboard_fab2(sch_1):tp_pvddq_abc_mp2" )
			)
			( signal "TP_PVDDQ_ABC_PH3_IMON"
				( objectStatus "@baseboard_fab2_lib.baseboard_fab2(sch_1):tp_pvddq_abc_ph3_imon" )
			)
			( signal "TP_PVDDQ_ABC_PH3_IMON_REF"
				( objectStatus "@baseboard_fab2_lib.baseboard_fab2(sch_1):tp_pvddq_abc_ph3_imon_ref" )
			)
			( signal "TP_PVDDQ_ABC_PINALRT_N"
				( objectStatus "@baseboard_fab2_lib.baseboard_fab2(sch_1):tp_pvddq_abc_pinalrt_n" )
			)
			( signal "TP_PVDDQ_ABC_PWM3"
				( objectStatus "@baseboard_fab2_lib.baseboard_fab2(sch_1):tp_pvddq_abc_pwm3" )
			)
			( signal "TP_PVDDQ_ABC_RESET_N"
				( objectStatus "@baseboard_fab2_lib.baseboard_fab2(sch_1):tp_pvddq_abc_reset_n" )
			)
			( signal "VR_FET_SW_P12V_STBY_PVDDQ_ABC"
				( objectStatus "@baseboard_fab2_lib.baseboard_fab2(sch_1):vr_fet_sw_p12v_stby_pvddq_abc" )
			)
			( signal "VR_PVDDQ_ABC_AIREF1"
				( objectStatus "@baseboard_fab2_lib.baseboard_fab2(sch_1):vr_pvddq_abc_airef1" )
			)
			( signal "VR_PVDDQ_ABC_AIREF2"
				( objectStatus "@baseboard_fab2_lib.baseboard_fab2(sch_1):vr_pvddq_abc_airef2" )
			)
			( signal "VR_PVDDQ_ABC_AVSP"
				( objectStatus "@baseboard_fab2_lib.baseboard_fab2(sch_1):vr_pvddq_abc_avsp" )
			)
			( signal "VR_PVDDQ_ABC_PWM1"
				( objectStatus "@baseboard_fab2_lib.baseboard_fab2(sch_1):vr_pvddq_abc_pwm1" )
			)
			( signal "VR_PVDDQ_ABC_PWM2"
				( objectStatus "@baseboard_fab2_lib.baseboard_fab2(sch_1):vr_pvddq_abc_pwm2" )
			)
			( signal "VR_PVDDQ_ABC_VD12"
				( objectStatus "@baseboard_fab2_lib.baseboard_fab2(sch_1):vr_pvddq_abc_vd12" )
			)
			( signal "VR_PVDDQ_ABC_VDD"
				( objectStatus "@baseboard_fab2_lib.baseboard_fab2(sch_1):vr_pvddq_abc_vdd" )
			)
			( signal "VR_PVDDQ_ABC_VINSEN"
				( objectStatus "@baseboard_fab2_lib.baseboard_fab2(sch_1):vr_pvddq_abc_vinsen" )
			)
			( signal "VR_PVDDQ_ABC_VREN"
				( objectStatus "@baseboard_fab2_lib.baseboard_fab2(sch_1):vr_pvddq_abc_vren" )
			)
			( signal "VR_PVDDQ_ABC_XADDR1"
				( objectStatus "@baseboard_fab2_lib.baseboard_fab2(sch_1):vr_pvddq_abc_xaddr1" )
			)
			( signal "VR_PVDDQ_ABC_XADDR2"
				( objectStatus "@baseboard_fab2_lib.baseboard_fab2(sch_1):vr_pvddq_abc_xaddr2" )
			)
			( signal "VSENSE_PVDDQ_ABC_N"
				( objectStatus "@baseboard_fab2_lib.baseboard_fab2(sch_1):vsense_pvddq_abc_n" )
			)
			( signal "VSENSE_PVDDQ_ABC_P"
				( objectStatus "@baseboard_fab2_lib.baseboard_fab2(sch_1):vsense_pvddq_abc_p" )
			)
			( signal "NC_PVDDQ_ABC_PH1_P31"
				( objectStatus "@baseboard_fab2_lib.baseboard_fab2(sch_1):nc_pvddq_abc_ph1_p31" )
			)
			( signal "NC_PVDDQ_ABC_PH2_P31"
				( objectStatus "@baseboard_fab2_lib.baseboard_fab2(sch_1):nc_pvddq_abc_ph2_p31" )
			)
			( signal "TP_PVDDQ_ABC_PH1_GL_0"
				( objectStatus "@baseboard_fab2_lib.baseboard_fab2(sch_1):tp_pvddq_abc_ph1_gl_0" )
			)
			( signal "TP_PVDDQ_ABC_PH1_GL_1"
				( objectStatus "@baseboard_fab2_lib.baseboard_fab2(sch_1):tp_pvddq_abc_ph1_gl_1" )
			)
			( signal "TP_PVDDQ_ABC_PH2_GL_0"
				( objectStatus "@baseboard_fab2_lib.baseboard_fab2(sch_1):tp_pvddq_abc_ph2_gl_0" )
			)
			( signal "TP_PVDDQ_ABC_PH2_GL_1"
				( objectStatus "@baseboard_fab2_lib.baseboard_fab2(sch_1):tp_pvddq_abc_ph2_gl_1" )
			)
			( signal "VR_PVDDQ_ABC_PH1_BOOT"
				( objectStatus "@baseboard_fab2_lib.baseboard_fab2(sch_1):vr_pvddq_abc_ph1_boot" )
			)
			( signal "VR_PVDDQ_ABC_PH1_OCSET"
				( attribute "VOLTAGE" "3.6"
					( Units "uVoltage" "V" 1.000000)
					( Status sAliasFlattened )
					( Origin gFrontEnd )
				)
				( objectStatus "@baseboard_fab2_lib.baseboard_fab2(sch_1):vr_pvddq_abc_ph1_ocset" )
			)
			( signal "VR_PVDDQ_ABC_PH1_PHASE"
				( objectStatus "@baseboard_fab2_lib.baseboard_fab2(sch_1):vr_pvddq_abc_ph1_phase" )
			)
			( signal "VR_PVDDQ_ABC_PH1_SW"
				( objectStatus "@baseboard_fab2_lib.baseboard_fab2(sch_1):vr_pvddq_abc_ph1_sw" )
			)
			( signal "VR_PVDDQ_ABC_PH1_VCIN"
				( objectStatus "@baseboard_fab2_lib.baseboard_fab2(sch_1):vr_pvddq_abc_ph1_vcin" )
			)
			( signal "VR_PVDDQ_ABC_PH2_BOOT"
				( objectStatus "@baseboard_fab2_lib.baseboard_fab2(sch_1):vr_pvddq_abc_ph2_boot" )
			)
			( signal "VR_PVDDQ_ABC_PH2_OCSET"
				( attribute "VOLTAGE" "3.6"
					( Units "uVoltage" "V" 1.000000)
					( Status sAliasFlattened )
					( Origin gFrontEnd )
				)
				( objectStatus "@baseboard_fab2_lib.baseboard_fab2(sch_1):vr_pvddq_abc_ph2_ocset" )
			)
			( signal "VR_PVDDQ_ABC_PH2_PHASE"
				( objectStatus "@baseboard_fab2_lib.baseboard_fab2(sch_1):vr_pvddq_abc_ph2_phase" )
			)
			( signal "VR_PVDDQ_ABC_PH2_SW"
				( objectStatus "@baseboard_fab2_lib.baseboard_fab2(sch_1):vr_pvddq_abc_ph2_sw" )
			)
			( signal "VR_PVDDQ_ABC_PH2_VCIN"
				( objectStatus "@baseboard_fab2_lib.baseboard_fab2(sch_1):vr_pvddq_abc_ph2_vcin" )
			)
			( signal "A_TSENSE_PVDDQ_DEF"
				( objectStatus "@baseboard_fab2_lib.baseboard_fab2(sch_1):a_tsense_pvddq_def" )
			)
			( signal "IRQ_PVDDQ_DEF_VRHOT_LVT3_R_N"
				( objectStatus "@baseboard_fab2_lib.baseboard_fab2(sch_1):irq_pvddq_def_vrhot_lvt3_r_n" )
			)
			( signal "ISENSE_PVDDQ_DEF_PH1_IMON"
				( objectStatus "@baseboard_fab2_lib.baseboard_fab2(sch_1):isense_pvddq_def_ph1_imon" )
			)
			( signal "ISENSE_PVDDQ_DEF_PH2_IMON"
				( objectStatus "@baseboard_fab2_lib.baseboard_fab2(sch_1):isense_pvddq_def_ph2_imon" )
			)
			( signal "NC_PVDDQ_DEF_DNC0"
				( objectStatus "@baseboard_fab2_lib.baseboard_fab2(sch_1):nc_pvddq_def_dnc0" )
			)
			( signal "NC_PVDDQ_DEF_DNC1"
				( objectStatus "@baseboard_fab2_lib.baseboard_fab2(sch_1):nc_pvddq_def_dnc1" )
			)
			( signal "PU_VR_PVDDQ_DEF_FAULT1"
				( objectStatus "@baseboard_fab2_lib.baseboard_fab2(sch_1):pu_vr_pvddq_def_fault1" )
			)
			( signal "PWRGD_PVDDQ_DEF"
				( objectStatus "@baseboard_fab2_lib.baseboard_fab2(sch_1):pwrgd_pvddq_def" )
			)
			( signal "PWRGD_PVDDQ_DEF_R"
				( objectStatus "@baseboard_fab2_lib.baseboard_fab2(sch_1):pwrgd_pvddq_def_r" )
			)
			( signal "SMB_VR_SCL_VDDQ_DEF"
				( objectStatus "@baseboard_fab2_lib.baseboard_fab2(sch_1):smb_vr_scl_vddq_def" )
			)
			( signal "SMB_VR_SDA_VDDQ_DEF"
				( objectStatus "@baseboard_fab2_lib.baseboard_fab2(sch_1):smb_vr_sda_vddq_def" )
			)
			( signal "SVID_ALERT_PVDDQ_DEF"
				( objectStatus "@baseboard_fab2_lib.baseboard_fab2(sch_1):svid_alert_pvddq_def" )
			)
			( signal "SVID_CLK_PVDDQ_DEF"
				( objectStatus "@baseboard_fab2_lib.baseboard_fab2(sch_1):svid_clk_pvddq_def" )
			)
			( signal "SVID_VDIO_PVDDQ_DEF"
				( objectStatus "@baseboard_fab2_lib.baseboard_fab2(sch_1):svid_vdio_pvddq_def" )
			)
			( signal "TP_PVDDQ_DEF_BPWM1"
				( objectStatus "@baseboard_fab2_lib.baseboard_fab2(sch_1):tp_pvddq_def_bpwm1" )
			)
			( signal "TP_PVDDQ_DEF_BREF1"
				( objectStatus "@baseboard_fab2_lib.baseboard_fab2(sch_1):tp_pvddq_def_bref1" )
			)
			( signal "TP_PVDDQ_DEF_BTSEN"
				( objectStatus "@baseboard_fab2_lib.baseboard_fab2(sch_1):tp_pvddq_def_btsen" )
			)
			( signal "TP_PVDDQ_DEF_BVREF"
				( objectStatus "@baseboard_fab2_lib.baseboard_fab2(sch_1):tp_pvddq_def_bvref" )
			)
			( signal "TP_PVDDQ_DEF_BVSEN"
				( objectStatus "@baseboard_fab2_lib.baseboard_fab2(sch_1):tp_pvddq_def_bvsen" )
			)
			( signal "TP_PVDDQ_DEF_MP1"
				( objectStatus "@baseboard_fab2_lib.baseboard_fab2(sch_1):tp_pvddq_def_mp1" )
			)
			( signal "TP_PVDDQ_DEF_MP2"
				( objectStatus "@baseboard_fab2_lib.baseboard_fab2(sch_1):tp_pvddq_def_mp2" )
			)
			( signal "TP_PVDDQ_DEF_PH3_IMON"
				( objectStatus "@baseboard_fab2_lib.baseboard_fab2(sch_1):tp_pvddq_def_ph3_imon" )
			)
			( signal "TP_PVDDQ_DEF_PH3_IMON_REF"
				( objectStatus "@baseboard_fab2_lib.baseboard_fab2(sch_1):tp_pvddq_def_ph3_imon_ref" )
			)
			( signal "TP_PVDDQ_DEF_PINALRT_N"
				( objectStatus "@baseboard_fab2_lib.baseboard_fab2(sch_1):tp_pvddq_def_pinalrt_n" )
			)
			( signal "TP_PVDDQ_DEF_PWM3"
				( objectStatus "@baseboard_fab2_lib.baseboard_fab2(sch_1):tp_pvddq_def_pwm3" )
			)
			( signal "TP_PVDDQ_DEF_RESET_N"
				( objectStatus "@baseboard_fab2_lib.baseboard_fab2(sch_1):tp_pvddq_def_reset_n" )
			)
			( signal "VR_FET_SW_P12V_STBY_PVDDQ_DEF"
				( objectStatus "@baseboard_fab2_lib.baseboard_fab2(sch_1):vr_fet_sw_p12v_stby_pvddq_def" )
			)
			( signal "VR_PVDDQ_DEF_AIREF1"
				( objectStatus "@baseboard_fab2_lib.baseboard_fab2(sch_1):vr_pvddq_def_airef1" )
			)
			( signal "VR_PVDDQ_DEF_AIREF2"
				( objectStatus "@baseboard_fab2_lib.baseboard_fab2(sch_1):vr_pvddq_def_airef2" )
			)
			( signal "VR_PVDDQ_DEF_AVSP"
				( objectStatus "@baseboard_fab2_lib.baseboard_fab2(sch_1):vr_pvddq_def_avsp" )
			)
			( signal "VR_PVDDQ_DEF_PWM1"
				( objectStatus "@baseboard_fab2_lib.baseboard_fab2(sch_1):vr_pvddq_def_pwm1" )
			)
			( signal "VR_PVDDQ_DEF_PWM2"
				( objectStatus "@baseboard_fab2_lib.baseboard_fab2(sch_1):vr_pvddq_def_pwm2" )
			)
			( signal "VR_PVDDQ_DEF_VD12"
				( objectStatus "@baseboard_fab2_lib.baseboard_fab2(sch_1):vr_pvddq_def_vd12" )
			)
			( signal "VR_PVDDQ_DEF_VDD"
				( objectStatus "@baseboard_fab2_lib.baseboard_fab2(sch_1):vr_pvddq_def_vdd" )
			)
			( signal "VR_PVDDQ_DEF_VINSEN"
				( objectStatus "@baseboard_fab2_lib.baseboard_fab2(sch_1):vr_pvddq_def_vinsen" )
			)
			( signal "VR_PVDDQ_DEF_VREN"
				( objectStatus "@baseboard_fab2_lib.baseboard_fab2(sch_1):vr_pvddq_def_vren" )
			)
			( signal "VR_PVDDQ_DEF_XADDR1"
				( objectStatus "@baseboard_fab2_lib.baseboard_fab2(sch_1):vr_pvddq_def_xaddr1" )
			)
			( signal "VR_PVDDQ_DEF_XADDR2"
				( objectStatus "@baseboard_fab2_lib.baseboard_fab2(sch_1):vr_pvddq_def_xaddr2" )
			)
			( signal "VSENSE_PVDDQ_DEF_N"
				( objectStatus "@baseboard_fab2_lib.baseboard_fab2(sch_1):vsense_pvddq_def_n" )
			)
			( signal "VSENSE_PVDDQ_DEF_P"
				( objectStatus "@baseboard_fab2_lib.baseboard_fab2(sch_1):vsense_pvddq_def_p" )
			)
			( signal "NC_PVDDQ_DEF_PH1_P31"
				( objectStatus "@baseboard_fab2_lib.baseboard_fab2(sch_1):nc_pvddq_def_ph1_p31" )
			)
			( signal "NC_PVDDQ_DEF_PH2_P31"
				( objectStatus "@baseboard_fab2_lib.baseboard_fab2(sch_1):nc_pvddq_def_ph2_p31" )
			)
			( signal "TP_PVDDQ_DEF_PH1_GL_0"
				( objectStatus "@baseboard_fab2_lib.baseboard_fab2(sch_1):tp_pvddq_def_ph1_gl_0" )
			)
			( signal "TP_PVDDQ_DEF_PH1_GL_1"
				( objectStatus "@baseboard_fab2_lib.baseboard_fab2(sch_1):tp_pvddq_def_ph1_gl_1" )
			)
			( signal "TP_PVDDQ_DEF_PH2_GL_0"
				( objectStatus "@baseboard_fab2_lib.baseboard_fab2(sch_1):tp_pvddq_def_ph2_gl_0" )
			)
			( signal "TP_PVDDQ_DEF_PH2_GL_1"
				( objectStatus "@baseboard_fab2_lib.baseboard_fab2(sch_1):tp_pvddq_def_ph2_gl_1" )
			)
			( signal "VR_PVDDQ_DEF_PH1_BOOT"
				( objectStatus "@baseboard_fab2_lib.baseboard_fab2(sch_1):vr_pvddq_def_ph1_boot" )
			)
			( signal "VR_PVDDQ_DEF_PH1_OCSET"
				( attribute "VOLTAGE" "3.6"
					( Units "uVoltage" "V" 1.000000)
					( Status sAliasFlattened )
					( Origin gFrontEnd )
				)
				( objectStatus "@baseboard_fab2_lib.baseboard_fab2(sch_1):vr_pvddq_def_ph1_ocset" )
			)
			( signal "VR_PVDDQ_DEF_PH1_PHASE"
				( objectStatus "@baseboard_fab2_lib.baseboard_fab2(sch_1):vr_pvddq_def_ph1_phase" )
			)
			( signal "VR_PVDDQ_DEF_PH1_SW"
				( objectStatus "@baseboard_fab2_lib.baseboard_fab2(sch_1):vr_pvddq_def_ph1_sw" )
			)
			( signal "VR_PVDDQ_DEF_PH1_VCIN"
				( objectStatus "@baseboard_fab2_lib.baseboard_fab2(sch_1):vr_pvddq_def_ph1_vcin" )
			)
			( signal "VR_PVDDQ_DEF_PH2_BOOT"
				( objectStatus "@baseboard_fab2_lib.baseboard_fab2(sch_1):vr_pvddq_def_ph2_boot" )
			)
			( signal "VR_PVDDQ_DEF_PH2_OCSET"
				( attribute "VOLTAGE" "3.6"
					( Units "uVoltage" "V" 1.000000)
					( Status sAliasFlattened )
					( Origin gFrontEnd )
				)
				( objectStatus "@baseboard_fab2_lib.baseboard_fab2(sch_1):vr_pvddq_def_ph2_ocset" )
			)
			( signal "VR_PVDDQ_DEF_PH2_PHASE"
				( objectStatus "@baseboard_fab2_lib.baseboard_fab2(sch_1):vr_pvddq_def_ph2_phase" )
			)
			( signal "VR_PVDDQ_DEF_PH2_SW"
				( objectStatus "@baseboard_fab2_lib.baseboard_fab2(sch_1):vr_pvddq_def_ph2_sw" )
			)
			( signal "VR_PVDDQ_DEF_PH2_VCIN"
				( objectStatus "@baseboard_fab2_lib.baseboard_fab2(sch_1):vr_pvddq_def_ph2_vcin" )
			)
			( signal "FM_PVTT_ABC_EN_R"
				( objectStatus "@baseboard_fab2_lib.baseboard_fab2(sch_1):fm_pvtt_abc_en_r" )
			)
			( signal "PWRGD_PVTT_ABC_CPU0_R"
				( objectStatus "@baseboard_fab2_lib.baseboard_fab2(sch_1):pwrgd_pvtt_abc_cpu0_r" )
			)
			( signal "VR_PVTT_ABC_BIAS"
				( objectStatus "@baseboard_fab2_lib.baseboard_fab2(sch_1):vr_pvtt_abc_bias" )
			)
			( signal "VR_PVTT_ABC_SNS"
				( objectStatus "@baseboard_fab2_lib.baseboard_fab2(sch_1):vr_pvtt_abc_sns" )
			)
			( signal "VR_PVTT_ABC_VREF"
				( objectStatus "@baseboard_fab2_lib.baseboard_fab2(sch_1):vr_pvtt_abc_vref" )
			)
			( signal "VSENSE_PVDDQ_ABC_VTT"
				( objectStatus "@baseboard_fab2_lib.baseboard_fab2(sch_1):vsense_pvddq_abc_vtt" )
			)
			( signal "FM_PVTT_DEF_EN_R"
				( objectStatus "@baseboard_fab2_lib.baseboard_fab2(sch_1):fm_pvtt_def_en_r" )
			)
			( signal "PWRGD_PVTT_DEF_CPU0_R"
				( objectStatus "@baseboard_fab2_lib.baseboard_fab2(sch_1):pwrgd_pvtt_def_cpu0_r" )
			)
			( signal "VR_PVTT_DEF_BIAS"
				( objectStatus "@baseboard_fab2_lib.baseboard_fab2(sch_1):vr_pvtt_def_bias" )
			)
			( signal "VR_PVTT_DEF_SNS"
				( objectStatus "@baseboard_fab2_lib.baseboard_fab2(sch_1):vr_pvtt_def_sns" )
			)
			( signal "VR_PVTT_DEF_VREF"
				( objectStatus "@baseboard_fab2_lib.baseboard_fab2(sch_1):vr_pvtt_def_vref" )
			)
			( signal "VSENSE_PVDDQ_DEF_VTT"
				( objectStatus "@baseboard_fab2_lib.baseboard_fab2(sch_1):vsense_pvddq_def_vtt" )
			)
			( signal "A_TSENSE_PVDDQ_GHJ"
				( objectStatus "@baseboard_fab2_lib.baseboard_fab2(sch_1):a_tsense_pvddq_ghj" )
			)
			( signal "IRQ_PVDDQ_GHJ_VRHOT_LVT3_R_N"
				( objectStatus "@baseboard_fab2_lib.baseboard_fab2(sch_1):irq_pvddq_ghj_vrhot_lvt3_r_n" )
			)
			( signal "ISENSE_PVDDQ_GHJ_PH1_IMON"
				( objectStatus "@baseboard_fab2_lib.baseboard_fab2(sch_1):isense_pvddq_ghj_ph1_imon" )
			)
			( signal "ISENSE_PVDDQ_GHJ_PH2_IMON"
				( objectStatus "@baseboard_fab2_lib.baseboard_fab2(sch_1):isense_pvddq_ghj_ph2_imon" )
			)
			( signal "NC_PVDDQ_GHJ_DNC0"
				( objectStatus "@baseboard_fab2_lib.baseboard_fab2(sch_1):nc_pvddq_ghj_dnc0" )
			)
			( signal "NC_PVDDQ_GHJ_DNC1"
				( objectStatus "@baseboard_fab2_lib.baseboard_fab2(sch_1):nc_pvddq_ghj_dnc1" )
			)
			( signal "NC_PVDDQ_GHJ_PINALRT_N"
				( objectStatus "@baseboard_fab2_lib.baseboard_fab2(sch_1):nc_pvddq_ghj_pinalrt_n" )
			)
			( signal "PU_VR_PVDDQ_GHJ_FAULT1"
				( objectStatus "@baseboard_fab2_lib.baseboard_fab2(sch_1):pu_vr_pvddq_ghj_fault1" )
			)
			( signal "PWRGD_PVDDQ_GHJ"
				( objectStatus "@baseboard_fab2_lib.baseboard_fab2(sch_1):pwrgd_pvddq_ghj" )
			)
			( signal "PWRGD_PVDDQ_GHJ_R"
				( objectStatus "@baseboard_fab2_lib.baseboard_fab2(sch_1):pwrgd_pvddq_ghj_r" )
			)
			( signal "SMB_VR_SCL_VDDQ_GHJ"
				( objectStatus "@baseboard_fab2_lib.baseboard_fab2(sch_1):smb_vr_scl_vddq_ghj" )
			)
			( signal "SMB_VR_SDA_VDDQ_GHJ"
				( objectStatus "@baseboard_fab2_lib.baseboard_fab2(sch_1):smb_vr_sda_vddq_ghj" )
			)
			( signal "SVID_ALERT_PVDDQ_GHJ"
				( objectStatus "@baseboard_fab2_lib.baseboard_fab2(sch_1):svid_alert_pvddq_ghj" )
			)
			( signal "SVID_CLK_PVDDQ_GHJ"
				( objectStatus "@baseboard_fab2_lib.baseboard_fab2(sch_1):svid_clk_pvddq_ghj" )
			)
			( signal "SVID_VDIO_PVDDQ_GHJ"
				( objectStatus "@baseboard_fab2_lib.baseboard_fab2(sch_1):svid_vdio_pvddq_ghj" )
			)
			( signal "TP_PVDDQ_GHJ_BPWM1"
				( objectStatus "@baseboard_fab2_lib.baseboard_fab2(sch_1):tp_pvddq_ghj_bpwm1" )
			)
			( signal "TP_PVDDQ_GHJ_BREF1"
				( objectStatus "@baseboard_fab2_lib.baseboard_fab2(sch_1):tp_pvddq_ghj_bref1" )
			)
			( signal "TP_PVDDQ_GHJ_BTSEN"
				( objectStatus "@baseboard_fab2_lib.baseboard_fab2(sch_1):tp_pvddq_ghj_btsen" )
			)
			( signal "TP_PVDDQ_GHJ_BVREF"
				( objectStatus "@baseboard_fab2_lib.baseboard_fab2(sch_1):tp_pvddq_ghj_bvref" )
			)
			( signal "TP_PVDDQ_GHJ_BVSEN"
				( objectStatus "@baseboard_fab2_lib.baseboard_fab2(sch_1):tp_pvddq_ghj_bvsen" )
			)
			( signal "TP_PVDDQ_GHJ_MP1"
				( objectStatus "@baseboard_fab2_lib.baseboard_fab2(sch_1):tp_pvddq_ghj_mp1" )
			)
			( signal "TP_PVDDQ_GHJ_MP2"
				( objectStatus "@baseboard_fab2_lib.baseboard_fab2(sch_1):tp_pvddq_ghj_mp2" )
			)
			( signal "TP_PVDDQ_GHJ_PH3_IMON"
				( objectStatus "@baseboard_fab2_lib.baseboard_fab2(sch_1):tp_pvddq_ghj_ph3_imon" )
			)
			( signal "TP_PVDDQ_GHJ_PH3_IMON_REF"
				( objectStatus "@baseboard_fab2_lib.baseboard_fab2(sch_1):tp_pvddq_ghj_ph3_imon_ref" )
			)
			( signal "TP_PVDDQ_GHJ_PWM3"
				( objectStatus "@baseboard_fab2_lib.baseboard_fab2(sch_1):tp_pvddq_ghj_pwm3" )
			)
			( signal "TP_PVDDQ_GHJ_RESET_N"
				( objectStatus "@baseboard_fab2_lib.baseboard_fab2(sch_1):tp_pvddq_ghj_reset_n" )
			)
			( signal "VR_FET_SW_P12V_STBY_PVDDQ_GHJ"
				( objectStatus "@baseboard_fab2_lib.baseboard_fab2(sch_1):vr_fet_sw_p12v_stby_pvddq_ghj" )
			)
			( signal "VR_PVDDQ_GHJ_AIREF1"
				( objectStatus "@baseboard_fab2_lib.baseboard_fab2(sch_1):vr_pvddq_ghj_airef1" )
			)
			( signal "VR_PVDDQ_GHJ_AIREF2"
				( objectStatus "@baseboard_fab2_lib.baseboard_fab2(sch_1):vr_pvddq_ghj_airef2" )
			)
			( signal "VR_PVDDQ_GHJ_AVSP"
				( objectStatus "@baseboard_fab2_lib.baseboard_fab2(sch_1):vr_pvddq_ghj_avsp" )
			)
			( signal "VR_PVDDQ_GHJ_PWM1"
				( objectStatus "@baseboard_fab2_lib.baseboard_fab2(sch_1):vr_pvddq_ghj_pwm1" )
			)
			( signal "VR_PVDDQ_GHJ_PWM2"
				( objectStatus "@baseboard_fab2_lib.baseboard_fab2(sch_1):vr_pvddq_ghj_pwm2" )
			)
			( signal "VR_PVDDQ_GHJ_VD12"
				( objectStatus "@baseboard_fab2_lib.baseboard_fab2(sch_1):vr_pvddq_ghj_vd12" )
			)
			( signal "VR_PVDDQ_GHJ_VDD"
				( objectStatus "@baseboard_fab2_lib.baseboard_fab2(sch_1):vr_pvddq_ghj_vdd" )
			)
			( signal "VR_PVDDQ_GHJ_VINSEN"
				( objectStatus "@baseboard_fab2_lib.baseboard_fab2(sch_1):vr_pvddq_ghj_vinsen" )
			)
			( signal "VR_PVDDQ_GHJ_VREN"
				( objectStatus "@baseboard_fab2_lib.baseboard_fab2(sch_1):vr_pvddq_ghj_vren" )
			)
			( signal "VR_PVDDQ_GHJ_XADDR1"
				( objectStatus "@baseboard_fab2_lib.baseboard_fab2(sch_1):vr_pvddq_ghj_xaddr1" )
			)
			( signal "VR_PVDDQ_GHJ_XADDR2"
				( objectStatus "@baseboard_fab2_lib.baseboard_fab2(sch_1):vr_pvddq_ghj_xaddr2" )
			)
			( signal "VSENSE_PVDDQ_GHJ_N"
				( objectStatus "@baseboard_fab2_lib.baseboard_fab2(sch_1):vsense_pvddq_ghj_n" )
			)
			( signal "VSENSE_PVDDQ_GHJ_P"
				( objectStatus "@baseboard_fab2_lib.baseboard_fab2(sch_1):vsense_pvddq_ghj_p" )
			)
			( signal "NC_PVDDQ_GHJ_PH1_P31"
				( objectStatus "@baseboard_fab2_lib.baseboard_fab2(sch_1):nc_pvddq_ghj_ph1_p31" )
			)
			( signal "NC_PVDDQ_GHJ_PH2_P31"
				( objectStatus "@baseboard_fab2_lib.baseboard_fab2(sch_1):nc_pvddq_ghj_ph2_p31" )
			)
			( signal "TP_PVDDQ_GHJ_PH1_GL_0"
				( objectStatus "@baseboard_fab2_lib.baseboard_fab2(sch_1):tp_pvddq_ghj_ph1_gl_0" )
			)
			( signal "TP_PVDDQ_GHJ_PH1_GL_1"
				( objectStatus "@baseboard_fab2_lib.baseboard_fab2(sch_1):tp_pvddq_ghj_ph1_gl_1" )
			)
			( signal "TP_PVDDQ_GHJ_PH2_GL_0"
				( objectStatus "@baseboard_fab2_lib.baseboard_fab2(sch_1):tp_pvddq_ghj_ph2_gl_0" )
			)
			( signal "TP_PVDDQ_GHJ_PH2_GL_1"
				( objectStatus "@baseboard_fab2_lib.baseboard_fab2(sch_1):tp_pvddq_ghj_ph2_gl_1" )
			)
			( signal "VR_PVDDQ_GHJ_PH1_BOOT"
				( objectStatus "@baseboard_fab2_lib.baseboard_fab2(sch_1):vr_pvddq_ghj_ph1_boot" )
			)
			( signal "VR_PVDDQ_GHJ_PH1_OCSET"
				( attribute "VOLTAGE" "3.6"
					( Units "uVoltage" "V" 1.000000)
					( Status sAliasFlattened )
					( Origin gFrontEnd )
				)
				( objectStatus "@baseboard_fab2_lib.baseboard_fab2(sch_1):vr_pvddq_ghj_ph1_ocset" )
			)
			( signal "VR_PVDDQ_GHJ_PH1_PHASE"
				( objectStatus "@baseboard_fab2_lib.baseboard_fab2(sch_1):vr_pvddq_ghj_ph1_phase" )
			)
			( signal "VR_PVDDQ_GHJ_PH1_SW"
				( objectStatus "@baseboard_fab2_lib.baseboard_fab2(sch_1):vr_pvddq_ghj_ph1_sw" )
			)
			( signal "VR_PVDDQ_GHJ_PH1_VCIN"
				( objectStatus "@baseboard_fab2_lib.baseboard_fab2(sch_1):vr_pvddq_ghj_ph1_vcin" )
			)
			( signal "VR_PVDDQ_GHJ_PH2_BOOT"
				( objectStatus "@baseboard_fab2_lib.baseboard_fab2(sch_1):vr_pvddq_ghj_ph2_boot" )
			)
			( signal "VR_PVDDQ_GHJ_PH2_OCSET"
				( attribute "VOLTAGE" "3.6"
					( Units "uVoltage" "V" 1.000000)
					( Status sAliasFlattened )
					( Origin gFrontEnd )
				)
				( objectStatus "@baseboard_fab2_lib.baseboard_fab2(sch_1):vr_pvddq_ghj_ph2_ocset" )
			)
			( signal "VR_PVDDQ_GHJ_PH2_PHASE"
				( objectStatus "@baseboard_fab2_lib.baseboard_fab2(sch_1):vr_pvddq_ghj_ph2_phase" )
			)
			( signal "VR_PVDDQ_GHJ_PH2_SW"
				( objectStatus "@baseboard_fab2_lib.baseboard_fab2(sch_1):vr_pvddq_ghj_ph2_sw" )
			)
			( signal "VR_PVDDQ_GHJ_PH2_VCIN"
				( objectStatus "@baseboard_fab2_lib.baseboard_fab2(sch_1):vr_pvddq_ghj_ph2_vcin" )
			)
			( signal "A_TSENSE_PVDDQ_KLM"
				( objectStatus "@baseboard_fab2_lib.baseboard_fab2(sch_1):a_tsense_pvddq_klm" )
			)
			( signal "IRQ_PVDDQ_KLM_VRHOT_LVT3_R_N"
				( objectStatus "@baseboard_fab2_lib.baseboard_fab2(sch_1):irq_pvddq_klm_vrhot_lvt3_r_n" )
			)
			( signal "ISENSE_PVDDQ_KLM_PH1_IMON"
				( objectStatus "@baseboard_fab2_lib.baseboard_fab2(sch_1):isense_pvddq_klm_ph1_imon" )
			)
			( signal "ISENSE_PVDDQ_KLM_PH2_IMON"
				( objectStatus "@baseboard_fab2_lib.baseboard_fab2(sch_1):isense_pvddq_klm_ph2_imon" )
			)
			( signal "NC_PVDDQ_KLM_DNC0"
				( objectStatus "@baseboard_fab2_lib.baseboard_fab2(sch_1):nc_pvddq_klm_dnc0" )
			)
			( signal "NC_PVDDQ_KLM_DNC1"
				( objectStatus "@baseboard_fab2_lib.baseboard_fab2(sch_1):nc_pvddq_klm_dnc1" )
			)
			( signal "NC_PVDDQ_KLM_GP0"
				( objectStatus "@baseboard_fab2_lib.baseboard_fab2(sch_1):nc_pvddq_klm_gp0" )
			)
			( signal "NC_PVDDQ_KLM_GP1"
				( objectStatus "@baseboard_fab2_lib.baseboard_fab2(sch_1):nc_pvddq_klm_gp1" )
			)
			( signal "NC_PVDDQ_KLM_PINALRT_N"
				( objectStatus "@baseboard_fab2_lib.baseboard_fab2(sch_1):nc_pvddq_klm_pinalrt_n" )
			)
			( signal "NC_PVDDQ_KLM_PWM3"
				( objectStatus "@baseboard_fab2_lib.baseboard_fab2(sch_1):nc_pvddq_klm_pwm3" )
			)
			( signal "PU_VR_PVDDQ_KLM_FAULT1"
				( objectStatus "@baseboard_fab2_lib.baseboard_fab2(sch_1):pu_vr_pvddq_klm_fault1" )
			)
			( signal "PWRGD_PVDDQ_KLM"
				( objectStatus "@baseboard_fab2_lib.baseboard_fab2(sch_1):pwrgd_pvddq_klm" )
			)
			( signal "PWRGD_PVDDQ_KLM_R"
				( objectStatus "@baseboard_fab2_lib.baseboard_fab2(sch_1):pwrgd_pvddq_klm_r" )
			)
			( signal "SMB_VR_SCL_VDDQ_KLM"
				( objectStatus "@baseboard_fab2_lib.baseboard_fab2(sch_1):smb_vr_scl_vddq_klm" )
			)
			( signal "SMB_VR_SDA_VDDQ_KLM"
				( objectStatus "@baseboard_fab2_lib.baseboard_fab2(sch_1):smb_vr_sda_vddq_klm" )
			)
			( signal "SVID_ALERT_PVDDQ_KLM"
				( objectStatus "@baseboard_fab2_lib.baseboard_fab2(sch_1):svid_alert_pvddq_klm" )
			)
			( signal "SVID_CLK_PVDDQ_KLM"
				( objectStatus "@baseboard_fab2_lib.baseboard_fab2(sch_1):svid_clk_pvddq_klm" )
			)
			( signal "SVID_VDIO_PVDDQ_KLM"
				( objectStatus "@baseboard_fab2_lib.baseboard_fab2(sch_1):svid_vdio_pvddq_klm" )
			)
			( signal "TP_PVDDQ_KLM_BPWM1"
				( objectStatus "@baseboard_fab2_lib.baseboard_fab2(sch_1):tp_pvddq_klm_bpwm1" )
			)
			( signal "TP_PVDDQ_KLM_BREF1"
				( objectStatus "@baseboard_fab2_lib.baseboard_fab2(sch_1):tp_pvddq_klm_bref1" )
			)
			( signal "TP_PVDDQ_KLM_BTSEN"
				( objectStatus "@baseboard_fab2_lib.baseboard_fab2(sch_1):tp_pvddq_klm_btsen" )
			)
			( signal "TP_PVDDQ_KLM_BVREF"
				( objectStatus "@baseboard_fab2_lib.baseboard_fab2(sch_1):tp_pvddq_klm_bvref" )
			)
			( signal "TP_PVDDQ_KLM_BVSEN"
				( objectStatus "@baseboard_fab2_lib.baseboard_fab2(sch_1):tp_pvddq_klm_bvsen" )
			)
			( signal "TP_PVDDQ_KLM_PH3_IMON"
				( objectStatus "@baseboard_fab2_lib.baseboard_fab2(sch_1):tp_pvddq_klm_ph3_imon" )
			)
			( signal "TP_PVDDQ_KLM_PH3_IMON_REF"
				( objectStatus "@baseboard_fab2_lib.baseboard_fab2(sch_1):tp_pvddq_klm_ph3_imon_ref" )
			)
			( signal "TP_PVDDQ_KLM_RESET_N"
				( objectStatus "@baseboard_fab2_lib.baseboard_fab2(sch_1):tp_pvddq_klm_reset_n" )
			)
			( signal "VR_FET_SW_P12V_STBY_PVDDQ_KLM"
				( objectStatus "@baseboard_fab2_lib.baseboard_fab2(sch_1):vr_fet_sw_p12v_stby_pvddq_klm" )
			)
			( signal "VR_PVDDQ_KLM_AIREF1"
				( objectStatus "@baseboard_fab2_lib.baseboard_fab2(sch_1):vr_pvddq_klm_airef1" )
			)
			( signal "VR_PVDDQ_KLM_AIREF2"
				( objectStatus "@baseboard_fab2_lib.baseboard_fab2(sch_1):vr_pvddq_klm_airef2" )
			)
			( signal "VR_PVDDQ_KLM_AVSP"
				( objectStatus "@baseboard_fab2_lib.baseboard_fab2(sch_1):vr_pvddq_klm_avsp" )
			)
			( signal "VR_PVDDQ_KLM_PWM1"
				( objectStatus "@baseboard_fab2_lib.baseboard_fab2(sch_1):vr_pvddq_klm_pwm1" )
			)
			( signal "VR_PVDDQ_KLM_PWM2"
				( objectStatus "@baseboard_fab2_lib.baseboard_fab2(sch_1):vr_pvddq_klm_pwm2" )
			)
			( signal "VR_PVDDQ_KLM_VD12"
				( objectStatus "@baseboard_fab2_lib.baseboard_fab2(sch_1):vr_pvddq_klm_vd12" )
			)
			( signal "VR_PVDDQ_KLM_VDD"
				( objectStatus "@baseboard_fab2_lib.baseboard_fab2(sch_1):vr_pvddq_klm_vdd" )
			)
			( signal "VR_PVDDQ_KLM_VINSEN"
				( objectStatus "@baseboard_fab2_lib.baseboard_fab2(sch_1):vr_pvddq_klm_vinsen" )
			)
			( signal "VR_PVDDQ_KLM_VREN"
				( objectStatus "@baseboard_fab2_lib.baseboard_fab2(sch_1):vr_pvddq_klm_vren" )
			)
			( signal "VR_PVDDQ_KLM_XADDR1"
				( objectStatus "@baseboard_fab2_lib.baseboard_fab2(sch_1):vr_pvddq_klm_xaddr1" )
			)
			( signal "VR_PVDDQ_KLM_XADDR2"
				( objectStatus "@baseboard_fab2_lib.baseboard_fab2(sch_1):vr_pvddq_klm_xaddr2" )
			)
			( signal "VSENSE_PVDDQ_KLM_N"
				( objectStatus "@baseboard_fab2_lib.baseboard_fab2(sch_1):vsense_pvddq_klm_n" )
			)
			( signal "VSENSE_PVDDQ_KLM_P"
				( objectStatus "@baseboard_fab2_lib.baseboard_fab2(sch_1):vsense_pvddq_klm_p" )
			)
			( signal "NC_PVDDQ_KLM_PH1_P31"
				( objectStatus "@baseboard_fab2_lib.baseboard_fab2(sch_1):nc_pvddq_klm_ph1_p31" )
			)
			( signal "NC_PVDDQ_KLM_PH2_P31"
				( objectStatus "@baseboard_fab2_lib.baseboard_fab2(sch_1):nc_pvddq_klm_ph2_p31" )
			)
			( signal "TP_PVDDQ_KLM_PH1_GL_0"
				( objectStatus "@baseboard_fab2_lib.baseboard_fab2(sch_1):tp_pvddq_klm_ph1_gl_0" )
			)
			( signal "TP_PVDDQ_KLM_PH1_GL_1"
				( objectStatus "@baseboard_fab2_lib.baseboard_fab2(sch_1):tp_pvddq_klm_ph1_gl_1" )
			)
			( signal "TP_PVDDQ_KLM_PH2_GL_0"
				( objectStatus "@baseboard_fab2_lib.baseboard_fab2(sch_1):tp_pvddq_klm_ph2_gl_0" )
			)
			( signal "TP_PVDDQ_KLM_PH2_GL_1"
				( objectStatus "@baseboard_fab2_lib.baseboard_fab2(sch_1):tp_pvddq_klm_ph2_gl_1" )
			)
			( signal "VR_PVDDQ_KLM_PH1_BOOT"
				( objectStatus "@baseboard_fab2_lib.baseboard_fab2(sch_1):vr_pvddq_klm_ph1_boot" )
			)
			( signal "VR_PVDDQ_KLM_PH1_OCSET"
				( attribute "VOLTAGE" "3.6"
					( Units "uVoltage" "V" 1.000000)
					( Status sAliasFlattened )
					( Origin gFrontEnd )
				)
				( objectStatus "@baseboard_fab2_lib.baseboard_fab2(sch_1):vr_pvddq_klm_ph1_ocset" )
			)
			( signal "VR_PVDDQ_KLM_PH1_PHASE"
				( objectStatus "@baseboard_fab2_lib.baseboard_fab2(sch_1):vr_pvddq_klm_ph1_phase" )
			)
			( signal "VR_PVDDQ_KLM_PH1_SW"
				( objectStatus "@baseboard_fab2_lib.baseboard_fab2(sch_1):vr_pvddq_klm_ph1_sw" )
			)
			( signal "VR_PVDDQ_KLM_PH1_VCIN"
				( objectStatus "@baseboard_fab2_lib.baseboard_fab2(sch_1):vr_pvddq_klm_ph1_vcin" )
			)
			( signal "VR_PVDDQ_KLM_PH2_BOOT"
				( objectStatus "@baseboard_fab2_lib.baseboard_fab2(sch_1):vr_pvddq_klm_ph2_boot" )
			)
			( signal "VR_PVDDQ_KLM_PH2_OCSET"
				( attribute "VOLTAGE" "3.6"
					( Units "uVoltage" "V" 1.000000)
					( Status sAliasFlattened )
					( Origin gFrontEnd )
				)
				( objectStatus "@baseboard_fab2_lib.baseboard_fab2(sch_1):vr_pvddq_klm_ph2_ocset" )
			)
			( signal "VR_PVDDQ_KLM_PH2_PHASE"
				( objectStatus "@baseboard_fab2_lib.baseboard_fab2(sch_1):vr_pvddq_klm_ph2_phase" )
			)
			( signal "VR_PVDDQ_KLM_PH2_SW"
				( objectStatus "@baseboard_fab2_lib.baseboard_fab2(sch_1):vr_pvddq_klm_ph2_sw" )
			)
			( signal "VR_PVDDQ_KLM_PH2_VCIN"
				( objectStatus "@baseboard_fab2_lib.baseboard_fab2(sch_1):vr_pvddq_klm_ph2_vcin" )
			)
			( signal "FM_PVTT_GHJ_EN_R"
				( objectStatus "@baseboard_fab2_lib.baseboard_fab2(sch_1):fm_pvtt_ghj_en_r" )
			)
			( signal "PWRGD_PVTT_GHJ_CPU1_R"
				( objectStatus "@baseboard_fab2_lib.baseboard_fab2(sch_1):pwrgd_pvtt_ghj_cpu1_r" )
			)
			( signal "VR_PVTT_GHJ_BIAS"
				( objectStatus "@baseboard_fab2_lib.baseboard_fab2(sch_1):vr_pvtt_ghj_bias" )
			)
			( signal "VR_PVTT_GHJ_SNS"
				( objectStatus "@baseboard_fab2_lib.baseboard_fab2(sch_1):vr_pvtt_ghj_sns" )
			)
			( signal "VR_PVTT_GHJ_VREF"
				( objectStatus "@baseboard_fab2_lib.baseboard_fab2(sch_1):vr_pvtt_ghj_vref" )
			)
			( signal "VSENSE_PVDDQ_GHJ_VTT"
				( objectStatus "@baseboard_fab2_lib.baseboard_fab2(sch_1):vsense_pvddq_ghj_vtt" )
			)
			( signal "FM_PVTT_KLM_EN_R"
				( objectStatus "@baseboard_fab2_lib.baseboard_fab2(sch_1):fm_pvtt_klm_en_r" )
			)
			( signal "PWRGD_PVTT_KLM_CPU1_R"
				( objectStatus "@baseboard_fab2_lib.baseboard_fab2(sch_1):pwrgd_pvtt_klm_cpu1_r" )
			)
			( signal "VR_PVTT_KLM_BIAS"
				( objectStatus "@baseboard_fab2_lib.baseboard_fab2(sch_1):vr_pvtt_klm_bias" )
			)
			( signal "VR_PVTT_KLM_SNS"
				( objectStatus "@baseboard_fab2_lib.baseboard_fab2(sch_1):vr_pvtt_klm_sns" )
			)
			( signal "VR_PVTT_KLM_VREF"
				( objectStatus "@baseboard_fab2_lib.baseboard_fab2(sch_1):vr_pvtt_klm_vref" )
			)
			( signal "VSENSE_PVDDQ_KLM_VTT"
				( objectStatus "@baseboard_fab2_lib.baseboard_fab2(sch_1):vsense_pvddq_klm_vtt" )
			)
			( signal "AGND_PVPP_ABC"
				( attribute "VOLTAGE" "0.0V"
					( Units "uVoltage" "V" 1.000000)
					( Status sAliasFlattened )
					( Origin gFrontEnd )
				)
				( objectStatus "@baseboard_fab2_lib.baseboard_fab2(sch_1):agnd_pvpp_abc" )
			)
			( signal "FM_PVPP_PVDDQ_CPU0_EN_ABC"
				( objectStatus "@baseboard_fab2_lib.baseboard_fab2(sch_1):fm_pvpp_pvddq_cpu0_en_abc" )
			)
			( signal "PWRGD_PVPP_ABC_R"
				( objectStatus "@baseboard_fab2_lib.baseboard_fab2(sch_1):pwrgd_pvpp_abc_r" )
			)
			( signal "VR_COMP_PVPP_ABC"
				( objectStatus "@baseboard_fab2_lib.baseboard_fab2(sch_1):vr_comp_pvpp_abc" )
			)
			( signal "VR_COMP_PVPP_ABC_3"
				( objectStatus "@baseboard_fab2_lib.baseboard_fab2(sch_1):vr_comp_pvpp_abc_3" )
			)
			( signal "VR_COMP_RC_PVPP_ABC"
				( objectStatus "@baseboard_fab2_lib.baseboard_fab2(sch_1):vr_comp_rc_pvpp_abc" )
			)
			( signal "VR_FB_PVPP_ABC"
				( objectStatus "@baseboard_fab2_lib.baseboard_fab2(sch_1):vr_fb_pvpp_abc" )
			)
			( signal "VR_FET_SW_P12V_STBY_PVPP_ABC"
				( objectStatus "@baseboard_fab2_lib.baseboard_fab2(sch_1):vr_fet_sw_p12v_stby_pvpp_abc" )
			)
			( signal "VR_PVPP_ABC_BOOT"
				( objectStatus "@baseboard_fab2_lib.baseboard_fab2(sch_1):vr_pvpp_abc_boot" )
			)
			( signal "VR_PVPP_ABC_BOOT_R"
				( objectStatus "@baseboard_fab2_lib.baseboard_fab2(sch_1):vr_pvpp_abc_boot_r" )
			)
			( signal "VR_PVPP_ABC_ISET"
				( objectStatus "@baseboard_fab2_lib.baseboard_fab2(sch_1):vr_pvpp_abc_iset" )
			)
			( signal "VR_PVPP_ABC_PHASE"
				( objectStatus "@baseboard_fab2_lib.baseboard_fab2(sch_1):vr_pvpp_abc_phase" )
			)
			( signal "VR_PVPP_ABC_SNUB"
				( objectStatus "@baseboard_fab2_lib.baseboard_fab2(sch_1):vr_pvpp_abc_snub" )
			)
			( signal "VR_PVPP_ABC_SS"
				( objectStatus "@baseboard_fab2_lib.baseboard_fab2(sch_1):vr_pvpp_abc_ss" )
			)
			( signal "VR_VB_PVPP_ABC"
				( objectStatus "@baseboard_fab2_lib.baseboard_fab2(sch_1):vr_vb_pvpp_abc" )
			)
			( signal "VSENSE_PVPP_ABC"
				( objectStatus "@baseboard_fab2_lib.baseboard_fab2(sch_1):vsense_pvpp_abc" )
			)
			( signal "AGND_PVPP_DEF"
				( attribute "VOLTAGE" "0.0V"
					( Units "uVoltage" "V" 1.000000)
					( Status sAliasFlattened )
					( Origin gFrontEnd )
				)
				( objectStatus "@baseboard_fab2_lib.baseboard_fab2(sch_1):agnd_pvpp_def" )
			)
			( signal "FM_PVPP_PVDDQ_CPU0_EN_DEF"
				( objectStatus "@baseboard_fab2_lib.baseboard_fab2(sch_1):fm_pvpp_pvddq_cpu0_en_def" )
			)
			( signal "PWRGD_PVPP_DEF_R"
				( objectStatus "@baseboard_fab2_lib.baseboard_fab2(sch_1):pwrgd_pvpp_def_r" )
			)
			( signal "VR_COMP_PVPP_DEF"
				( objectStatus "@baseboard_fab2_lib.baseboard_fab2(sch_1):vr_comp_pvpp_def" )
			)
			( signal "VR_COMP_PVPP_DEF_3"
				( objectStatus "@baseboard_fab2_lib.baseboard_fab2(sch_1):vr_comp_pvpp_def_3" )
			)
			( signal "VR_COMP_RC_PVPP_DEF"
				( objectStatus "@baseboard_fab2_lib.baseboard_fab2(sch_1):vr_comp_rc_pvpp_def" )
			)
			( signal "VR_FB_PVPP_DEF"
				( objectStatus "@baseboard_fab2_lib.baseboard_fab2(sch_1):vr_fb_pvpp_def" )
			)
			( signal "VR_FET_SW_P12V_STBY_PVPP_DEF"
				( objectStatus "@baseboard_fab2_lib.baseboard_fab2(sch_1):vr_fet_sw_p12v_stby_pvpp_def" )
			)
			( signal "VR_PVPP_DEF_BOOT"
				( objectStatus "@baseboard_fab2_lib.baseboard_fab2(sch_1):vr_pvpp_def_boot" )
			)
			( signal "VR_PVPP_DEF_BOOT_R"
				( objectStatus "@baseboard_fab2_lib.baseboard_fab2(sch_1):vr_pvpp_def_boot_r" )
			)
			( signal "VR_PVPP_DEF_ISET"
				( objectStatus "@baseboard_fab2_lib.baseboard_fab2(sch_1):vr_pvpp_def_iset" )
			)
			( signal "VR_PVPP_DEF_PHASE"
				( objectStatus "@baseboard_fab2_lib.baseboard_fab2(sch_1):vr_pvpp_def_phase" )
			)
			( signal "VR_PVPP_DEF_SNUB"
				( objectStatus "@baseboard_fab2_lib.baseboard_fab2(sch_1):vr_pvpp_def_snub" )
			)
			( signal "VR_PVPP_DEF_SS"
				( objectStatus "@baseboard_fab2_lib.baseboard_fab2(sch_1):vr_pvpp_def_ss" )
			)
			( signal "VR_VB_PVPP_DEF"
				( objectStatus "@baseboard_fab2_lib.baseboard_fab2(sch_1):vr_vb_pvpp_def" )
			)
			( signal "VSENSE_PVPP_DEF"
				( objectStatus "@baseboard_fab2_lib.baseboard_fab2(sch_1):vsense_pvpp_def" )
			)
			( signal "AGND_PVPP_GHJ"
				( attribute "VOLTAGE" "0.0V"
					( Units "uVoltage" "V" 1.000000)
					( Status sAliasFlattened )
					( Origin gFrontEnd )
				)
				( objectStatus "@baseboard_fab2_lib.baseboard_fab2(sch_1):agnd_pvpp_ghj" )
			)
			( signal "FM_PVPP_PVDDQ_CPU1_EN_GHJ"
				( objectStatus "@baseboard_fab2_lib.baseboard_fab2(sch_1):fm_pvpp_pvddq_cpu1_en_ghj" )
			)
			( signal "PWRGD_PVPP_GHJ_R"
				( objectStatus "@baseboard_fab2_lib.baseboard_fab2(sch_1):pwrgd_pvpp_ghj_r" )
			)
			( signal "VR_COMP_PVPP_GHJ"
				( objectStatus "@baseboard_fab2_lib.baseboard_fab2(sch_1):vr_comp_pvpp_ghj" )
			)
			( signal "VR_COMP_PVPP_GHJ_3"
				( objectStatus "@baseboard_fab2_lib.baseboard_fab2(sch_1):vr_comp_pvpp_ghj_3" )
			)
			( signal "VR_COMP_RC_PVPP_GHJ"
				( objectStatus "@baseboard_fab2_lib.baseboard_fab2(sch_1):vr_comp_rc_pvpp_ghj" )
			)
			( signal "VR_FB_PVPP_GHJ"
				( objectStatus "@baseboard_fab2_lib.baseboard_fab2(sch_1):vr_fb_pvpp_ghj" )
			)
			( signal "VR_FET_SW_P12V_STBY_PVPP_GHJ"
				( objectStatus "@baseboard_fab2_lib.baseboard_fab2(sch_1):vr_fet_sw_p12v_stby_pvpp_ghj" )
			)
			( signal "VR_PVPP_GHJ_BOOT"
				( objectStatus "@baseboard_fab2_lib.baseboard_fab2(sch_1):vr_pvpp_ghj_boot" )
			)
			( signal "VR_PVPP_GHJ_BOOT_R"
				( objectStatus "@baseboard_fab2_lib.baseboard_fab2(sch_1):vr_pvpp_ghj_boot_r" )
			)
			( signal "VR_PVPP_GHJ_ISET"
				( objectStatus "@baseboard_fab2_lib.baseboard_fab2(sch_1):vr_pvpp_ghj_iset" )
			)
			( signal "VR_PVPP_GHJ_PHASE"
				( objectStatus "@baseboard_fab2_lib.baseboard_fab2(sch_1):vr_pvpp_ghj_phase" )
			)
			( signal "VR_PVPP_GHJ_SNUB"
				( objectStatus "@baseboard_fab2_lib.baseboard_fab2(sch_1):vr_pvpp_ghj_snub" )
			)
			( signal "VR_PVPP_GHJ_SS"
				( objectStatus "@baseboard_fab2_lib.baseboard_fab2(sch_1):vr_pvpp_ghj_ss" )
			)
			( signal "VR_VB_PVPP_GHJ"
				( objectStatus "@baseboard_fab2_lib.baseboard_fab2(sch_1):vr_vb_pvpp_ghj" )
			)
			( signal "VSENSE_PVPP_GHJ"
				( objectStatus "@baseboard_fab2_lib.baseboard_fab2(sch_1):vsense_pvpp_ghj" )
			)
			( signal "AGND_PVPP_KLM"
				( attribute "VOLTAGE" "0.0V"
					( Units "uVoltage" "V" 1.000000)
					( Status sAliasFlattened )
					( Origin gFrontEnd )
				)
				( objectStatus "@baseboard_fab2_lib.baseboard_fab2(sch_1):agnd_pvpp_klm" )
			)
			( signal "FM_PVPP_PVDDQ_CPU1_EN_KLM"
				( objectStatus "@baseboard_fab2_lib.baseboard_fab2(sch_1):fm_pvpp_pvddq_cpu1_en_klm" )
			)
			( signal "PWRGD_PVPP_KLM_R"
				( objectStatus "@baseboard_fab2_lib.baseboard_fab2(sch_1):pwrgd_pvpp_klm_r" )
			)
			( signal "VR_COMP_PVPP_KLM"
				( objectStatus "@baseboard_fab2_lib.baseboard_fab2(sch_1):vr_comp_pvpp_klm" )
			)
			( signal "VR_COMP_PVPP_KLM_3"
				( objectStatus "@baseboard_fab2_lib.baseboard_fab2(sch_1):vr_comp_pvpp_klm_3" )
			)
			( signal "VR_COMP_RC_PVPP_KLM"
				( objectStatus "@baseboard_fab2_lib.baseboard_fab2(sch_1):vr_comp_rc_pvpp_klm" )
			)
			( signal "VR_FB_PVPP_KLM"
				( objectStatus "@baseboard_fab2_lib.baseboard_fab2(sch_1):vr_fb_pvpp_klm" )
			)
			( signal "VR_FET_SW_P12V_STBY_PVPP_KLM"
				( objectStatus "@baseboard_fab2_lib.baseboard_fab2(sch_1):vr_fet_sw_p12v_stby_pvpp_klm" )
			)
			( signal "VR_PVPP_KLM_BOOT"
				( objectStatus "@baseboard_fab2_lib.baseboard_fab2(sch_1):vr_pvpp_klm_boot" )
			)
			( signal "VR_PVPP_KLM_BOOT_R"
				( objectStatus "@baseboard_fab2_lib.baseboard_fab2(sch_1):vr_pvpp_klm_boot_r" )
			)
			( signal "VR_PVPP_KLM_ISET"
				( objectStatus "@baseboard_fab2_lib.baseboard_fab2(sch_1):vr_pvpp_klm_iset" )
			)
			( signal "VR_PVPP_KLM_PHASE"
				( objectStatus "@baseboard_fab2_lib.baseboard_fab2(sch_1):vr_pvpp_klm_phase" )
			)
			( signal "VR_PVPP_KLM_SNUB"
				( objectStatus "@baseboard_fab2_lib.baseboard_fab2(sch_1):vr_pvpp_klm_snub" )
			)
			( signal "VR_PVPP_KLM_SS"
				( objectStatus "@baseboard_fab2_lib.baseboard_fab2(sch_1):vr_pvpp_klm_ss" )
			)
			( signal "VR_VB_PVPP_KLM"
				( objectStatus "@baseboard_fab2_lib.baseboard_fab2(sch_1):vr_vb_pvpp_klm" )
			)
			( signal "VSENSE_PVPP_KLM"
				( objectStatus "@baseboard_fab2_lib.baseboard_fab2(sch_1):vsense_pvpp_klm" )
			)
			( signal "A_TSENSE_P1V05_PCH_STBY_TMON"
				( objectStatus "@baseboard_fab2_lib.baseboard_fab2(sch_1):a_tsense_p1v05_pch_stby_tmon" )
			)
			( signal "A_TSENSE_PVNN_PCH_TMON"
				( objectStatus "@baseboard_fab2_lib.baseboard_fab2(sch_1):a_tsense_pvnn_pch_tmon" )
			)
			( signal "IRQ_PVNN_PCH_VRHOT_N"
				( objectStatus "@baseboard_fab2_lib.baseboard_fab2(sch_1):irq_pvnn_pch_vrhot_n" )
			)
			( signal "ISENSE_P1V05_PCH_STBY_PH1_IMON"
				( objectStatus "@baseboard_fab2_lib.baseboard_fab2(sch_1):isense_p1v05_pch_stby_ph1_imon" )
			)
			( signal "ISENSE_PVNN_PCH_PH1_IMON"
				( objectStatus "@baseboard_fab2_lib.baseboard_fab2(sch_1):isense_pvnn_pch_ph1_imon" )
			)
			( signal "NC_PVNN_PCH_DNC0"
				( objectStatus "@baseboard_fab2_lib.baseboard_fab2(sch_1):nc_pvnn_pch_dnc0" )
			)
			( signal "NC_PVNN_PCH_DNC1"
				( objectStatus "@baseboard_fab2_lib.baseboard_fab2(sch_1):nc_pvnn_pch_dnc1" )
			)
			( signal "NC_PVNN_PCH_DNC2"
				( objectStatus "@baseboard_fab2_lib.baseboard_fab2(sch_1):nc_pvnn_pch_dnc2" )
			)
			( signal "NC_PVNN_PCH_DNC3"
				( objectStatus "@baseboard_fab2_lib.baseboard_fab2(sch_1):nc_pvnn_pch_dnc3" )
			)
			( signal "NC_PVNN_PCH_DNC4"
				( objectStatus "@baseboard_fab2_lib.baseboard_fab2(sch_1):nc_pvnn_pch_dnc4" )
			)
			( signal "PU_VR_PVNN_PCH_FAULT1"
				( objectStatus "@baseboard_fab2_lib.baseboard_fab2(sch_1):pu_vr_pvnn_pch_fault1" )
			)
			( signal "PWRGD_P1V8_PCH_STBY"
				( objectStatus "@baseboard_fab2_lib.baseboard_fab2(sch_1):pwrgd_p1v8_pch_stby" )
			)
			( signal "PWRGD_PVNN_PCH_R"
				( objectStatus "@baseboard_fab2_lib.baseboard_fab2(sch_1):pwrgd_pvnn_pch_r" )
			)
			( signal "SMB_VR_SCL_PVNN_PCH"
				( objectStatus "@baseboard_fab2_lib.baseboard_fab2(sch_1):smb_vr_scl_pvnn_pch" )
			)
			( signal "SMB_VR_SDA_PVNN_PCH"
				( objectStatus "@baseboard_fab2_lib.baseboard_fab2(sch_1):smb_vr_sda_pvnn_pch" )
			)
			( signal "TP_PVNN_PCH_MP2"
				( objectStatus "@baseboard_fab2_lib.baseboard_fab2(sch_1):tp_pvnn_pch_mp2" )
			)
			( signal "TP_PVNN_PCH_MP3"
				( objectStatus "@baseboard_fab2_lib.baseboard_fab2(sch_1):tp_pvnn_pch_mp3" )
			)
			( signal "TP_PVNN_PCH_PINALRT_N"
				( objectStatus "@baseboard_fab2_lib.baseboard_fab2(sch_1):tp_pvnn_pch_pinalrt_n" )
			)
			( signal "TP_PVNN_PCH_RESET_N"
				( objectStatus "@baseboard_fab2_lib.baseboard_fab2(sch_1):tp_pvnn_pch_reset_n" )
			)
			( signal "TP_PVNN_PCH_SVID_ALERT"
				( objectStatus "@baseboard_fab2_lib.baseboard_fab2(sch_1):tp_pvnn_pch_svid_alert" )
			)
			( signal "TP_PVNN_PCH_VCLK"
				( objectStatus "@baseboard_fab2_lib.baseboard_fab2(sch_1):tp_pvnn_pch_vclk" )
			)
			( signal "TP_PVNN_PCH_VDIO"
				( objectStatus "@baseboard_fab2_lib.baseboard_fab2(sch_1):tp_pvnn_pch_vdio" )
			)
			( signal "TP_VR_PVNN_PCH_AIINSEN"
				( objectStatus "@baseboard_fab2_lib.baseboard_fab2(sch_1):tp_vr_pvnn_pch_aiinsen" )
			)
			( signal "VR_P1V05_PCH_BIREF1"
				( objectStatus "@baseboard_fab2_lib.baseboard_fab2(sch_1):vr_p1v05_pch_biref1" )
			)
			( signal "VR_P1V05_PCH_STBY_AVSP"
				( objectStatus "@baseboard_fab2_lib.baseboard_fab2(sch_1):vr_p1v05_pch_stby_avsp" )
			)
			( signal "VR_P1V05_PCH_STBY_PWM1"
				( objectStatus "@baseboard_fab2_lib.baseboard_fab2(sch_1):vr_p1v05_pch_stby_pwm1" )
			)
			( signal "VR_PVNN_P1V05_PCH_VD12"
				( objectStatus "@baseboard_fab2_lib.baseboard_fab2(sch_1):vr_pvnn_p1v05_pch_vd12" )
			)
			( signal "VR_PVNN_PCH_AIREF1"
				( objectStatus "@baseboard_fab2_lib.baseboard_fab2(sch_1):vr_pvnn_pch_airef1" )
			)
			( signal "VR_PVNN_PCH_AVSP"
				( objectStatus "@baseboard_fab2_lib.baseboard_fab2(sch_1):vr_pvnn_pch_avsp" )
			)
			( signal "VR_PVNN_PCH_PWM1"
				( objectStatus "@baseboard_fab2_lib.baseboard_fab2(sch_1):vr_pvnn_pch_pwm1" )
			)
			( signal "VR_PVNN_PCH_VDD"
				( objectStatus "@baseboard_fab2_lib.baseboard_fab2(sch_1):vr_pvnn_pch_vdd" )
			)
			( signal "VR_PVNN_PCH_VINSEN"
				( objectStatus "@baseboard_fab2_lib.baseboard_fab2(sch_1):vr_pvnn_pch_vinsen" )
			)
			( signal "VR_PVNN_PCH_VREN"
				( objectStatus "@baseboard_fab2_lib.baseboard_fab2(sch_1):vr_pvnn_pch_vren" )
			)
			( signal "VR_PVNN_PCH_XADDR1"
				( objectStatus "@baseboard_fab2_lib.baseboard_fab2(sch_1):vr_pvnn_pch_xaddr1" )
			)
			( signal "VR_PVNN_PCH_XADDR2"
				( objectStatus "@baseboard_fab2_lib.baseboard_fab2(sch_1):vr_pvnn_pch_xaddr2" )
			)
			( signal "VSENSE_P1V05_PCH_STBY_AVSN"
				( objectStatus "@baseboard_fab2_lib.baseboard_fab2(sch_1):vsense_p1v05_pch_stby_avsn" )
			)
			( signal "VSENSE_P1V05_PCH_STBY_AVSP"
				( objectStatus "@baseboard_fab2_lib.baseboard_fab2(sch_1):vsense_p1v05_pch_stby_avsp" )
			)
			( signal "VSENSE_PVNN_PCH_STBY_AVSN"
				( objectStatus "@baseboard_fab2_lib.baseboard_fab2(sch_1):vsense_pvnn_pch_stby_avsn" )
			)
			( signal "VSENSE_PVNN_PCH_STBY_AVSP"
				( objectStatus "@baseboard_fab2_lib.baseboard_fab2(sch_1):vsense_pvnn_pch_stby_avsp" )
			)
			( signal "NC_P1V05_PCH_STBY_PH1_P31"
				( objectStatus "@baseboard_fab2_lib.baseboard_fab2(sch_1):nc_p1v05_pch_stby_ph1_p31" )
			)
			( signal "NC_PVNN_PCH_PH1_P31"
				( objectStatus "@baseboard_fab2_lib.baseboard_fab2(sch_1):nc_pvnn_pch_ph1_p31" )
			)
			( signal "TP_P1V05_PCH_GL_0"
				( objectStatus "@baseboard_fab2_lib.baseboard_fab2(sch_1):tp_p1v05_pch_gl_0" )
			)
			( signal "TP_P1V05_PCH_GL_1"
				( objectStatus "@baseboard_fab2_lib.baseboard_fab2(sch_1):tp_p1v05_pch_gl_1" )
			)
			( signal "TP_PVNN_PCH_GL_0"
				( objectStatus "@baseboard_fab2_lib.baseboard_fab2(sch_1):tp_pvnn_pch_gl_0" )
			)
			( signal "TP_PVNN_PCH_GL_1"
				( objectStatus "@baseboard_fab2_lib.baseboard_fab2(sch_1):tp_pvnn_pch_gl_1" )
			)
			( signal "VR_P1V05_PCH_STBY_OCSET"
				( objectStatus "@baseboard_fab2_lib.baseboard_fab2(sch_1):vr_p1v05_pch_stby_ocset" )
			)
			( signal "VR_P1V05_PCH_STBY_PH1_BOOT"
				( objectStatus "@baseboard_fab2_lib.baseboard_fab2(sch_1):vr_p1v05_pch_stby_ph1_boot" )
			)
			( signal "VR_P1V05_PCH_STBY_PH1_PHASE"
				( objectStatus "@baseboard_fab2_lib.baseboard_fab2(sch_1):vr_p1v05_pch_stby_ph1_phase" )
			)
			( signal "VR_P1V05_PCH_STBY_PH1_PHASE_SW"
				( objectStatus "@baseboard_fab2_lib.baseboard_fab2(sch_1):vr_p1v05_pch_stby_ph1_phase_sw" )
			)
			( signal "VR_P1V05_PCH_STBY_PH1_VCIN"
				( objectStatus "@baseboard_fab2_lib.baseboard_fab2(sch_1):vr_p1v05_pch_stby_ph1_vcin" )
			)
			( signal "VR_PVNN_PCH_PH1_BOOT"
				( objectStatus "@baseboard_fab2_lib.baseboard_fab2(sch_1):vr_pvnn_pch_ph1_boot" )
			)
			( signal "VR_PVNN_PCH_PH1_PHASE"
				( objectStatus "@baseboard_fab2_lib.baseboard_fab2(sch_1):vr_pvnn_pch_ph1_phase" )
			)
			( signal "VR_PVNN_PCH_PH1_PHASE_SW"
				( objectStatus "@baseboard_fab2_lib.baseboard_fab2(sch_1):vr_pvnn_pch_ph1_phase_sw" )
			)
			( signal "VR_PVNN_PCH_PH1_VCIN"
				( objectStatus "@baseboard_fab2_lib.baseboard_fab2(sch_1):vr_pvnn_pch_ph1_vcin" )
			)
			( signal "VR_PVNN_PCH_STBY_OCSET"
				( objectStatus "@baseboard_fab2_lib.baseboard_fab2(sch_1):vr_pvnn_pch_stby_ocset" )
			)
			( signal "PWRGD_P1V8_PCH_STBY_R"
				( objectStatus "@baseboard_fab2_lib.baseboard_fab2(sch_1):pwrgd_p1v8_pch_stby_r" )
			)
			( signal "VR_P1V8_PCH_STBY_FB"
				( objectStatus "@baseboard_fab2_lib.baseboard_fab2(sch_1):vr_p1v8_pch_stby_fb" )
			)
			( signal "PWRGD_P1V26_BMC_STBY_R"
				( objectStatus "@baseboard_fab2_lib.baseboard_fab2(sch_1):pwrgd_p1v26_bmc_stby_r" )
			)
			( signal "PWRGD_P1V538_BMC_STBY"
				( objectStatus "@baseboard_fab2_lib.baseboard_fab2(sch_1):pwrgd_p1v538_bmc_stby" )
			)
			( signal "VR_P1V26_BMC_STBY_FB"
				( objectStatus "@baseboard_fab2_lib.baseboard_fab2(sch_1):vr_p1v26_bmc_stby_fb" )
			)
			( signal "PWRGD_P1V538_BMC_STBY_R"
				( objectStatus "@baseboard_fab2_lib.baseboard_fab2(sch_1):pwrgd_p1v538_bmc_stby_r" )
			)
			( signal "VR_P1V538_BMC_STBY_FB"
				( objectStatus "@baseboard_fab2_lib.baseboard_fab2(sch_1):vr_p1v538_bmc_stby_fb" )
			)
			( signal "AGND_P3V3_STBY"
				( attribute "VOLTAGE" "0V"
					( Units "uVoltage" "V" 1.000000)
					( Status sAliasFlattened )
					( Origin gFrontEnd )
				)
				( objectStatus "@baseboard_fab2_lib.baseboard_fab2(sch_1):agnd_p3v3_stby" )
			)
			( signal "PWRGD_P3V3_STBY_R"
				( objectStatus "@baseboard_fab2_lib.baseboard_fab2(sch_1):pwrgd_p3v3_stby_r" )
			)
			( signal "PWRGD_P5V_STBY"
				( objectStatus "@baseboard_fab2_lib.baseboard_fab2(sch_1):pwrgd_p5v_stby" )
			)
			( signal "VR_FET_SW_P12V_STBY_P3V3_STBY"
				( objectStatus "@baseboard_fab2_lib.baseboard_fab2(sch_1):vr_fet_sw_p12v_stby_p3v3_stby" )
			)
			( signal "VR_P3V3_STBY_BOOT"
				( objectStatus "@baseboard_fab2_lib.baseboard_fab2(sch_1):vr_p3v3_stby_boot" )
			)
			( signal "VR_P3V3_STBY_BOOT_R"
				( objectStatus "@baseboard_fab2_lib.baseboard_fab2(sch_1):vr_p3v3_stby_boot_r" )
			)
			( signal "VR_P3V3_STBY_EN"
				( objectStatus "@baseboard_fab2_lib.baseboard_fab2(sch_1):vr_p3v3_stby_en" )
			)
			( signal "VR_P3V3_STBY_LGATE"
				( objectStatus "@baseboard_fab2_lib.baseboard_fab2(sch_1):vr_p3v3_stby_lgate" )
			)
			( signal "VR_P3V3_STBY_OCSELECT"
				( objectStatus "@baseboard_fab2_lib.baseboard_fab2(sch_1):vr_p3v3_stby_ocselect" )
			)
			( signal "VR_P3V3_STBY_PHASE"
				( objectStatus "@baseboard_fab2_lib.baseboard_fab2(sch_1):vr_p3v3_stby_phase" )
			)
			( signal "VR_P3V3_STBY_SNUB"
				( objectStatus "@baseboard_fab2_lib.baseboard_fab2(sch_1):vr_p3v3_stby_snub" )
			)
			( signal "VR_P3V3_STBY_UGATE"
				( objectStatus "@baseboard_fab2_lib.baseboard_fab2(sch_1):vr_p3v3_stby_ugate" )
			)
			( signal "VSENSE_P3V3_STBY"
				( objectStatus "@baseboard_fab2_lib.baseboard_fab2(sch_1):vsense_p3v3_stby" )
			)
			( signal "VSENSE_RGND_P3V3_STBY"
				( objectStatus "@baseboard_fab2_lib.baseboard_fab2(sch_1):vsense_rgnd_p3v3_stby" )
			)
			( signal "VSENSE_VOUT_P3V3_STBY"
				( objectStatus "@baseboard_fab2_lib.baseboard_fab2(sch_1):vsense_vout_p3v3_stby" )
			)
			( signal "AGND_P5V_STBY"
				( attribute "VOLTAGE" "0"
					( Units "uVoltage" "V" 1.000000)
					( Status sAliasFlattened )
					( Origin gFrontEnd )
				)
				( objectStatus "@baseboard_fab2_lib.baseboard_fab2(sch_1):agnd_p5v_stby" )
			)
			( signal "PWRGD_P5V_STBY_R"
				( objectStatus "@baseboard_fab2_lib.baseboard_fab2(sch_1):pwrgd_p5v_stby_r" )
			)
			( signal "VR_FET_SW_P5V_STBY_PVIN"
				( objectStatus "@baseboard_fab2_lib.baseboard_fab2(sch_1):vr_fet_sw_p5v_stby_pvin" )
			)
			( signal "VR_P5V_STBY_BOOT"
				( objectStatus "@baseboard_fab2_lib.baseboard_fab2(sch_1):vr_p5v_stby_boot" )
			)
			( signal "VR_P5V_STBY_COMP"
				( objectStatus "@baseboard_fab2_lib.baseboard_fab2(sch_1):vr_p5v_stby_comp" )
			)
			( signal "VR_P5V_STBY_EN"
				( objectStatus "@baseboard_fab2_lib.baseboard_fab2(sch_1):vr_p5v_stby_en" )
			)
			( signal "VR_P5V_STBY_PHASE"
				( objectStatus "@baseboard_fab2_lib.baseboard_fab2(sch_1):vr_p5v_stby_phase" )
			)
			( signal "VR_P5V_STBY_RC_COMP"
				( objectStatus "@baseboard_fab2_lib.baseboard_fab2(sch_1):vr_p5v_stby_rc_comp" )
			)
			( signal "VR_P5V_STBY_RT"
				( objectStatus "@baseboard_fab2_lib.baseboard_fab2(sch_1):vr_p5v_stby_rt" )
			)
			( signal "VR_P5V_STBY_SS"
				( objectStatus "@baseboard_fab2_lib.baseboard_fab2(sch_1):vr_p5v_stby_ss" )
			)
			( signal "VR_P5V_STBY_VIN"
				( objectStatus "@baseboard_fab2_lib.baseboard_fab2(sch_1):vr_p5v_stby_vin" )
			)
			( signal "VR_P5V_STBY_VSENSE"
				( objectStatus "@baseboard_fab2_lib.baseboard_fab2(sch_1):vr_p5v_stby_vsense" )
			)
			( signal "VR_P5V_STBY_VSENSE_R"
				( objectStatus "@baseboard_fab2_lib.baseboard_fab2(sch_1):vr_p5v_stby_vsense_r" )
			)
			( signal "UNNAMED_219_3D01R5F-GP_I126_2"
				( objectStatus "@baseboard_fab2_lib.baseboard_fab2(sch_1):\unnamed_219_3d01r5f-gp_i126_2\" )
			)
			( signal "VR_PVCCIN_CPU0_PH1_BOOT_R"
				( objectStatus "@baseboard_fab2_lib.baseboard_fab2(sch_1):vr_pvccin_cpu0_ph1_boot_r" )
			)
			( signal "VR_PVCCIN_CPU0_PH2_BOOT_R"
				( objectStatus "@baseboard_fab2_lib.baseboard_fab2(sch_1):vr_pvccin_cpu0_ph2_boot_r" )
			)
			( signal "UNNAMED_208_3D01R5F-GP_I94_2"
				( objectStatus "@baseboard_fab2_lib.baseboard_fab2(sch_1):\unnamed_208_3d01r5f-gp_i94_2\" )
			)
			( signal "VR_PVDDQ_KLM_PH1_BOOT_R"
				( objectStatus "@baseboard_fab2_lib.baseboard_fab2(sch_1):vr_pvddq_klm_ph1_boot_r" )
			)
			( signal "VR_PVDDQ_KLM_PH2_BOOT_R"
				( objectStatus "@baseboard_fab2_lib.baseboard_fab2(sch_1):vr_pvddq_klm_ph2_boot_r" )
			)
			( signal "UNNAMED_227_3D01R5F-GP_I124_1"
				( objectStatus "@baseboard_fab2_lib.baseboard_fab2(sch_1):\unnamed_227_3d01r5f-gp_i124_1\" )
			)
			( signal "VR_PVCCIN_CPU1_PH5_BOOT_R"
				( objectStatus "@baseboard_fab2_lib.baseboard_fab2(sch_1):vr_pvccin_cpu1_ph5_boot_r" )
			)
			( signal "UNNAMED_208_3D01R5F-GP_I86_2"
				( objectStatus "@baseboard_fab2_lib.baseboard_fab2(sch_1):\unnamed_208_3d01r5f-gp_i86_2\" )
			)
			( signal "VR_PVCCIN_CPU1_PH3_BOOT_R"
				( objectStatus "@baseboard_fab2_lib.baseboard_fab2(sch_1):vr_pvccin_cpu1_ph3_boot_r" )
			)
			( signal "VR_PVCCIN_CPU1_PH4_BOOT_R"
				( objectStatus "@baseboard_fab2_lib.baseboard_fab2(sch_1):vr_pvccin_cpu1_ph4_boot_r" )
			)
			( signal "UNNAMED_224_3D01R5F-GP_I129_2"
				( objectStatus "@baseboard_fab2_lib.baseboard_fab2(sch_1):\unnamed_224_3d01r5f-gp_i129_2\" )
			)
			( signal "VR_PVCCIN_CPU1_PH1_BOOT_R"
				( objectStatus "@baseboard_fab2_lib.baseboard_fab2(sch_1):vr_pvccin_cpu1_ph1_boot_r" )
			)
			( signal "VR_PVDDQ_GHJ_PH1_BOOT_R"
				( objectStatus "@baseboard_fab2_lib.baseboard_fab2(sch_1):vr_pvddq_ghj_ph1_boot_r" )
			)
			( signal "UNNAMED_224_3D01R5F-GP_I119_2"
				( objectStatus "@baseboard_fab2_lib.baseboard_fab2(sch_1):\unnamed_224_3d01r5f-gp_i119_2\" )
			)
			( signal "VR_PVDDQ_GHJ_PH2_BOOT_R"
				( objectStatus "@baseboard_fab2_lib.baseboard_fab2(sch_1):vr_pvddq_ghj_ph2_boot_r" )
			)
			( signal "UNNAMED_203_3D01R5F-GP_I105_2"
				( objectStatus "@baseboard_fab2_lib.baseboard_fab2(sch_1):\unnamed_203_3d01r5f-gp_i105_2\" )
			)
			( signal "VR_PVCCIN_CPU0_PH5_BOOT_R"
				( objectStatus "@baseboard_fab2_lib.baseboard_fab2(sch_1):vr_pvccin_cpu0_ph5_boot_r" )
			)
			( signal "UNNAMED_203_3D01R5F-GP_I102_2"
				( objectStatus "@baseboard_fab2_lib.baseboard_fab2(sch_1):\unnamed_203_3d01r5f-gp_i102_2\" )
			)
			( signal "VR_PVCCIN_CPU0_PH3_BOOT_R"
				( objectStatus "@baseboard_fab2_lib.baseboard_fab2(sch_1):vr_pvccin_cpu0_ph3_boot_r" )
			)
			( signal "VR_PVDDQ_DEF_PH1_BOOT_R"
				( objectStatus "@baseboard_fab2_lib.baseboard_fab2(sch_1):vr_pvddq_def_ph1_boot_r" )
			)
			( signal "VR_PVDDQ_DEF_PH2_BOOT_R"
				( objectStatus "@baseboard_fab2_lib.baseboard_fab2(sch_1):vr_pvddq_def_ph2_boot_r" )
			)
			( signal "UNNAMED_216_3D01R5F-GP_I123_2"
				( objectStatus "@baseboard_fab2_lib.baseboard_fab2(sch_1):\unnamed_216_3d01r5f-gp_i123_2\" )
			)
			( signal "UNNAMED_210_3D01R5F-GP_I59_2"
				( objectStatus "@baseboard_fab2_lib.baseboard_fab2(sch_1):\unnamed_210_3d01r5f-gp_i59_2\" )
			)
			( signal "VR_PVDDQ_ABC_PH1_BOOT_R"
				( objectStatus "@baseboard_fab2_lib.baseboard_fab2(sch_1):vr_pvddq_abc_ph1_boot_r" )
			)
			( signal "VR_PVDDQ_ABC_PH2_BOOT_R"
				( objectStatus "@baseboard_fab2_lib.baseboard_fab2(sch_1):vr_pvddq_abc_ph2_boot_r" )
			)
			( signal "UNNAMED_205_3D01R5F-GP_I68_2"
				( objectStatus "@baseboard_fab2_lib.baseboard_fab2(sch_1):\unnamed_205_3d01r5f-gp_i68_2\" )
			)
			( signal "VR_PVSA_CPU1_BOOT_R"
				( objectStatus "@baseboard_fab2_lib.baseboard_fab2(sch_1):vr_pvsa_cpu1_boot_r" )
			)
			( signal "VR_PVSA_CPU0_BOOT_R"
				( objectStatus "@baseboard_fab2_lib.baseboard_fab2(sch_1):vr_pvsa_cpu0_boot_r" )
			)
			( signal "VR_PVCCIO_CPU1_PH1_BOOT_R"
				( objectStatus "@baseboard_fab2_lib.baseboard_fab2(sch_1):vr_pvccio_cpu1_ph1_boot_r" )
			)
			( signal "VR_P1V05_PCH_STBY_PH1_BOOT_R"
				( objectStatus "@baseboard_fab2_lib.baseboard_fab2(sch_1):vr_p1v05_pch_stby_ph1_boot_r" )
			)
			( signal "VR_PVNN_PCH_PH1_BOOT_R"
				( objectStatus "@baseboard_fab2_lib.baseboard_fab2(sch_1):vr_pvnn_pch_ph1_boot_r" )
			)
			( signal "UNNAMED_212_3D01R5F-GP_I112_2"
				( objectStatus "@baseboard_fab2_lib.baseboard_fab2(sch_1):\unnamed_212_3d01r5f-gp_i112_2\" )
			)
			( signal "UNNAMED_236_3D01R5F-GP_I132_2"
				( objectStatus "@baseboard_fab2_lib.baseboard_fab2(sch_1):\unnamed_236_3d01r5f-gp_i132_2\" )
			)
			( signal "VR_PVCCIO_CPU0_PH1_BOOT_R"
				( objectStatus "@baseboard_fab2_lib.baseboard_fab2(sch_1):vr_pvccio_cpu0_ph1_boot_r" )
			)
			( signal "VR_PVCCIN_CPU1_PH2_BOOT_R"
				( objectStatus "@baseboard_fab2_lib.baseboard_fab2(sch_1):vr_pvccin_cpu1_ph2_boot_r" )
			)
			( signal "UNNAMED_227_3D01R5F-GP_I125_1"
				( objectStatus "@baseboard_fab2_lib.baseboard_fab2(sch_1):\unnamed_227_3d01r5f-gp_i125_1\" )
			)
			( signal "VR_PVCCIN_CPU0_PH4_BOOT_R"
				( objectStatus "@baseboard_fab2_lib.baseboard_fab2(sch_1):vr_pvccin_cpu0_ph4_boot_r" )
			)
			( signal "P3E_CPU0_PE1_PCH_CON_RXN<8>"
				( objectStatus "@baseboard_fab2_lib.baseboard_fab2(sch_1):p3e_cpu0_pe1_pch_con_rxn(8)" )
			)
			( signal "P3E_CPU0_PE1_PCH_CON_RXN<9>"
				( objectStatus "@baseboard_fab2_lib.baseboard_fab2(sch_1):p3e_cpu0_pe1_pch_con_rxn(9)" )
			)
			( signal "P3E_CPU0_PE1_PCH_CON_RXN<10>"
				( objectStatus "@baseboard_fab2_lib.baseboard_fab2(sch_1):p3e_cpu0_pe1_pch_con_rxn(10)" )
			)
			( signal "P3E_CPU0_PE1_PCH_CON_RXN<11>"
				( objectStatus "@baseboard_fab2_lib.baseboard_fab2(sch_1):p3e_cpu0_pe1_pch_con_rxn(11)" )
			)
			( signal "P3E_CPU0_PE1_PCH_CON_RXN<12>"
				( objectStatus "@baseboard_fab2_lib.baseboard_fab2(sch_1):p3e_cpu0_pe1_pch_con_rxn(12)" )
			)
			( signal "P3E_CPU0_PE1_PCH_CON_RXN<13>"
				( objectStatus "@baseboard_fab2_lib.baseboard_fab2(sch_1):p3e_cpu0_pe1_pch_con_rxn(13)" )
			)
			( signal "P3E_CPU0_PE1_PCH_CON_RXN<14>"
				( objectStatus "@baseboard_fab2_lib.baseboard_fab2(sch_1):p3e_cpu0_pe1_pch_con_rxn(14)" )
			)
			( signal "P3E_CPU0_PE1_PCH_CON_RXN<15>"
				( objectStatus "@baseboard_fab2_lib.baseboard_fab2(sch_1):p3e_cpu0_pe1_pch_con_rxn(15)" )
			)
			( signal "P3E_CPU0_PE1_PCH_CON_RXP<8>"
				( objectStatus "@baseboard_fab2_lib.baseboard_fab2(sch_1):p3e_cpu0_pe1_pch_con_rxp(8)" )
			)
			( signal "P3E_CPU0_PE1_PCH_CON_RXP<9>"
				( objectStatus "@baseboard_fab2_lib.baseboard_fab2(sch_1):p3e_cpu0_pe1_pch_con_rxp(9)" )
			)
			( signal "P3E_CPU0_PE1_PCH_CON_RXP<10>"
				( objectStatus "@baseboard_fab2_lib.baseboard_fab2(sch_1):p3e_cpu0_pe1_pch_con_rxp(10)" )
			)
			( signal "P3E_CPU0_PE1_PCH_CON_RXP<11>"
				( objectStatus "@baseboard_fab2_lib.baseboard_fab2(sch_1):p3e_cpu0_pe1_pch_con_rxp(11)" )
			)
			( signal "P3E_CPU0_PE1_PCH_CON_RXP<12>"
				( objectStatus "@baseboard_fab2_lib.baseboard_fab2(sch_1):p3e_cpu0_pe1_pch_con_rxp(12)" )
			)
			( signal "P3E_CPU0_PE1_PCH_CON_RXP<13>"
				( objectStatus "@baseboard_fab2_lib.baseboard_fab2(sch_1):p3e_cpu0_pe1_pch_con_rxp(13)" )
			)
			( signal "P3E_CPU0_PE1_PCH_CON_RXP<14>"
				( objectStatus "@baseboard_fab2_lib.baseboard_fab2(sch_1):p3e_cpu0_pe1_pch_con_rxp(14)" )
			)
			( signal "P3E_CPU0_PE1_PCH_CON_RXP<15>"
				( objectStatus "@baseboard_fab2_lib.baseboard_fab2(sch_1):p3e_cpu0_pe1_pch_con_rxp(15)" )
			)
			( signal "P3E_CPU0_PE1_PCH_CON_TXN<8>"
				( objectStatus "@baseboard_fab2_lib.baseboard_fab2(sch_1):p3e_cpu0_pe1_pch_con_txn(8)" )
			)
			( signal "P3E_CPU0_PE1_PCH_CON_TXN<9>"
				( objectStatus "@baseboard_fab2_lib.baseboard_fab2(sch_1):p3e_cpu0_pe1_pch_con_txn(9)" )
			)
			( signal "P3E_CPU0_PE1_PCH_CON_TXN<10>"
				( objectStatus "@baseboard_fab2_lib.baseboard_fab2(sch_1):p3e_cpu0_pe1_pch_con_txn(10)" )
			)
			( signal "P3E_CPU0_PE1_PCH_CON_TXN<11>"
				( objectStatus "@baseboard_fab2_lib.baseboard_fab2(sch_1):p3e_cpu0_pe1_pch_con_txn(11)" )
			)
			( signal "P3E_CPU0_PE1_PCH_CON_TXN<12>"
				( objectStatus "@baseboard_fab2_lib.baseboard_fab2(sch_1):p3e_cpu0_pe1_pch_con_txn(12)" )
			)
			( signal "P3E_CPU0_PE1_PCH_CON_TXN<13>"
				( objectStatus "@baseboard_fab2_lib.baseboard_fab2(sch_1):p3e_cpu0_pe1_pch_con_txn(13)" )
			)
			( signal "P3E_CPU0_PE1_PCH_CON_TXN<14>"
				( objectStatus "@baseboard_fab2_lib.baseboard_fab2(sch_1):p3e_cpu0_pe1_pch_con_txn(14)" )
			)
			( signal "P3E_CPU0_PE1_PCH_CON_TXN<15>"
				( objectStatus "@baseboard_fab2_lib.baseboard_fab2(sch_1):p3e_cpu0_pe1_pch_con_txn(15)" )
			)
			( signal "P3E_CPU0_PE1_PCH_CON_TXP<8>"
				( objectStatus "@baseboard_fab2_lib.baseboard_fab2(sch_1):p3e_cpu0_pe1_pch_con_txp(8)" )
			)
			( signal "P3E_CPU0_PE1_PCH_CON_TXP<9>"
				( objectStatus "@baseboard_fab2_lib.baseboard_fab2(sch_1):p3e_cpu0_pe1_pch_con_txp(9)" )
			)
			( signal "P3E_CPU0_PE1_PCH_CON_TXP<10>"
				( objectStatus "@baseboard_fab2_lib.baseboard_fab2(sch_1):p3e_cpu0_pe1_pch_con_txp(10)" )
			)
			( signal "P3E_CPU0_PE1_PCH_CON_TXP<11>"
				( objectStatus "@baseboard_fab2_lib.baseboard_fab2(sch_1):p3e_cpu0_pe1_pch_con_txp(11)" )
			)
			( signal "P3E_CPU0_PE1_PCH_CON_TXP<12>"
				( objectStatus "@baseboard_fab2_lib.baseboard_fab2(sch_1):p3e_cpu0_pe1_pch_con_txp(12)" )
			)
			( signal "P3E_CPU0_PE1_PCH_CON_TXP<13>"
				( objectStatus "@baseboard_fab2_lib.baseboard_fab2(sch_1):p3e_cpu0_pe1_pch_con_txp(13)" )
			)
			( signal "P3E_CPU0_PE1_PCH_CON_TXP<14>"
				( objectStatus "@baseboard_fab2_lib.baseboard_fab2(sch_1):p3e_cpu0_pe1_pch_con_txp(14)" )
			)
			( signal "P3E_CPU0_PE1_PCH_CON_TXP<15>"
				( objectStatus "@baseboard_fab2_lib.baseboard_fab2(sch_1):p3e_cpu0_pe1_pch_con_txp(15)" )
			)
			( signal "UV_HIGH_SET_N"
				( objectStatus "@baseboard_fab2_lib.baseboard_fab2(sch_1):uv_high_set_n" )
			)
			( signal "BMC_UV_HIGH_SET"
				( objectStatus "@baseboard_fab2_lib.baseboard_fab2(sch_1):bmc_uv_high_set" )
			)
			( signal "PCA9555_A0"
				( objectStatus "@baseboard_fab2_lib.baseboard_fab2(sch_1):pca9555_a0" )
			)
			( signal "PCA9555_A1"
				( objectStatus "@baseboard_fab2_lib.baseboard_fab2(sch_1):pca9555_a1" )
			)
			( signal "PCA9555_A2"
				( objectStatus "@baseboard_fab2_lib.baseboard_fab2(sch_1):pca9555_a2" )
			)
			( signal "PCA9555_INT_N"
				( objectStatus "@baseboard_fab2_lib.baseboard_fab2(sch_1):pca9555_int_n" )
			)
			( signal "UART_SELECT_Q"
				( objectStatus "@baseboard_fab2_lib.baseboard_fab2(sch_1):uart_select_q" )
			)
			( signal "SPA_MID_DBG1__RX"
				( objectStatus "@baseboard_fab2_lib.baseboard_fab2(sch_1):\spa_mid_dbg1__rx\" )
			)
			( signal "SPA_MID_DBG2_RX"
				( objectStatus "@baseboard_fab2_lib.baseboard_fab2(sch_1):spa_mid_dbg2_rx" )
			)
			( signal "BMC_TPM_HW_C_RST"
				( objectStatus "@baseboard_fab2_lib.baseboard_fab2(sch_1):bmc_tpm_hw_c_rst" )
			)
			( signal "BMC_TPM_HW_RST"
				( objectStatus "@baseboard_fab2_lib.baseboard_fab2(sch_1):bmc_tpm_hw_rst" )
			)
			( signal "FM_TPM_PRES_RST"
				( objectStatus "@baseboard_fab2_lib.baseboard_fab2(sch_1):fm_tpm_pres_rst" )
			)
			( signal "FM_TPM_PRES_RST_N"
				( objectStatus "@baseboard_fab2_lib.baseboard_fab2(sch_1):fm_tpm_pres_rst_n" )
			)
			( signal "VREF_2V2"
				( objectStatus "@baseboard_fab2_lib.baseboard_fab2(sch_1):vref_2v2" )
			)
			( signal "BMC_M_A0"
				( objectStatus "@baseboard_fab2_lib.baseboard_fab2(sch_1):bmc_m_a0" )
			)
			( signal "BMC_M_A1"
				( objectStatus "@baseboard_fab2_lib.baseboard_fab2(sch_1):bmc_m_a1" )
			)
			( signal "BMC_M_A10"
				( objectStatus "@baseboard_fab2_lib.baseboard_fab2(sch_1):bmc_m_a10" )
			)
			( signal "BMC_M_A11"
				( objectStatus "@baseboard_fab2_lib.baseboard_fab2(sch_1):bmc_m_a11" )
			)
			( signal "BMC_M_A12"
				( objectStatus "@baseboard_fab2_lib.baseboard_fab2(sch_1):bmc_m_a12" )
			)
			( signal "BMC_M_A13"
				( objectStatus "@baseboard_fab2_lib.baseboard_fab2(sch_1):bmc_m_a13" )
			)
			( signal "BMC_M_A2"
				( objectStatus "@baseboard_fab2_lib.baseboard_fab2(sch_1):bmc_m_a2" )
			)
			( signal "BMC_M_A3"
				( objectStatus "@baseboard_fab2_lib.baseboard_fab2(sch_1):bmc_m_a3" )
			)
			( signal "BMC_M_A4"
				( objectStatus "@baseboard_fab2_lib.baseboard_fab2(sch_1):bmc_m_a4" )
			)
			( signal "BMC_M_A5"
				( objectStatus "@baseboard_fab2_lib.baseboard_fab2(sch_1):bmc_m_a5" )
			)
			( signal "BMC_M_A6"
				( objectStatus "@baseboard_fab2_lib.baseboard_fab2(sch_1):bmc_m_a6" )
			)
			( signal "BMC_M_A7"
				( objectStatus "@baseboard_fab2_lib.baseboard_fab2(sch_1):bmc_m_a7" )
			)
			( signal "BMC_M_A8"
				( objectStatus "@baseboard_fab2_lib.baseboard_fab2(sch_1):bmc_m_a8" )
			)
			( signal "BMC_M_A9"
				( objectStatus "@baseboard_fab2_lib.baseboard_fab2(sch_1):bmc_m_a9" )
			)
			( signal "BMC_M_BA0"
				( objectStatus "@baseboard_fab2_lib.baseboard_fab2(sch_1):bmc_m_ba0" )
			)
			( signal "BMC_M_BA1"
				( objectStatus "@baseboard_fab2_lib.baseboard_fab2(sch_1):bmc_m_ba1" )
			)
			( signal "BMC_M_BG0"
				( objectStatus "@baseboard_fab2_lib.baseboard_fab2(sch_1):bmc_m_bg0" )
			)
			( signal "BMC_M_CAS_N"
				( objectStatus "@baseboard_fab2_lib.baseboard_fab2(sch_1):bmc_m_cas_n" )
			)
			( signal "BMC_M_CKE"
				( objectStatus "@baseboard_fab2_lib.baseboard_fab2(sch_1):bmc_m_cke" )
			)
			( signal "BMC_M_CLK_DN"
				( objectStatus "@baseboard_fab2_lib.baseboard_fab2(sch_1):bmc_m_clk_dn" )
			)
			( signal "BMC_M_CLK_DP"
				( objectStatus "@baseboard_fab2_lib.baseboard_fab2(sch_1):bmc_m_clk_dp" )
			)
			( signal "BMC_M_CS_N"
				( objectStatus "@baseboard_fab2_lib.baseboard_fab2(sch_1):bmc_m_cs_n" )
			)
			( signal "BMC_M_DM0"
				( objectStatus "@baseboard_fab2_lib.baseboard_fab2(sch_1):bmc_m_dm0" )
			)
			( signal "BMC_M_DM1"
				( objectStatus "@baseboard_fab2_lib.baseboard_fab2(sch_1):bmc_m_dm1" )
			)
			( signal "BMC_M_DQ0"
				( objectStatus "@baseboard_fab2_lib.baseboard_fab2(sch_1):bmc_m_dq0" )
			)
			( signal "BMC_M_DQ1"
				( objectStatus "@baseboard_fab2_lib.baseboard_fab2(sch_1):bmc_m_dq1" )
			)
			( signal "BMC_M_DQ10"
				( objectStatus "@baseboard_fab2_lib.baseboard_fab2(sch_1):bmc_m_dq10" )
			)
			( signal "BMC_M_DQ11"
				( objectStatus "@baseboard_fab2_lib.baseboard_fab2(sch_1):bmc_m_dq11" )
			)
			( signal "BMC_M_DQ12"
				( objectStatus "@baseboard_fab2_lib.baseboard_fab2(sch_1):bmc_m_dq12" )
			)
			( signal "BMC_M_DQ13"
				( objectStatus "@baseboard_fab2_lib.baseboard_fab2(sch_1):bmc_m_dq13" )
			)
			( signal "BMC_M_DQ14"
				( objectStatus "@baseboard_fab2_lib.baseboard_fab2(sch_1):bmc_m_dq14" )
			)
			( signal "BMC_M_DQ15"
				( objectStatus "@baseboard_fab2_lib.baseboard_fab2(sch_1):bmc_m_dq15" )
			)
			( signal "BMC_M_DQ2"
				( objectStatus "@baseboard_fab2_lib.baseboard_fab2(sch_1):bmc_m_dq2" )
			)
			( signal "BMC_M_DQ3"
				( objectStatus "@baseboard_fab2_lib.baseboard_fab2(sch_1):bmc_m_dq3" )
			)
			( signal "BMC_M_DQ4"
				( objectStatus "@baseboard_fab2_lib.baseboard_fab2(sch_1):bmc_m_dq4" )
			)
			( signal "BMC_M_DQ5"
				( objectStatus "@baseboard_fab2_lib.baseboard_fab2(sch_1):bmc_m_dq5" )
			)
			( signal "BMC_M_DQ6"
				( objectStatus "@baseboard_fab2_lib.baseboard_fab2(sch_1):bmc_m_dq6" )
			)
			( signal "BMC_M_DQ7"
				( objectStatus "@baseboard_fab2_lib.baseboard_fab2(sch_1):bmc_m_dq7" )
			)
			( signal "BMC_M_DQ8"
				( objectStatus "@baseboard_fab2_lib.baseboard_fab2(sch_1):bmc_m_dq8" )
			)
			( signal "BMC_M_DQ9"
				( objectStatus "@baseboard_fab2_lib.baseboard_fab2(sch_1):bmc_m_dq9" )
			)
			( signal "BMC_M_DQS0_DN"
				( objectStatus "@baseboard_fab2_lib.baseboard_fab2(sch_1):bmc_m_dqs0_dn" )
			)
			( signal "BMC_M_DQS0_DP"
				( objectStatus "@baseboard_fab2_lib.baseboard_fab2(sch_1):bmc_m_dqs0_dp" )
			)
			( signal "BMC_M_DQS1_DN"
				( objectStatus "@baseboard_fab2_lib.baseboard_fab2(sch_1):bmc_m_dqs1_dn" )
			)
			( signal "BMC_M_DQS1_DP"
				( objectStatus "@baseboard_fab2_lib.baseboard_fab2(sch_1):bmc_m_dqs1_dp" )
			)
			( signal "BMC_M_MACT_N"
				( objectStatus "@baseboard_fab2_lib.baseboard_fab2(sch_1):bmc_m_mact_n" )
			)
			( signal "BMC_M_MALERT_N"
				( objectStatus "@baseboard_fab2_lib.baseboard_fab2(sch_1):bmc_m_malert_n" )
			)
			( signal "BMC_M_ODT"
				( objectStatus "@baseboard_fab2_lib.baseboard_fab2(sch_1):bmc_m_odt" )
			)
			( signal "BMC_M_RAS_N"
				( objectStatus "@baseboard_fab2_lib.baseboard_fab2(sch_1):bmc_m_ras_n" )
			)
			( signal "BMC_M_RST_N"
				( objectStatus "@baseboard_fab2_lib.baseboard_fab2(sch_1):bmc_m_rst_n" )
			)
			( signal "BMC_M_VREFCA"
				( objectStatus "@baseboard_fab2_lib.baseboard_fab2(sch_1):bmc_m_vrefca" )
			)
			( signal "BMC_M_WE_N"
				( objectStatus "@baseboard_fab2_lib.baseboard_fab2(sch_1):bmc_m_we_n" )
			)
			( signal "BMC_MIOZ"
				( objectStatus "@baseboard_fab2_lib.baseboard_fab2(sch_1):bmc_mioz" )
			)
			( signal "BMC_ZQ"
				( objectStatus "@baseboard_fab2_lib.baseboard_fab2(sch_1):bmc_zq" )
			)
			( signal "P1V2_AUX_BMC"
				( attribute "VOLTAGE" "1.5"
					( Units "uVoltage" "V" 1.000000)
					( Status sAliasFlattened )
					( Origin gFrontEnd )
				)
				( objectStatus "@baseboard_fab2_lib.baseboard_fab2(sch_1):p1v2_aux_bmc" )
			)
			( signal "P2V5_AUX_BMC"
				( objectStatus "@baseboard_fab2_lib.baseboard_fab2(sch_1):p2v5_aux_bmc" )
			)
			( signal "BMC_M_PAR"
				( objectStatus "@baseboard_fab2_lib.baseboard_fab2(sch_1):bmc_m_par" )
			)
			( signal "A_DACRSET"
				( objectStatus "@baseboard_fab2_lib.baseboard_fab2(sch_1):a_dacrset" )
			)
			( signal "IRQ_LPC_SERIRQ_R"
				( objectStatus "@baseboard_fab2_lib.baseboard_fab2(sch_1):irq_lpc_serirq_r" )
			)
			( signal "LPC_LAD0_IO0_R"
				( objectStatus "@baseboard_fab2_lib.baseboard_fab2(sch_1):lpc_lad0_io0_r" )
			)
			( signal "LPC_LAD1_IO1_R"
				( objectStatus "@baseboard_fab2_lib.baseboard_fab2(sch_1):lpc_lad1_io1_r" )
			)
			( signal "LPC_LAD2_IO2_R"
				( objectStatus "@baseboard_fab2_lib.baseboard_fab2(sch_1):lpc_lad2_io2_r" )
			)
			( signal "LPC_LAD3_IO3_R"
				( objectStatus "@baseboard_fab2_lib.baseboard_fab2(sch_1):lpc_lad3_io3_r" )
			)
			( signal "LPC_LFRAME_N_CS0_R_N"
				( objectStatus "@baseboard_fab2_lib.baseboard_fab2(sch_1):lpc_lframe_n_cs0_r_n" )
			)
			( signal "VCC_D_PLL_3V3"
				( objectStatus "@baseboard_fab2_lib.baseboard_fab2(sch_1):vcc_d_pll_3v3" )
			)
			( signal "RST_BMC_LVC3_N"
				( objectStatus "@baseboard_fab2_lib.baseboard_fab2(sch_1):rst_bmc_lvc3_n" )
			)
			( signal "SGPIO_BMC_CLK_R"
				( objectStatus "@baseboard_fab2_lib.baseboard_fab2(sch_1):sgpio_bmc_clk_r" )
			)
			( signal "SGPIO_BMC_DOUT_R"
				( objectStatus "@baseboard_fab2_lib.baseboard_fab2(sch_1):sgpio_bmc_dout_r" )
			)
			( signal "SGPIO_BMC_LD_R_N"
				( objectStatus "@baseboard_fab2_lib.baseboard_fab2(sch_1):sgpio_bmc_ld_r_n" )
			)
			( signal "VCC_D_3V3"
				( objectStatus "@baseboard_fab2_lib.baseboard_fab2(sch_1):vcc_d_3v3" )
			)
			( signal "TP_DACG"
				( objectStatus "@baseboard_fab2_lib.baseboard_fab2(sch_1):tp_dacg" )
			)
			( signal "TP_DACB"
				( objectStatus "@baseboard_fab2_lib.baseboard_fab2(sch_1):tp_dacb" )
			)
			( signal "VCC_A_1V1"
				( objectStatus "@baseboard_fab2_lib.baseboard_fab2(sch_1):vcc_a_1v1" )
			)
			( signal "PU_24M_OSC_OE"
				( objectStatus "@baseboard_fab2_lib.baseboard_fab2(sch_1):pu_24m_osc_oe" )
			)
			( signal "TP_JTAG_BMC_RTCK"
				( objectStatus "@baseboard_fab2_lib.baseboard_fab2(sch_1):tp_jtag_bmc_rtck" )
			)
			( signal "SMB_PCIE_SSD_3V3AUX_SDA"
				( objectStatus "@baseboard_fab2_lib.baseboard_fab2(sch_1):smb_pcie_ssd_3v3aux_sda" )
			)
			( signal "A_USB2BVRES"
				( objectStatus "@baseboard_fab2_lib.baseboard_fab2(sch_1):a_usb2bvres" )
			)
			( signal "VCCBAT_TW12"
				( objectStatus "@baseboard_fab2_lib.baseboard_fab2(sch_1):vccbat_tw12" )
			)
			( signal "A_USB2AVRES"
				( objectStatus "@baseboard_fab2_lib.baseboard_fab2(sch_1):a_usb2avres" )
			)
			( signal "GPIOS7"
				( objectStatus "@baseboard_fab2_lib.baseboard_fab2(sch_1):gpios7" )
			)
			( signal "SMB_IPMB_3V3AUX_SCL_R"
				( objectStatus "@baseboard_fab2_lib.baseboard_fab2(sch_1):smb_ipmb_3v3aux_scl_r" )
			)
			( signal "SMB_IPMB_3V3AUX_SDA_R"
				( objectStatus "@baseboard_fab2_lib.baseboard_fab2(sch_1):smb_ipmb_3v3aux_sda_r" )
			)
			( signal "UNNAMED_239_CAP_I84_A"
				( objectStatus "@baseboard_fab2_lib.baseboard_fab2(sch_1):unnamed_239_cap_i84_a" )
			)
			( signal "UNNAMED_239_CAP_I91_A"
				( objectStatus "@baseboard_fab2_lib.baseboard_fab2(sch_1):unnamed_239_cap_i91_a" )
			)
			( signal "UNNAMED_239_OFFPAGE_I76_A"
				( objectStatus "@baseboard_fab2_lib.baseboard_fab2(sch_1):unnamed_239_offpage_i76_a" )
			)
			( signal "FM_TPM_PRES_RST_N_R"
				( objectStatus "@baseboard_fab2_lib.baseboard_fab2(sch_1):fm_tpm_pres_rst_n_r" )
			)
			( signal "FM_SPEAKER_PCH_N_R"
				( objectStatus "@baseboard_fab2_lib.baseboard_fab2(sch_1):fm_speaker_pch_n_r" )
			)
			( signal "USB2_P02_DN"
				( objectStatus "@baseboard_fab2_lib.baseboard_fab2(sch_1):usb2_p02_dn" )
			)
			( signal "USB2_P02_DP"
				( objectStatus "@baseboard_fab2_lib.baseboard_fab2(sch_1):usb2_p02_dp" )
			)
			( signal "CLK_100M_SRC13_DN"
				( objectStatus "@baseboard_fab2_lib.baseboard_fab2(sch_1):clk_100m_src13_dn" )
			)
			( signal "CLK_100M_SRC13_DP"
				( objectStatus "@baseboard_fab2_lib.baseboard_fab2(sch_1):clk_100m_src13_dp" )
			)
			( signal "TP_SMB_BUS11_SCL"
				( objectStatus "@baseboard_fab2_lib.baseboard_fab2(sch_1):tp_smb_bus11_scl" )
			)
			( signal "CLK_24M_BMC_LPC_R1"
				( objectStatus "@baseboard_fab2_lib.baseboard_fab2(sch_1):clk_24m_bmc_lpc_r1" )
			)
			( signal "TP_SMB_BUS11_SDA"
				( objectStatus "@baseboard_fab2_lib.baseboard_fab2(sch_1):tp_smb_bus11_sda" )
			)
			( signal "HSC_SMBUS_SWITCH_EN"
				( objectStatus "@baseboard_fab2_lib.baseboard_fab2(sch_1):hsc_smbus_switch_en" )
			)
			( signal "SMB_HOST_STBY_LVC3_SCL_R3"
				( objectStatus "@baseboard_fab2_lib.baseboard_fab2(sch_1):smb_host_stby_lvc3_scl_r3" )
			)
			( signal "SMB_HOST_STBY_LVC3_SDA_R3"
				( objectStatus "@baseboard_fab2_lib.baseboard_fab2(sch_1):smb_host_stby_lvc3_sda_r3" )
			)
			( signal "PD_ID_EEPROM_WP"
				( objectStatus "@baseboard_fab2_lib.baseboard_fab2(sch_1):pd_id_eeprom_wp" )
			)
			( signal "PU_ID_EEPROM_A2"
				( objectStatus "@baseboard_fab2_lib.baseboard_fab2(sch_1):pu_id_eeprom_a2" )
			)
			( signal "TP_BMC_M_A15"
				( objectStatus "@baseboard_fab2_lib.baseboard_fab2(sch_1):tp_bmc_m_a15" )
			)
			( gate "R6N10"
				( objectStatus "@baseboard_fab2_lib.baseboard_fab2(sch_1):page21_i149" )
			)
			( gate "R6N12"
				( objectStatus "@baseboard_fab2_lib.baseboard_fab2(sch_1):page21_i150" )
			)
			( gate "R6N11"
				( objectStatus "@baseboard_fab2_lib.baseboard_fab2(sch_1):page21_i151" )
			)
			( gate "R6B3"
				( objectStatus "@baseboard_fab2_lib.baseboard_fab2(sch_1):page21_i152" )
			)
			( gate "R6B5"
				( objectStatus "@baseboard_fab2_lib.baseboard_fab2(sch_1):page21_i153" )
			)
			( gate "R6B4"
				( objectStatus "@baseboard_fab2_lib.baseboard_fab2(sch_1):page21_i154" )
			)
			( gate "R6B2"
				( objectStatus "@baseboard_fab2_lib.baseboard_fab2(sch_1):page21_i159" )
			)
			( gate "R6B1"
				( objectStatus "@baseboard_fab2_lib.baseboard_fab2(sch_1):page21_i161" )
			)
			( gate "R6N2"
				( objectStatus "@baseboard_fab2_lib.baseboard_fab2(sch_1):page21_i163" )
			)
			( gate "R6N1"
				( objectStatus "@baseboard_fab2_lib.baseboard_fab2(sch_1):page21_i164" )
			)
			( gate "R5D1"
				( objectStatus "@baseboard_fab2_lib.baseboard_fab2(sch_1):page21_i177" )
			)
			( gate "R5D2"
				( objectStatus "@baseboard_fab2_lib.baseboard_fab2(sch_1):page21_i178" )
			)
			( gate "R6D1"
				( objectStatus "@baseboard_fab2_lib.baseboard_fab2(sch_1):page21_i179" )
			)
			( gate "R4P8"
				( objectStatus "@baseboard_fab2_lib.baseboard_fab2(sch_1):page21_i180" )
			)
			( gate "R4P10"
				( objectStatus "@baseboard_fab2_lib.baseboard_fab2(sch_1):page21_i181" )
			)
			( gate "R4P11"
				( objectStatus "@baseboard_fab2_lib.baseboard_fab2(sch_1):page21_i182" )
			)
			( gate "R6D11"
				( objectStatus "@baseboard_fab2_lib.baseboard_fab2(sch_1):page21_i184" )
			)
			( gate "R4P3"
				( objectStatus "@baseboard_fab2_lib.baseboard_fab2(sch_1):page21_i186" )
			)
			( gate "R4P2"
				( objectStatus "@baseboard_fab2_lib.baseboard_fab2(sch_1):page21_i188" )
			)
			( gate "R4P4"
				( objectStatus "@baseboard_fab2_lib.baseboard_fab2(sch_1):page21_i189" )
			)
			( gate "R6D2"
				( objectStatus "@baseboard_fab2_lib.baseboard_fab2(sch_1):page21_i204" )
			)
			( gate "XRU1"
				( objectStatus "@baseboard_fab2_lib.baseboard_fab2(sch_1):page21_i216" )
			)
			( gate "XLU1"
				( objectStatus "@baseboard_fab2_lib.baseboard_fab2(sch_1):page21_i217" )
			)
			( gate "R4P19"
				( objectStatus "@baseboard_fab2_lib.baseboard_fab2(sch_1):page21_i219" )
			)
			( gate "R5N2"
				( objectStatus "@baseboard_fab2_lib.baseboard_fab2(sch_1):page21_i227" )
			)
			( gate "R5N1"
				( objectStatus "@baseboard_fab2_lib.baseboard_fab2(sch_1):page21_i238" )
			)
			( gate "R5N5"
				( objectStatus "@baseboard_fab2_lib.baseboard_fab2(sch_1):page21_i239" )
			)
			( gate "R5N3"
				( objectStatus "@baseboard_fab2_lib.baseboard_fab2(sch_1):page21_i240" )
			)
			( gate "R5N4"
				( objectStatus "@baseboard_fab2_lib.baseboard_fab2(sch_1):page21_i241" )
			)
			( gate "R4P18"
				( objectStatus "@baseboard_fab2_lib.baseboard_fab2(sch_1):page21_i244" )
			)
			( gate "R4R5"
				( objectStatus "@baseboard_fab2_lib.baseboard_fab2(sch_1):page21_i258" )
			)
			( gate "U5D1"
				( objectStatus "@baseboard_fab2_lib.baseboard_fab2(sch_1):page21_i259" )
			)
			( gate "R5R1"
				( objectStatus "@baseboard_fab2_lib.baseboard_fab2(sch_1):page22_i188" )
			)
			( gate "R5P4"
				( objectStatus "@baseboard_fab2_lib.baseboard_fab2(sch_1):page22_i190" )
			)
			( gate "U5D1"
				( objectStatus "@baseboard_fab2_lib.baseboard_fab2(sch_1):page22_i204" )
			)
			( gate "U5D1"
				( objectStatus "@baseboard_fab2_lib.baseboard_fab2(sch_1):page23_i172" )
			)
			( gate "U5D1"
				( objectStatus "@baseboard_fab2_lib.baseboard_fab2(sch_1):page24_i172" )
			)
			( gate "U5D1"
				( objectStatus "@baseboard_fab2_lib.baseboard_fab2(sch_1):page25_i172" )
			)
			( gate "U5D1"
				( objectStatus "@baseboard_fab2_lib.baseboard_fab2(sch_1):page26_i172" )
			)
			( gate "U5D1"
				( objectStatus "@baseboard_fab2_lib.baseboard_fab2(sch_1):page27_i172" )
			)
			( gate "U5D1"
				( objectStatus "@baseboard_fab2_lib.baseboard_fab2(sch_1):page28_i172" )
			)
			( gate "U5D1"
				( objectStatus "@baseboard_fab2_lib.baseboard_fab2(sch_1):page29_i61" )
			)
			( gate "U5D1"
				( objectStatus "@baseboard_fab2_lib.baseboard_fab2(sch_1):page30_i84" )
			)
			( gate "U5D1"
				( objectStatus "@baseboard_fab2_lib.baseboard_fab2(sch_1):page31_i106" )
			)
			( gate "U5D1"
				( objectStatus "@baseboard_fab2_lib.baseboard_fab2(sch_1):page32_i89" )
			)
			( gate "U5D1"
				( objectStatus "@baseboard_fab2_lib.baseboard_fab2(sch_1):page33_i86" )
			)
			( gate "U5D1"
				( objectStatus "@baseboard_fab2_lib.baseboard_fab2(sch_1):page34_i86" )
			)
			( gate "U5D1"
				( objectStatus "@baseboard_fab2_lib.baseboard_fab2(sch_1):page35_i3" )
			)
			( gate "U5D1"
				( objectStatus "@baseboard_fab2_lib.baseboard_fab2(sch_1):page36_i15" )
			)
			( gate "U5D1"
				( objectStatus "@baseboard_fab2_lib.baseboard_fab2(sch_1):page36_i16" )
			)
			( gate "R5D5"
				( objectStatus "@baseboard_fab2_lib.baseboard_fab2(sch_1):page37_i303" )
			)
			( gate "R5P1"
				( objectStatus "@baseboard_fab2_lib.baseboard_fab2(sch_1):page37_i309" )
			)
			( gate "U5D1"
				( objectStatus "@baseboard_fab2_lib.baseboard_fab2(sch_1):page37_i310" )
			)
			( gate "U5D1"
				( objectStatus "@baseboard_fab2_lib.baseboard_fab2(sch_1):page37_i311" )
			)
			( gate "R5D6"
				( objectStatus "@baseboard_fab2_lib.baseboard_fab2(sch_1):page37_i312" )
			)
			( gate "C6D1"
				( objectStatus "@baseboard_fab2_lib.baseboard_fab2(sch_1):page38_i19" )
			)
			( gate "U5D1"
				( objectStatus "@baseboard_fab2_lib.baseboard_fab2(sch_1):page38_i33" )
			)
			( gate "U5D1"
				( objectStatus "@baseboard_fab2_lib.baseboard_fab2(sch_1):page38_i34" )
			)
			( gate "U5D1"
				( objectStatus "@baseboard_fab2_lib.baseboard_fab2(sch_1):page39_i127" )
			)
			( gate "U5D1"
				( objectStatus "@baseboard_fab2_lib.baseboard_fab2(sch_1):page40_i20" )
			)
			( gate "U5D1"
				( objectStatus "@baseboard_fab2_lib.baseboard_fab2(sch_1):page40_i21" )
			)
			( gate "U5D1"
				( objectStatus "@baseboard_fab2_lib.baseboard_fab2(sch_1):page40_i22" )
			)
			( gate "U5D1"
				( objectStatus "@baseboard_fab2_lib.baseboard_fab2(sch_1):page40_i23" )
			)
			( gate "U5D1"
				( objectStatus "@baseboard_fab2_lib.baseboard_fab2(sch_1):page41_i283" )
			)
			( gate "U5D1"
				( objectStatus "@baseboard_fab2_lib.baseboard_fab2(sch_1):page41_i284" )
			)
			( gate "U5D1"
				( objectStatus "@baseboard_fab2_lib.baseboard_fab2(sch_1):page41_i285" )
			)
			( gate "U5D1"
				( objectStatus "@baseboard_fab2_lib.baseboard_fab2(sch_1):page41_i286" )
			)
			( gate "C5P18"
				( objectStatus "@baseboard_fab2_lib.baseboard_fab2(sch_1):page42_i2" )
			)
			( gate "C5P28"
				( objectStatus "@baseboard_fab2_lib.baseboard_fab2(sch_1):page42_i3" )
			)
			( gate "C5P11"
				( objectStatus "@baseboard_fab2_lib.baseboard_fab2(sch_1):page42_i4" )
			)
			( gate "C5P10"
				( objectStatus "@baseboard_fab2_lib.baseboard_fab2(sch_1):page42_i6" )
			)
			( gate "C4P3"
				( objectStatus "@baseboard_fab2_lib.baseboard_fab2(sch_1):page42_i8" )
			)
			( gate "C4P7"
				( objectStatus "@baseboard_fab2_lib.baseboard_fab2(sch_1):page42_i9" )
			)
			( gate "C4P1"
				( objectStatus "@baseboard_fab2_lib.baseboard_fab2(sch_1):page42_i10" )
			)
			( gate "C4P9"
				( objectStatus "@baseboard_fab2_lib.baseboard_fab2(sch_1):page42_i12" )
			)
			( gate "C5P19"
				( objectStatus "@baseboard_fab2_lib.baseboard_fab2(sch_1):page42_i13" )
			)
			( gate "C4P4"
				( objectStatus "@baseboard_fab2_lib.baseboard_fab2(sch_1):page42_i14" )
			)
			( gate "C4P10"
				( objectStatus "@baseboard_fab2_lib.baseboard_fab2(sch_1):page42_i17" )
			)
			( gate "C5P9"
				( objectStatus "@baseboard_fab2_lib.baseboard_fab2(sch_1):page42_i18" )
			)
			( gate "C5P8"
				( objectStatus "@baseboard_fab2_lib.baseboard_fab2(sch_1):page42_i19" )
			)
			( gate "C5P7"
				( objectStatus "@baseboard_fab2_lib.baseboard_fab2(sch_1):page42_i25" )
			)
			( gate "C5P4"
				( objectStatus "@baseboard_fab2_lib.baseboard_fab2(sch_1):page42_i27" )
			)
			( gate "C5P23"
				( objectStatus "@baseboard_fab2_lib.baseboard_fab2(sch_1):page42_i28" )
			)
			( gate "C5P24"
				( objectStatus "@baseboard_fab2_lib.baseboard_fab2(sch_1):page42_i33" )
			)
			( gate "C5P25"
				( objectStatus "@baseboard_fab2_lib.baseboard_fab2(sch_1):page42_i37" )
			)
			( gate "C5P6"
				( objectStatus "@baseboard_fab2_lib.baseboard_fab2(sch_1):page42_i38" )
			)
			( gate "C5P41"
				( objectStatus "@baseboard_fab2_lib.baseboard_fab2(sch_1):page42_i40" )
			)
			( gate "C5P14"
				( objectStatus "@baseboard_fab2_lib.baseboard_fab2(sch_1):page42_i41" )
			)
			( gate "C5P5"
				( objectStatus "@baseboard_fab2_lib.baseboard_fab2(sch_1):page42_i42" )
			)
			( gate "C5P27"
				( objectStatus "@baseboard_fab2_lib.baseboard_fab2(sch_1):page42_i44" )
			)
			( gate "C5P33"
				( objectStatus "@baseboard_fab2_lib.baseboard_fab2(sch_1):page42_i50" )
			)
			( gate "C5P35"
				( objectStatus "@baseboard_fab2_lib.baseboard_fab2(sch_1):page42_i51" )
			)
			( gate "C5P32"
				( objectStatus "@baseboard_fab2_lib.baseboard_fab2(sch_1):page42_i53" )
			)
			( gate "C5P34"
				( objectStatus "@baseboard_fab2_lib.baseboard_fab2(sch_1):page42_i54" )
			)
			( gate "C5P22"
				( objectStatus "@baseboard_fab2_lib.baseboard_fab2(sch_1):page42_i55" )
			)
			( gate "C5P26"
				( objectStatus "@baseboard_fab2_lib.baseboard_fab2(sch_1):page42_i56" )
			)
			( gate "C5P40"
				( objectStatus "@baseboard_fab2_lib.baseboard_fab2(sch_1):page42_i57" )
			)
			( gate "C5P42"
				( objectStatus "@baseboard_fab2_lib.baseboard_fab2(sch_1):page42_i59" )
			)
			( gate "C5P43"
				( objectStatus "@baseboard_fab2_lib.baseboard_fab2(sch_1):page42_i60" )
			)
			( gate "C5P44"
				( objectStatus "@baseboard_fab2_lib.baseboard_fab2(sch_1):page42_i61" )
			)
			( gate "C5P37"
				( objectStatus "@baseboard_fab2_lib.baseboard_fab2(sch_1):page42_i63" )
			)
			( gate "C5P36"
				( objectStatus "@baseboard_fab2_lib.baseboard_fab2(sch_1):page42_i65" )
			)
			( gate "C6D8"
				( objectStatus "@baseboard_fab2_lib.baseboard_fab2(sch_1):page42_i68" )
			)
			( gate "C5D38"
				( objectStatus "@baseboard_fab2_lib.baseboard_fab2(sch_1):page42_i69" )
			)
			( gate "C5D37"
				( objectStatus "@baseboard_fab2_lib.baseboard_fab2(sch_1):page42_i70" )
			)
			( gate "C6D7"
				( objectStatus "@baseboard_fab2_lib.baseboard_fab2(sch_1):page42_i72" )
			)
			( gate "C6D4"
				( objectStatus "@baseboard_fab2_lib.baseboard_fab2(sch_1):page42_i74" )
			)
			( gate "C6D5"
				( objectStatus "@baseboard_fab2_lib.baseboard_fab2(sch_1):page42_i75" )
			)
			( gate "C6D2"
				( objectStatus "@baseboard_fab2_lib.baseboard_fab2(sch_1):page42_i77" )
			)
			( gate "C6D3"
				( objectStatus "@baseboard_fab2_lib.baseboard_fab2(sch_1):page42_i80" )
			)
			( gate "C6D6"
				( objectStatus "@baseboard_fab2_lib.baseboard_fab2(sch_1):page42_i81" )
			)
			( gate "C5D51"
				( objectStatus "@baseboard_fab2_lib.baseboard_fab2(sch_1):page42_i83" )
			)
			( gate "C5D21"
				( objectStatus "@baseboard_fab2_lib.baseboard_fab2(sch_1):page42_i88" )
			)
			( gate "C5D50"
				( objectStatus "@baseboard_fab2_lib.baseboard_fab2(sch_1):page42_i89" )
			)
			( gate "C5D48"
				( objectStatus "@baseboard_fab2_lib.baseboard_fab2(sch_1):page42_i90" )
			)
			( gate "C5D13"
				( objectStatus "@baseboard_fab2_lib.baseboard_fab2(sch_1):page42_i91" )
			)
			( gate "C5D11"
				( objectStatus "@baseboard_fab2_lib.baseboard_fab2(sch_1):page42_i93" )
			)
			( gate "C5D12"
				( objectStatus "@baseboard_fab2_lib.baseboard_fab2(sch_1):page42_i94" )
			)
			( gate "C5D23"
				( objectStatus "@baseboard_fab2_lib.baseboard_fab2(sch_1):page42_i98" )
			)
			( gate "C5D28"
				( objectStatus "@baseboard_fab2_lib.baseboard_fab2(sch_1):page42_i100" )
			)
			( gate "C5D29"
				( objectStatus "@baseboard_fab2_lib.baseboard_fab2(sch_1):page42_i102" )
			)
			( gate "C5D32"
				( objectStatus "@baseboard_fab2_lib.baseboard_fab2(sch_1):page42_i103" )
			)
			( gate "C5D47"
				( objectStatus "@baseboard_fab2_lib.baseboard_fab2(sch_1):page42_i104" )
			)
			( gate "C5D31"
				( objectStatus "@baseboard_fab2_lib.baseboard_fab2(sch_1):page42_i106" )
			)
			( gate "C5D46"
				( objectStatus "@baseboard_fab2_lib.baseboard_fab2(sch_1):page42_i107" )
			)
			( gate "C5D10"
				( objectStatus "@baseboard_fab2_lib.baseboard_fab2(sch_1):page42_i108" )
			)
			( gate "C5D27"
				( objectStatus "@baseboard_fab2_lib.baseboard_fab2(sch_1):page42_i109" )
			)
			( gate "C5D30"
				( objectStatus "@baseboard_fab2_lib.baseboard_fab2(sch_1):page42_i111" )
			)
			( gate "C5D60"
				( objectStatus "@baseboard_fab2_lib.baseboard_fab2(sch_1):page42_i112" )
			)
			( gate "C5D61"
				( objectStatus "@baseboard_fab2_lib.baseboard_fab2(sch_1):page42_i113" )
			)
			( gate "C5D41"
				( objectStatus "@baseboard_fab2_lib.baseboard_fab2(sch_1):page42_i114" )
			)
			( gate "C5D40"
				( objectStatus "@baseboard_fab2_lib.baseboard_fab2(sch_1):page42_i115" )
			)
			( gate "C5D14"
				( objectStatus "@baseboard_fab2_lib.baseboard_fab2(sch_1):page42_i117" )
			)
			( gate "C5D17"
				( objectStatus "@baseboard_fab2_lib.baseboard_fab2(sch_1):page42_i118" )
			)
			( gate "C5D58"
				( objectStatus "@baseboard_fab2_lib.baseboard_fab2(sch_1):page42_i120" )
			)
			( gate "C5D16"
				( objectStatus "@baseboard_fab2_lib.baseboard_fab2(sch_1):page42_i123" )
			)
			( gate "C5D5"
				( objectStatus "@baseboard_fab2_lib.baseboard_fab2(sch_1):page42_i125" )
			)
			( gate "C5D1"
				( objectStatus "@baseboard_fab2_lib.baseboard_fab2(sch_1):page42_i126" )
			)
			( gate "C5D4"
				( objectStatus "@baseboard_fab2_lib.baseboard_fab2(sch_1):page42_i127" )
			)
			( gate "C5D19"
				( objectStatus "@baseboard_fab2_lib.baseboard_fab2(sch_1):page42_i128" )
			)
			( gate "C5D59"
				( objectStatus "@baseboard_fab2_lib.baseboard_fab2(sch_1):page42_i129" )
			)
			( gate "C5D3"
				( objectStatus "@baseboard_fab2_lib.baseboard_fab2(sch_1):page42_i130" )
			)
			( gate "C5D43"
				( objectStatus "@baseboard_fab2_lib.baseboard_fab2(sch_1):page42_i131" )
			)
			( gate "C5D15"
				( objectStatus "@baseboard_fab2_lib.baseboard_fab2(sch_1):page42_i132" )
			)
			( gate "C5D18"
				( objectStatus "@baseboard_fab2_lib.baseboard_fab2(sch_1):page42_i134" )
			)
			( gate "C5D42"
				( objectStatus "@baseboard_fab2_lib.baseboard_fab2(sch_1):page42_i135" )
			)
			( gate "C5D2"
				( objectStatus "@baseboard_fab2_lib.baseboard_fab2(sch_1):page42_i136" )
			)
			( gate "C5D24"
				( objectStatus "@baseboard_fab2_lib.baseboard_fab2(sch_1):page42_i138" )
			)
			( gate "C5D39"
				( objectStatus "@baseboard_fab2_lib.baseboard_fab2(sch_1):page42_i140" )
			)
			( gate "C5D44"
				( objectStatus "@baseboard_fab2_lib.baseboard_fab2(sch_1):page42_i142" )
			)
			( gate "C6D9"
				( objectStatus "@baseboard_fab2_lib.baseboard_fab2(sch_1):page42_i145" )
			)
			( gate "C6D10"
				( objectStatus "@baseboard_fab2_lib.baseboard_fab2(sch_1):page42_i147" )
			)
			( gate "C5P30"
				( objectStatus "@baseboard_fab2_lib.baseboard_fab2(sch_1):page42_i148" )
			)
			( gate "C5P29"
				( objectStatus "@baseboard_fab2_lib.baseboard_fab2(sch_1):page42_i149" )
			)
			( gate "C5D36"
				( objectStatus "@baseboard_fab2_lib.baseboard_fab2(sch_1):page42_i151" )
			)
			( gate "C5D49"
				( objectStatus "@baseboard_fab2_lib.baseboard_fab2(sch_1):page42_i152" )
			)
			( gate "C5D22"
				( objectStatus "@baseboard_fab2_lib.baseboard_fab2(sch_1):page42_i153" )
			)
			( gate "C5D26"
				( objectStatus "@baseboard_fab2_lib.baseboard_fab2(sch_1):page42_i154" )
			)
			( gate "C5D25"
				( objectStatus "@baseboard_fab2_lib.baseboard_fab2(sch_1):page42_i155" )
			)
			( gate "C5D45"
				( objectStatus "@baseboard_fab2_lib.baseboard_fab2(sch_1):page42_i156" )
			)
			( gate "C5P31"
				( objectStatus "@baseboard_fab2_lib.baseboard_fab2(sch_1):page42_i162" )
			)
			( gate "C4P2"
				( objectStatus "@baseboard_fab2_lib.baseboard_fab2(sch_1):page42_i163" )
			)
			( gate "C4P6"
				( objectStatus "@baseboard_fab2_lib.baseboard_fab2(sch_1):page42_i164" )
			)
			( gate "C4P5"
				( objectStatus "@baseboard_fab2_lib.baseboard_fab2(sch_1):page42_i172" )
			)
			( gate "C5D20"
				( objectStatus "@baseboard_fab2_lib.baseboard_fab2(sch_1):page42_i173" )
			)
			( gate "C5D33"
				( objectStatus "@baseboard_fab2_lib.baseboard_fab2(sch_1):page42_i174" )
			)
			( gate "C5D34"
				( objectStatus "@baseboard_fab2_lib.baseboard_fab2(sch_1):page42_i175" )
			)
			( gate "C5D35"
				( objectStatus "@baseboard_fab2_lib.baseboard_fab2(sch_1):page42_i176" )
			)
			( gate "C4P8"
				( objectStatus "@baseboard_fab2_lib.baseboard_fab2(sch_1):page42_i178" )
			)
			( gate "C5D53"
				( objectStatus "@baseboard_fab2_lib.baseboard_fab2(sch_1):page42_i179" )
			)
			( gate "C5D52"
				( objectStatus "@baseboard_fab2_lib.baseboard_fab2(sch_1):page42_i180" )
			)
			( gate "C5P12"
				( objectStatus "@baseboard_fab2_lib.baseboard_fab2(sch_1):page42_i183" )
			)
			( gate "C5P21"
				( objectStatus "@baseboard_fab2_lib.baseboard_fab2(sch_1):page42_i184" )
			)
			( gate "C5P20"
				( objectStatus "@baseboard_fab2_lib.baseboard_fab2(sch_1):page42_i185" )
			)
			( gate "C5P13"
				( objectStatus "@baseboard_fab2_lib.baseboard_fab2(sch_1):page42_i186" )
			)
			( gate "C5P15"
				( objectStatus "@baseboard_fab2_lib.baseboard_fab2(sch_1):page42_i187" )
			)
			( gate "C5P16"
				( objectStatus "@baseboard_fab2_lib.baseboard_fab2(sch_1):page42_i188" )
			)
			( gate "C5P3"
				( objectStatus "@baseboard_fab2_lib.baseboard_fab2(sch_1):page42_i189" )
			)
			( gate "C5P17"
				( objectStatus "@baseboard_fab2_lib.baseboard_fab2(sch_1):page42_i190" )
			)
			( gate "J4G1"
				( objectStatus "@baseboard_fab2_lib.baseboard_fab2(sch_1):page43_i1" )
			)
			( gate "J4G1"
				( objectStatus "@baseboard_fab2_lib.baseboard_fab2(sch_1):page43_i2" )
			)
			( gate "J4G1"
				( objectStatus "@baseboard_fab2_lib.baseboard_fab2(sch_1):page43_i259" )
			)
			( gate "J4G1"
				( objectStatus "@baseboard_fab2_lib.baseboard_fab2(sch_1):page43_i260" )
			)
			( gate "C4F10"
				( objectStatus "@baseboard_fab2_lib.baseboard_fab2(sch_1):page43_i272" )
			)
			( gate "C6T1"
				( objectStatus "@baseboard_fab2_lib.baseboard_fab2(sch_1):page44_i2" )
			)
			( gate "J6T1"
				( objectStatus "@baseboard_fab2_lib.baseboard_fab2(sch_1):page44_i13" )
			)
			( gate "J6T1"
				( objectStatus "@baseboard_fab2_lib.baseboard_fab2(sch_1):page44_i75" )
			)
			( gate "J6T1"
				( objectStatus "@baseboard_fab2_lib.baseboard_fab2(sch_1):page44_i120" )
			)
			( gate "J6T1"
				( objectStatus "@baseboard_fab2_lib.baseboard_fab2(sch_1):page44_i139" )
			)
			( gate "J4G2"
				( objectStatus "@baseboard_fab2_lib.baseboard_fab2(sch_1):page45_i43" )
			)
			( gate "J4G2"
				( objectStatus "@baseboard_fab2_lib.baseboard_fab2(sch_1):page45_i61" )
			)
			( gate "J4G2"
				( objectStatus "@baseboard_fab2_lib.baseboard_fab2(sch_1):page45_i111" )
			)
			( gate "J4G2"
				( objectStatus "@baseboard_fab2_lib.baseboard_fab2(sch_1):page45_i169" )
			)
			( gate "C4G3"
				( objectStatus "@baseboard_fab2_lib.baseboard_fab2(sch_1):page45_i179" )
			)
			( gate "C6U9"
				( objectStatus "@baseboard_fab2_lib.baseboard_fab2(sch_1):page46_i5" )
			)
			( gate "J6U1"
				( objectStatus "@baseboard_fab2_lib.baseboard_fab2(sch_1):page46_i14" )
			)
			( gate "J6U1"
				( objectStatus "@baseboard_fab2_lib.baseboard_fab2(sch_1):page46_i67" )
			)
			( gate "J6U1"
				( objectStatus "@baseboard_fab2_lib.baseboard_fab2(sch_1):page46_i112" )
			)
			( gate "J6U1"
				( objectStatus "@baseboard_fab2_lib.baseboard_fab2(sch_1):page46_i138" )
			)
			( gate "J4G3"
				( objectStatus "@baseboard_fab2_lib.baseboard_fab2(sch_1):page47_i43" )
			)
			( gate "J4G3"
				( objectStatus "@baseboard_fab2_lib.baseboard_fab2(sch_1):page47_i61" )
			)
			( gate "J4G3"
				( objectStatus "@baseboard_fab2_lib.baseboard_fab2(sch_1):page47_i111" )
			)
			( gate "J4G3"
				( objectStatus "@baseboard_fab2_lib.baseboard_fab2(sch_1):page47_i179" )
			)
			( gate "C4G19"
				( objectStatus "@baseboard_fab2_lib.baseboard_fab2(sch_1):page47_i188" )
			)
			( gate "J6U2"
				( objectStatus "@baseboard_fab2_lib.baseboard_fab2(sch_1):page48_i43" )
			)
			( gate "J6U2"
				( objectStatus "@baseboard_fab2_lib.baseboard_fab2(sch_1):page48_i61" )
			)
			( gate "J6U2"
				( objectStatus "@baseboard_fab2_lib.baseboard_fab2(sch_1):page48_i111" )
			)
			( gate "J6U2"
				( objectStatus "@baseboard_fab2_lib.baseboard_fab2(sch_1):page48_i171" )
			)
			( gate "C6U17"
				( objectStatus "@baseboard_fab2_lib.baseboard_fab2(sch_1):page48_i176" )
			)
			( gate "J4B1"
				( objectStatus "@baseboard_fab2_lib.baseboard_fab2(sch_1):page49_i43" )
			)
			( gate "J4B1"
				( objectStatus "@baseboard_fab2_lib.baseboard_fab2(sch_1):page49_i66" )
			)
			( gate "J4B1"
				( objectStatus "@baseboard_fab2_lib.baseboard_fab2(sch_1):page49_i111" )
			)
			( gate "J4B1"
				( objectStatus "@baseboard_fab2_lib.baseboard_fab2(sch_1):page49_i169" )
			)
			( gate "C4B12"
				( objectStatus "@baseboard_fab2_lib.baseboard_fab2(sch_1):page49_i179" )
			)
			( gate "J6M1"
				( objectStatus "@baseboard_fab2_lib.baseboard_fab2(sch_1):page50_i44" )
			)
			( gate "J6M1"
				( objectStatus "@baseboard_fab2_lib.baseboard_fab2(sch_1):page50_i46" )
			)
			( gate "J6M1"
				( objectStatus "@baseboard_fab2_lib.baseboard_fab2(sch_1):page50_i50" )
			)
			( gate "J6M1"
				( objectStatus "@baseboard_fab2_lib.baseboard_fab2(sch_1):page50_i158" )
			)
			( gate "C6M1"
				( objectStatus "@baseboard_fab2_lib.baseboard_fab2(sch_1):page50_i177" )
			)
			( gate "J4A2"
				( objectStatus "@baseboard_fab2_lib.baseboard_fab2(sch_1):page51_i43" )
			)
			( gate "J4A2"
				( objectStatus "@baseboard_fab2_lib.baseboard_fab2(sch_1):page51_i66" )
			)
			( gate "J4A2"
				( objectStatus "@baseboard_fab2_lib.baseboard_fab2(sch_1):page51_i111" )
			)
			( gate "J4A2"
				( objectStatus "@baseboard_fab2_lib.baseboard_fab2(sch_1):page51_i167" )
			)
			( gate "C6L6"
				( objectStatus "@baseboard_fab2_lib.baseboard_fab2(sch_1):page51_i175" )
			)
			( gate "C4A18"
				( objectStatus "@baseboard_fab2_lib.baseboard_fab2(sch_1):page52_i3" )
			)
			( gate "J6L2"
				( objectStatus "@baseboard_fab2_lib.baseboard_fab2(sch_1):page52_i12" )
			)
			( gate "J6L2"
				( objectStatus "@baseboard_fab2_lib.baseboard_fab2(sch_1):page52_i55" )
			)
			( gate "J6L2"
				( objectStatus "@baseboard_fab2_lib.baseboard_fab2(sch_1):page52_i100" )
			)
			( gate "J6L2"
				( objectStatus "@baseboard_fab2_lib.baseboard_fab2(sch_1):page52_i138" )
			)
			( gate "J4A1"
				( objectStatus "@baseboard_fab2_lib.baseboard_fab2(sch_1):page53_i43" )
			)
			( gate "J4A1"
				( objectStatus "@baseboard_fab2_lib.baseboard_fab2(sch_1):page53_i66" )
			)
			( gate "J4A1"
				( objectStatus "@baseboard_fab2_lib.baseboard_fab2(sch_1):page53_i111" )
			)
			( gate "J4A1"
				( objectStatus "@baseboard_fab2_lib.baseboard_fab2(sch_1):page53_i171" )
			)
			( gate "C6L1"
				( objectStatus "@baseboard_fab2_lib.baseboard_fab2(sch_1):page53_i178" )
			)
			( gate "J6L1"
				( objectStatus "@baseboard_fab2_lib.baseboard_fab2(sch_1):page54_i43" )
			)
			( gate "J6L1"
				( objectStatus "@baseboard_fab2_lib.baseboard_fab2(sch_1):page54_i66" )
			)
			( gate "J6L1"
				( objectStatus "@baseboard_fab2_lib.baseboard_fab2(sch_1):page54_i111" )
			)
			( gate "J6L1"
				( objectStatus "@baseboard_fab2_lib.baseboard_fab2(sch_1):page54_i170" )
			)
			( gate "C4A5"
				( objectStatus "@baseboard_fab2_lib.baseboard_fab2(sch_1):page54_i179" )
			)
			( gate "R9N1"
				( objectStatus "@baseboard_fab2_lib.baseboard_fab2(sch_1):page55_i4" )
			)
			( gate "R9N2"
				( objectStatus "@baseboard_fab2_lib.baseboard_fab2(sch_1):page55_i7" )
			)
			( gate "R3B2"
				( objectStatus "@baseboard_fab2_lib.baseboard_fab2(sch_1):page55_i19" )
			)
			( gate "R3B4"
				( objectStatus "@baseboard_fab2_lib.baseboard_fab2(sch_1):page55_i21" )
			)
			( gate "R1C2"
				( objectStatus "@baseboard_fab2_lib.baseboard_fab2(sch_1):page55_i24" )
			)
			( gate "R1C3"
				( objectStatus "@baseboard_fab2_lib.baseboard_fab2(sch_1):page55_i25" )
			)
			( gate "R1C1"
				( objectStatus "@baseboard_fab2_lib.baseboard_fab2(sch_1):page55_i26" )
			)
			( gate "R3B1"
				( objectStatus "@baseboard_fab2_lib.baseboard_fab2(sch_1):page55_i27" )
			)
			( gate "R3B5"
				( objectStatus "@baseboard_fab2_lib.baseboard_fab2(sch_1):page55_i28" )
			)
			( gate "R3B3"
				( objectStatus "@baseboard_fab2_lib.baseboard_fab2(sch_1):page55_i29" )
			)
			( gate "R7P19"
				( objectStatus "@baseboard_fab2_lib.baseboard_fab2(sch_1):page55_i115" )
			)
			( gate "R3D1"
				( objectStatus "@baseboard_fab2_lib.baseboard_fab2(sch_1):page55_i116" )
			)
			( gate "R3D2"
				( objectStatus "@baseboard_fab2_lib.baseboard_fab2(sch_1):page55_i117" )
			)
			( gate "R3D3"
				( objectStatus "@baseboard_fab2_lib.baseboard_fab2(sch_1):page55_i118" )
			)
			( gate "R7P16"
				( objectStatus "@baseboard_fab2_lib.baseboard_fab2(sch_1):page55_i119" )
			)
			( gate "R7P8"
				( objectStatus "@baseboard_fab2_lib.baseboard_fab2(sch_1):page55_i123" )
			)
			( gate "R7P10"
				( objectStatus "@baseboard_fab2_lib.baseboard_fab2(sch_1):page55_i124" )
			)
			( gate "R3D19"
				( objectStatus "@baseboard_fab2_lib.baseboard_fab2(sch_1):page55_i125" )
			)
			( gate "R7P11"
				( objectStatus "@baseboard_fab2_lib.baseboard_fab2(sch_1):page55_i126" )
			)
			( gate "R7P17"
				( objectStatus "@baseboard_fab2_lib.baseboard_fab2(sch_1):page55_i140" )
			)
			( gate "XRU2"
				( objectStatus "@baseboard_fab2_lib.baseboard_fab2(sch_1):page55_i152" )
			)
			( gate "XLU2"
				( objectStatus "@baseboard_fab2_lib.baseboard_fab2(sch_1):page55_i153" )
			)
			( gate "R3D4"
				( objectStatus "@baseboard_fab2_lib.baseboard_fab2(sch_1):page55_i155" )
			)
			( gate "R7P26"
				( objectStatus "@baseboard_fab2_lib.baseboard_fab2(sch_1):page55_i156" )
			)
			( gate "R8N1"
				( objectStatus "@baseboard_fab2_lib.baseboard_fab2(sch_1):page55_i157" )
			)
			( gate "R8N4"
				( objectStatus "@baseboard_fab2_lib.baseboard_fab2(sch_1):page55_i158" )
			)
			( gate "R8N3"
				( objectStatus "@baseboard_fab2_lib.baseboard_fab2(sch_1):page55_i159" )
			)
			( gate "R8N5"
				( objectStatus "@baseboard_fab2_lib.baseboard_fab2(sch_1):page55_i160" )
			)
			( gate "R8N2"
				( objectStatus "@baseboard_fab2_lib.baseboard_fab2(sch_1):page55_i161" )
			)
			( gate "R7P25"
				( objectStatus "@baseboard_fab2_lib.baseboard_fab2(sch_1):page55_i170" )
			)
			( gate "U2D1"
				( objectStatus "@baseboard_fab2_lib.baseboard_fab2(sch_1):page55_i172" )
			)
			( gate "R6P39"
				( objectStatus "@baseboard_fab2_lib.baseboard_fab2(sch_1):page55_i181" )
			)
			( gate "U2D1"
				( objectStatus "@baseboard_fab2_lib.baseboard_fab2(sch_1):page56_i169" )
			)
			( gate "R8P3"
				( objectStatus "@baseboard_fab2_lib.baseboard_fab2(sch_1):page56_i173" )
			)
			( gate "R8R1"
				( objectStatus "@baseboard_fab2_lib.baseboard_fab2(sch_1):page56_i174" )
			)
			( gate "U2D1"
				( objectStatus "@baseboard_fab2_lib.baseboard_fab2(sch_1):page57_i172" )
			)
			( gate "U2D1"
				( objectStatus "@baseboard_fab2_lib.baseboard_fab2(sch_1):page58_i172" )
			)
			( gate "U2D1"
				( objectStatus "@baseboard_fab2_lib.baseboard_fab2(sch_1):page59_i172" )
			)
			( gate "U2D1"
				( objectStatus "@baseboard_fab2_lib.baseboard_fab2(sch_1):page60_i172" )
			)
			( gate "U2D1"
				( objectStatus "@baseboard_fab2_lib.baseboard_fab2(sch_1):page61_i172" )
			)
			( gate "U2D1"
				( objectStatus "@baseboard_fab2_lib.baseboard_fab2(sch_1):page62_i172" )
			)
			( gate "U2D1"
				( objectStatus "@baseboard_fab2_lib.baseboard_fab2(sch_1):page63_i23" )
			)
			( gate "U2D1"
				( objectStatus "@baseboard_fab2_lib.baseboard_fab2(sch_1):page64_i68" )
			)
			( gate "U2D1"
				( objectStatus "@baseboard_fab2_lib.baseboard_fab2(sch_1):page65_i68" )
			)
			( gate "U2D1"
				( objectStatus "@baseboard_fab2_lib.baseboard_fab2(sch_1):page66_i84" )
			)
			( gate "U2D1"
				( objectStatus "@baseboard_fab2_lib.baseboard_fab2(sch_1):page67_i132" )
			)
			( gate "U2D1"
				( objectStatus "@baseboard_fab2_lib.baseboard_fab2(sch_1):page68_i125" )
			)
			( gate "U2D1"
				( objectStatus "@baseboard_fab2_lib.baseboard_fab2(sch_1):page69_i1" )
			)
			( gate "U2D1"
				( objectStatus "@baseboard_fab2_lib.baseboard_fab2(sch_1):page70_i9" )
			)
			( gate "U2D1"
				( objectStatus "@baseboard_fab2_lib.baseboard_fab2(sch_1):page70_i10" )
			)
			( gate "R3D27"
				( objectStatus "@baseboard_fab2_lib.baseboard_fab2(sch_1):page71_i43" )
			)
			( gate "RT8P1"
				( objectStatus "@baseboard_fab2_lib.baseboard_fab2(sch_1):page71_i49" )
			)
			( gate "U2D1"
				( objectStatus "@baseboard_fab2_lib.baseboard_fab2(sch_1):page71_i50" )
			)
			( gate "U2D1"
				( objectStatus "@baseboard_fab2_lib.baseboard_fab2(sch_1):page71_i51" )
			)
			( gate "R3D32"
				( objectStatus "@baseboard_fab2_lib.baseboard_fab2(sch_1):page71_i53" )
			)
			( gate "C3D3"
				( objectStatus "@baseboard_fab2_lib.baseboard_fab2(sch_1):page72_i25" )
			)
			( gate "U2D1"
				( objectStatus "@baseboard_fab2_lib.baseboard_fab2(sch_1):page72_i32" )
			)
			( gate "U2D1"
				( objectStatus "@baseboard_fab2_lib.baseboard_fab2(sch_1):page72_i33" )
			)
			( gate "U2D1"
				( objectStatus "@baseboard_fab2_lib.baseboard_fab2(sch_1):page73_i107" )
			)
			( gate "U2D1"
				( objectStatus "@baseboard_fab2_lib.baseboard_fab2(sch_1):page74_i20" )
			)
			( gate "U2D1"
				( objectStatus "@baseboard_fab2_lib.baseboard_fab2(sch_1):page74_i21" )
			)
			( gate "U2D1"
				( objectStatus "@baseboard_fab2_lib.baseboard_fab2(sch_1):page74_i22" )
			)
			( gate "U2D1"
				( objectStatus "@baseboard_fab2_lib.baseboard_fab2(sch_1):page74_i23" )
			)
			( gate "U2D1"
				( objectStatus "@baseboard_fab2_lib.baseboard_fab2(sch_1):page75_i17" )
			)
			( gate "U2D1"
				( objectStatus "@baseboard_fab2_lib.baseboard_fab2(sch_1):page75_i18" )
			)
			( gate "U2D1"
				( objectStatus "@baseboard_fab2_lib.baseboard_fab2(sch_1):page75_i19" )
			)
			( gate "U2D1"
				( objectStatus "@baseboard_fab2_lib.baseboard_fab2(sch_1):page75_i20" )
			)
			( gate "C3D21"
				( objectStatus "@baseboard_fab2_lib.baseboard_fab2(sch_1):page76_i1" )
			)
			( gate "C3D5"
				( objectStatus "@baseboard_fab2_lib.baseboard_fab2(sch_1):page76_i3" )
			)
			( gate "C3D12"
				( objectStatus "@baseboard_fab2_lib.baseboard_fab2(sch_1):page76_i4" )
			)
			( gate "C3D4"
				( objectStatus "@baseboard_fab2_lib.baseboard_fab2(sch_1):page76_i5" )
			)
			( gate "C3D11"
				( objectStatus "@baseboard_fab2_lib.baseboard_fab2(sch_1):page76_i7" )
			)
			( gate "C3D13"
				( objectStatus "@baseboard_fab2_lib.baseboard_fab2(sch_1):page76_i8" )
			)
			( gate "C2D40"
				( objectStatus "@baseboard_fab2_lib.baseboard_fab2(sch_1):page76_i10" )
			)
			( gate "C3D9"
				( objectStatus "@baseboard_fab2_lib.baseboard_fab2(sch_1):page76_i15" )
			)
			( gate "C3D8"
				( objectStatus "@baseboard_fab2_lib.baseboard_fab2(sch_1):page76_i18" )
			)
			( gate "C7P6"
				( objectStatus "@baseboard_fab2_lib.baseboard_fab2(sch_1):page76_i23" )
			)
			( gate "C7P13"
				( objectStatus "@baseboard_fab2_lib.baseboard_fab2(sch_1):page76_i25" )
			)
			( gate "C7P10"
				( objectStatus "@baseboard_fab2_lib.baseboard_fab2(sch_1):page76_i26" )
			)
			( gate "C7P7"
				( objectStatus "@baseboard_fab2_lib.baseboard_fab2(sch_1):page76_i27" )
			)
			( gate "C8P22"
				( objectStatus "@baseboard_fab2_lib.baseboard_fab2(sch_1):page76_i28" )
			)
			( gate "C7P17"
				( objectStatus "@baseboard_fab2_lib.baseboard_fab2(sch_1):page76_i29" )
			)
			( gate "C2D8"
				( objectStatus "@baseboard_fab2_lib.baseboard_fab2(sch_1):page76_i33" )
			)
			( gate "C2D10"
				( objectStatus "@baseboard_fab2_lib.baseboard_fab2(sch_1):page76_i37" )
			)
			( gate "C2D11"
				( objectStatus "@baseboard_fab2_lib.baseboard_fab2(sch_1):page76_i42" )
			)
			( gate "C2D9"
				( objectStatus "@baseboard_fab2_lib.baseboard_fab2(sch_1):page76_i43" )
			)
			( gate "C7P15"
				( objectStatus "@baseboard_fab2_lib.baseboard_fab2(sch_1):page76_i45" )
			)
			( gate "C8P23"
				( objectStatus "@baseboard_fab2_lib.baseboard_fab2(sch_1):page76_i48" )
			)
			( gate "C7P14"
				( objectStatus "@baseboard_fab2_lib.baseboard_fab2(sch_1):page76_i49" )
			)
			( gate "C8P7"
				( objectStatus "@baseboard_fab2_lib.baseboard_fab2(sch_1):page76_i50" )
			)
			( gate "C7P18"
				( objectStatus "@baseboard_fab2_lib.baseboard_fab2(sch_1):page76_i51" )
			)
			( gate "C7P3"
				( objectStatus "@baseboard_fab2_lib.baseboard_fab2(sch_1):page76_i52" )
			)
			( gate "C8P6"
				( objectStatus "@baseboard_fab2_lib.baseboard_fab2(sch_1):page76_i55" )
			)
			( gate "C8P5"
				( objectStatus "@baseboard_fab2_lib.baseboard_fab2(sch_1):page76_i58" )
			)
			( gate "C2D12"
				( objectStatus "@baseboard_fab2_lib.baseboard_fab2(sch_1):page76_i59" )
			)
			( gate "C2D22"
				( objectStatus "@baseboard_fab2_lib.baseboard_fab2(sch_1):page76_i61" )
			)
			( gate "C2D31"
				( objectStatus "@baseboard_fab2_lib.baseboard_fab2(sch_1):page76_i63" )
			)
			( gate "C2D21"
				( objectStatus "@baseboard_fab2_lib.baseboard_fab2(sch_1):page76_i65" )
			)
			( gate "C2D27"
				( objectStatus "@baseboard_fab2_lib.baseboard_fab2(sch_1):page76_i66" )
			)
			( gate "C3D2"
				( objectStatus "@baseboard_fab2_lib.baseboard_fab2(sch_1):page76_i69" )
			)
			( gate "C2D36"
				( objectStatus "@baseboard_fab2_lib.baseboard_fab2(sch_1):page76_i70" )
			)
			( gate "C2D13"
				( objectStatus "@baseboard_fab2_lib.baseboard_fab2(sch_1):page76_i73" )
			)
			( gate "C2D19"
				( objectStatus "@baseboard_fab2_lib.baseboard_fab2(sch_1):page76_i75" )
			)
			( gate "C2D14"
				( objectStatus "@baseboard_fab2_lib.baseboard_fab2(sch_1):page76_i76" )
			)
			( gate "C2D20"
				( objectStatus "@baseboard_fab2_lib.baseboard_fab2(sch_1):page76_i79" )
			)
			( gate "C2D24"
				( objectStatus "@baseboard_fab2_lib.baseboard_fab2(sch_1):page76_i80" )
			)
			( gate "C2D25"
				( objectStatus "@baseboard_fab2_lib.baseboard_fab2(sch_1):page76_i82" )
			)
			( gate "C2D30"
				( objectStatus "@baseboard_fab2_lib.baseboard_fab2(sch_1):page76_i83" )
			)
			( gate "C2D33"
				( objectStatus "@baseboard_fab2_lib.baseboard_fab2(sch_1):page76_i85" )
			)
			( gate "C8P4"
				( objectStatus "@baseboard_fab2_lib.baseboard_fab2(sch_1):page76_i88" )
			)
			( gate "C8P20"
				( objectStatus "@baseboard_fab2_lib.baseboard_fab2(sch_1):page76_i89" )
			)
			( gate "C2D32"
				( objectStatus "@baseboard_fab2_lib.baseboard_fab2(sch_1):page76_i90" )
			)
			( gate "C8P18"
				( objectStatus "@baseboard_fab2_lib.baseboard_fab2(sch_1):page76_i92" )
			)
			( gate "C7P2"
				( objectStatus "@baseboard_fab2_lib.baseboard_fab2(sch_1):page76_i100" )
			)
			( gate "C8P3"
				( objectStatus "@baseboard_fab2_lib.baseboard_fab2(sch_1):page76_i101" )
			)
			( gate "C8P19"
				( objectStatus "@baseboard_fab2_lib.baseboard_fab2(sch_1):page76_i103" )
			)
			( gate "C7P1"
				( objectStatus "@baseboard_fab2_lib.baseboard_fab2(sch_1):page76_i105" )
			)
			( gate "C8P34"
				( objectStatus "@baseboard_fab2_lib.baseboard_fab2(sch_1):page76_i106" )
			)
			( gate "C8P12"
				( objectStatus "@baseboard_fab2_lib.baseboard_fab2(sch_1):page76_i107" )
			)
			( gate "C2D26"
				( objectStatus "@baseboard_fab2_lib.baseboard_fab2(sch_1):page76_i108" )
			)
			( gate "C3D1"
				( objectStatus "@baseboard_fab2_lib.baseboard_fab2(sch_1):page76_i111" )
			)
			( gate "C2D23"
				( objectStatus "@baseboard_fab2_lib.baseboard_fab2(sch_1):page76_i112" )
			)
			( gate "C2D17"
				( objectStatus "@baseboard_fab2_lib.baseboard_fab2(sch_1):page76_i114" )
			)
			( gate "C2D1"
				( objectStatus "@baseboard_fab2_lib.baseboard_fab2(sch_1):page76_i116" )
			)
			( gate "C8P26"
				( objectStatus "@baseboard_fab2_lib.baseboard_fab2(sch_1):page76_i118" )
			)
			( gate "C2D37"
				( objectStatus "@baseboard_fab2_lib.baseboard_fab2(sch_1):page76_i119" )
			)
			( gate "C2D34"
				( objectStatus "@baseboard_fab2_lib.baseboard_fab2(sch_1):page76_i122" )
			)
			( gate "C2D45"
				( objectStatus "@baseboard_fab2_lib.baseboard_fab2(sch_1):page76_i123" )
			)
			( gate "C2D16"
				( objectStatus "@baseboard_fab2_lib.baseboard_fab2(sch_1):page76_i124" )
			)
			( gate "C8P29"
				( objectStatus "@baseboard_fab2_lib.baseboard_fab2(sch_1):page76_i125" )
			)
			( gate "C8P10"
				( objectStatus "@baseboard_fab2_lib.baseboard_fab2(sch_1):page76_i127" )
			)
			( gate "C8P16"
				( objectStatus "@baseboard_fab2_lib.baseboard_fab2(sch_1):page76_i129" )
			)
			( gate "C8P33"
				( objectStatus "@baseboard_fab2_lib.baseboard_fab2(sch_1):page76_i131" )
			)
			( gate "C8P13"
				( objectStatus "@baseboard_fab2_lib.baseboard_fab2(sch_1):page76_i132" )
			)
			( gate "C8P17"
				( objectStatus "@baseboard_fab2_lib.baseboard_fab2(sch_1):page76_i133" )
			)
			( gate "C8P21"
				( objectStatus "@baseboard_fab2_lib.baseboard_fab2(sch_1):page76_i135" )
			)
			( gate "C8P25"
				( objectStatus "@baseboard_fab2_lib.baseboard_fab2(sch_1):page76_i136" )
			)
			( gate "C8P28"
				( objectStatus "@baseboard_fab2_lib.baseboard_fab2(sch_1):page76_i137" )
			)
			( gate "C8P11"
				( objectStatus "@baseboard_fab2_lib.baseboard_fab2(sch_1):page76_i139" )
			)
			( gate "C8P27"
				( objectStatus "@baseboard_fab2_lib.baseboard_fab2(sch_1):page76_i141" )
			)
			( gate "C2D15"
				( objectStatus "@baseboard_fab2_lib.baseboard_fab2(sch_1):page76_i159" )
			)
			( gate "C2D38"
				( objectStatus "@baseboard_fab2_lib.baseboard_fab2(sch_1):page76_i160" )
			)
			( gate "C2D35"
				( objectStatus "@baseboard_fab2_lib.baseboard_fab2(sch_1):page76_i161" )
			)
			( gate "C3D7"
				( objectStatus "@baseboard_fab2_lib.baseboard_fab2(sch_1):page76_i164" )
			)
			( gate "C2D39"
				( objectStatus "@baseboard_fab2_lib.baseboard_fab2(sch_1):page76_i165" )
			)
			( gate "C3D17"
				( objectStatus "@baseboard_fab2_lib.baseboard_fab2(sch_1):page76_i166" )
			)
			( gate "C3D18"
				( objectStatus "@baseboard_fab2_lib.baseboard_fab2(sch_1):page76_i169" )
			)
			( gate "C3D6"
				( objectStatus "@baseboard_fab2_lib.baseboard_fab2(sch_1):page76_i170" )
			)
			( gate "C3D14"
				( objectStatus "@baseboard_fab2_lib.baseboard_fab2(sch_1):page76_i171" )
			)
			( gate "C3D23"
				( objectStatus "@baseboard_fab2_lib.baseboard_fab2(sch_1):page76_i172" )
			)
			( gate "C3D15"
				( objectStatus "@baseboard_fab2_lib.baseboard_fab2(sch_1):page76_i174" )
			)
			( gate "C3D24"
				( objectStatus "@baseboard_fab2_lib.baseboard_fab2(sch_1):page76_i175" )
			)
			( gate "C3D16"
				( objectStatus "@baseboard_fab2_lib.baseboard_fab2(sch_1):page76_i176" )
			)
			( gate "C7P12"
				( objectStatus "@baseboard_fab2_lib.baseboard_fab2(sch_1):page76_i179" )
			)
			( gate "C7P9"
				( objectStatus "@baseboard_fab2_lib.baseboard_fab2(sch_1):page76_i181" )
			)
			( gate "C7P5"
				( objectStatus "@baseboard_fab2_lib.baseboard_fab2(sch_1):page76_i182" )
			)
			( gate "C7P11"
				( objectStatus "@baseboard_fab2_lib.baseboard_fab2(sch_1):page76_i183" )
			)
			( gate "C7P8"
				( objectStatus "@baseboard_fab2_lib.baseboard_fab2(sch_1):page76_i184" )
			)
			( gate "C7P4"
				( objectStatus "@baseboard_fab2_lib.baseboard_fab2(sch_1):page76_i195" )
			)
			( gate "C3D10"
				( objectStatus "@baseboard_fab2_lib.baseboard_fab2(sch_1):page76_i196" )
			)
			( gate "C2D18"
				( objectStatus "@baseboard_fab2_lib.baseboard_fab2(sch_1):page76_i197" )
			)
			( gate "C2D28"
				( objectStatus "@baseboard_fab2_lib.baseboard_fab2(sch_1):page76_i198" )
			)
			( gate "C2D29"
				( objectStatus "@baseboard_fab2_lib.baseboard_fab2(sch_1):page76_i199" )
			)
			( gate "C2D2"
				( objectStatus "@baseboard_fab2_lib.baseboard_fab2(sch_1):page76_i201" )
			)
			( gate "C2D3"
				( objectStatus "@baseboard_fab2_lib.baseboard_fab2(sch_1):page76_i202" )
			)
			( gate "C2D47"
				( objectStatus "@baseboard_fab2_lib.baseboard_fab2(sch_1):page76_i203" )
			)
			( gate "C2D46"
				( objectStatus "@baseboard_fab2_lib.baseboard_fab2(sch_1):page76_i204" )
			)
			( gate "C3D25"
				( objectStatus "@baseboard_fab2_lib.baseboard_fab2(sch_1):page76_i205" )
			)
			( gate "C7P16"
				( objectStatus "@baseboard_fab2_lib.baseboard_fab2(sch_1):page76_i206" )
			)
			( gate "C3D20"
				( objectStatus "@baseboard_fab2_lib.baseboard_fab2(sch_1):page76_i207" )
			)
			( gate "C3D19"
				( objectStatus "@baseboard_fab2_lib.baseboard_fab2(sch_1):page76_i208" )
			)
			( gate "C8P14"
				( objectStatus "@baseboard_fab2_lib.baseboard_fab2(sch_1):page76_i211" )
			)
			( gate "C8P15"
				( objectStatus "@baseboard_fab2_lib.baseboard_fab2(sch_1):page76_i212" )
			)
			( gate "C8P8"
				( objectStatus "@baseboard_fab2_lib.baseboard_fab2(sch_1):page76_i213" )
			)
			( gate "C8P9"
				( objectStatus "@baseboard_fab2_lib.baseboard_fab2(sch_1):page76_i214" )
			)
			( gate "C7P19"
				( objectStatus "@baseboard_fab2_lib.baseboard_fab2(sch_1):page76_i215" )
			)
			( gate "C8P32"
				( objectStatus "@baseboard_fab2_lib.baseboard_fab2(sch_1):page76_i216" )
			)
			( gate "C8P24"
				( objectStatus "@baseboard_fab2_lib.baseboard_fab2(sch_1):page76_i217" )
			)
			( gate "C7P20"
				( objectStatus "@baseboard_fab2_lib.baseboard_fab2(sch_1):page76_i218" )
			)
			( gate "J1G1"
				( objectStatus "@baseboard_fab2_lib.baseboard_fab2(sch_1):page77_i43" )
			)
			( gate "J1G1"
				( objectStatus "@baseboard_fab2_lib.baseboard_fab2(sch_1):page77_i66" )
			)
			( gate "J1G1"
				( objectStatus "@baseboard_fab2_lib.baseboard_fab2(sch_1):page77_i111" )
			)
			( gate "J1G1"
				( objectStatus "@baseboard_fab2_lib.baseboard_fab2(sch_1):page77_i171" )
			)
			( gate "C1F22"
				( objectStatus "@baseboard_fab2_lib.baseboard_fab2(sch_1):page77_i181" )
			)
			( gate "C9T7"
				( objectStatus "@baseboard_fab2_lib.baseboard_fab2(sch_1):page78_i2" )
			)
			( gate "J9T1"
				( objectStatus "@baseboard_fab2_lib.baseboard_fab2(sch_1):page78_i13" )
			)
			( gate "J9T1"
				( objectStatus "@baseboard_fab2_lib.baseboard_fab2(sch_1):page78_i75" )
			)
			( gate "J9T1"
				( objectStatus "@baseboard_fab2_lib.baseboard_fab2(sch_1):page78_i120" )
			)
			( gate "J9T1"
				( objectStatus "@baseboard_fab2_lib.baseboard_fab2(sch_1):page78_i144" )
			)
			( gate "J1G2"
				( objectStatus "@baseboard_fab2_lib.baseboard_fab2(sch_1):page79_i43" )
			)
			( gate "J1G2"
				( objectStatus "@baseboard_fab2_lib.baseboard_fab2(sch_1):page79_i64" )
			)
			( gate "J1G2"
				( objectStatus "@baseboard_fab2_lib.baseboard_fab2(sch_1):page79_i111" )
			)
			( gate "J1G2"
				( objectStatus "@baseboard_fab2_lib.baseboard_fab2(sch_1):page79_i169" )
			)
			( gate "C9U7"
				( objectStatus "@baseboard_fab2_lib.baseboard_fab2(sch_1):page79_i178" )
			)
			( gate "C1G10"
				( objectStatus "@baseboard_fab2_lib.baseboard_fab2(sch_1):page80_i3" )
			)
			( gate "J9U1"
				( objectStatus "@baseboard_fab2_lib.baseboard_fab2(sch_1):page80_i24" )
			)
			( gate "J9U1"
				( objectStatus "@baseboard_fab2_lib.baseboard_fab2(sch_1):page80_i56" )
			)
			( gate "J9U1"
				( objectStatus "@baseboard_fab2_lib.baseboard_fab2(sch_1):page80_i101" )
			)
			( gate "J9U1"
				( objectStatus "@baseboard_fab2_lib.baseboard_fab2(sch_1):page80_i138" )
			)
			( gate "J1G3"
				( objectStatus "@baseboard_fab2_lib.baseboard_fab2(sch_1):page81_i67" )
			)
			( gate "J1G3"
				( objectStatus "@baseboard_fab2_lib.baseboard_fab2(sch_1):page81_i169" )
			)
			( gate "C9U10"
				( objectStatus "@baseboard_fab2_lib.baseboard_fab2(sch_1):page81_i178" )
			)
			( gate "J1G3"
				( objectStatus "@baseboard_fab2_lib.baseboard_fab2(sch_1):page81_i185" )
			)
			( gate "J1G3"
				( objectStatus "@baseboard_fab2_lib.baseboard_fab2(sch_1):page81_i186" )
			)
			( gate "J9U2"
				( objectStatus "@baseboard_fab2_lib.baseboard_fab2(sch_1):page82_i64" )
			)
			( gate "J9U2"
				( objectStatus "@baseboard_fab2_lib.baseboard_fab2(sch_1):page82_i171" )
			)
			( gate "C1G19"
				( objectStatus "@baseboard_fab2_lib.baseboard_fab2(sch_1):page82_i180" )
			)
			( gate "J9U2"
				( objectStatus "@baseboard_fab2_lib.baseboard_fab2(sch_1):page82_i187" )
			)
			( gate "J9U2"
				( objectStatus "@baseboard_fab2_lib.baseboard_fab2(sch_1):page82_i188" )
			)
			( gate "J1B1"
				( objectStatus "@baseboard_fab2_lib.baseboard_fab2(sch_1):page83_i43" )
			)
			( gate "J1B1"
				( objectStatus "@baseboard_fab2_lib.baseboard_fab2(sch_1):page83_i66" )
			)
			( gate "J1B1"
				( objectStatus "@baseboard_fab2_lib.baseboard_fab2(sch_1):page83_i111" )
			)
			( gate "J1B1"
				( objectStatus "@baseboard_fab2_lib.baseboard_fab2(sch_1):page83_i167" )
			)
			( gate "C1B9"
				( objectStatus "@baseboard_fab2_lib.baseboard_fab2(sch_1):page83_i176" )
			)
			( gate "C9M1"
				( objectStatus "@baseboard_fab2_lib.baseboard_fab2(sch_1):page84_i4" )
			)
			( gate "J9M1"
				( objectStatus "@baseboard_fab2_lib.baseboard_fab2(sch_1):page84_i14" )
			)
			( gate "J9M1"
				( objectStatus "@baseboard_fab2_lib.baseboard_fab2(sch_1):page84_i57" )
			)
			( gate "J9M1"
				( objectStatus "@baseboard_fab2_lib.baseboard_fab2(sch_1):page84_i102" )
			)
			( gate "J9M1"
				( objectStatus "@baseboard_fab2_lib.baseboard_fab2(sch_1):page84_i138" )
			)
			( gate "J1A2"
				( objectStatus "@baseboard_fab2_lib.baseboard_fab2(sch_1):page85_i43" )
			)
			( gate "J1A2"
				( objectStatus "@baseboard_fab2_lib.baseboard_fab2(sch_1):page85_i66" )
			)
			( gate "J1A2"
				( objectStatus "@baseboard_fab2_lib.baseboard_fab2(sch_1):page85_i111" )
			)
			( gate "J1A2"
				( objectStatus "@baseboard_fab2_lib.baseboard_fab2(sch_1):page85_i172" )
			)
			( gate "C9L7"
				( objectStatus "@baseboard_fab2_lib.baseboard_fab2(sch_1):page85_i181" )
			)
			( gate "J9L2"
				( objectStatus "@baseboard_fab2_lib.baseboard_fab2(sch_1):page86_i12" )
			)
			( gate "J9L2"
				( objectStatus "@baseboard_fab2_lib.baseboard_fab2(sch_1):page86_i55" )
			)
			( gate "J9L2"
				( objectStatus "@baseboard_fab2_lib.baseboard_fab2(sch_1):page86_i100" )
			)
			( gate "J9L2"
				( objectStatus "@baseboard_fab2_lib.baseboard_fab2(sch_1):page86_i138" )
			)
			( gate "C1A17"
				( objectStatus "@baseboard_fab2_lib.baseboard_fab2(sch_1):page86_i182" )
			)
			( gate "J1A1"
				( objectStatus "@baseboard_fab2_lib.baseboard_fab2(sch_1):page87_i169" )
			)
			( gate "C1A5"
				( objectStatus "@baseboard_fab2_lib.baseboard_fab2(sch_1):page87_i178" )
			)
			( gate "J1A1"
				( objectStatus "@baseboard_fab2_lib.baseboard_fab2(sch_1):page87_i185" )
			)
			( gate "J1A1"
				( objectStatus "@baseboard_fab2_lib.baseboard_fab2(sch_1):page87_i186" )
			)
			( gate "J1A1"
				( objectStatus "@baseboard_fab2_lib.baseboard_fab2(sch_1):page87_i187" )
			)
			( gate "J9L1"
				( objectStatus "@baseboard_fab2_lib.baseboard_fab2(sch_1):page88_i25" )
			)
			( gate "J9L1"
				( objectStatus "@baseboard_fab2_lib.baseboard_fab2(sch_1):page88_i87" )
			)
			( gate "J9L1"
				( objectStatus "@baseboard_fab2_lib.baseboard_fab2(sch_1):page88_i111" )
			)
			( gate "J9L1"
				( objectStatus "@baseboard_fab2_lib.baseboard_fab2(sch_1):page88_i168" )
			)
			( gate "C9L1"
				( objectStatus "@baseboard_fab2_lib.baseboard_fab2(sch_1):page88_i177" )
			)
			( gate "R4T2"
				( objectStatus "@baseboard_fab2_lib.baseboard_fab2(sch_1):page89_i1" )
			)
			( gate "R4T1"
				( objectStatus "@baseboard_fab2_lib.baseboard_fab2(sch_1):page89_i2" )
			)
			( gate "R6F4"
				( objectStatus "@baseboard_fab2_lib.baseboard_fab2(sch_1):page89_i3" )
			)
			( gate "R6F1"
				( objectStatus "@baseboard_fab2_lib.baseboard_fab2(sch_1):page89_i4" )
			)
			( gate "R6F5"
				( objectStatus "@baseboard_fab2_lib.baseboard_fab2(sch_1):page89_i5" )
			)
			( gate "R6F2"
				( objectStatus "@baseboard_fab2_lib.baseboard_fab2(sch_1):page89_i6" )
			)
			( gate "R6F3"
				( objectStatus "@baseboard_fab2_lib.baseboard_fab2(sch_1):page89_i7" )
			)
			( gate "Q6F1"
				( objectStatus "@baseboard_fab2_lib.baseboard_fab2(sch_1):page89_i18" )
			)
			( gate "R2P12"
				( objectStatus "@baseboard_fab2_lib.baseboard_fab2(sch_1):page89_i23" )
			)
			( gate "R8D29"
				( objectStatus "@baseboard_fab2_lib.baseboard_fab2(sch_1):page89_i26" )
			)
			( gate "R8D31"
				( objectStatus "@baseboard_fab2_lib.baseboard_fab2(sch_1):page89_i27" )
			)
			( gate "R8D30"
				( objectStatus "@baseboard_fab2_lib.baseboard_fab2(sch_1):page89_i34" )
			)
			( gate "Q8D1"
				( objectStatus "@baseboard_fab2_lib.baseboard_fab2(sch_1):page89_i35" )
			)
			( gate "Q8D1"
				( objectStatus "@baseboard_fab2_lib.baseboard_fab2(sch_1):page89_i36" )
			)
			( gate "R6D6"
				( objectStatus "@baseboard_fab2_lib.baseboard_fab2(sch_1):page90_i3" )
			)
			( gate "R4P1"
				( objectStatus "@baseboard_fab2_lib.baseboard_fab2(sch_1):page90_i4" )
			)
			( gate "R3D12"
				( objectStatus "@baseboard_fab2_lib.baseboard_fab2(sch_1):page90_i11" )
			)
			( gate "R3D13"
				( objectStatus "@baseboard_fab2_lib.baseboard_fab2(sch_1):page90_i12" )
			)
			( gate "R3D22"
				( objectStatus "@baseboard_fab2_lib.baseboard_fab2(sch_1):page90_i17" )
			)
			( gate "R3D16"
				( objectStatus "@baseboard_fab2_lib.baseboard_fab2(sch_1):page90_i24" )
			)
			( gate "R3D23"
				( objectStatus "@baseboard_fab2_lib.baseboard_fab2(sch_1):page90_i25" )
			)
			( gate "R3D26"
				( objectStatus "@baseboard_fab2_lib.baseboard_fab2(sch_1):page90_i28" )
			)
			( gate "R5D3"
				( objectStatus "@baseboard_fab2_lib.baseboard_fab2(sch_1):page90_i29" )
			)
			( gate "R6D7"
				( objectStatus "@baseboard_fab2_lib.baseboard_fab2(sch_1):page90_i31" )
			)
			( gate "R5D4"
				( objectStatus "@baseboard_fab2_lib.baseboard_fab2(sch_1):page90_i32" )
			)
			( gate "R6D13"
				( objectStatus "@baseboard_fab2_lib.baseboard_fab2(sch_1):page90_i33" )
			)
			( gate "R6D15"
				( objectStatus "@baseboard_fab2_lib.baseboard_fab2(sch_1):page90_i48" )
			)
			( gate "R6D10"
				( objectStatus "@baseboard_fab2_lib.baseboard_fab2(sch_1):page90_i49" )
			)
			( gate "R6D14"
				( objectStatus "@baseboard_fab2_lib.baseboard_fab2(sch_1):page90_i52" )
			)
			( gate "R4P14"
				( objectStatus "@baseboard_fab2_lib.baseboard_fab2(sch_1):page90_i53" )
			)
			( gate "R3D24"
				( objectStatus "@baseboard_fab2_lib.baseboard_fab2(sch_1):page90_i59" )
			)
			( gate "R3D17"
				( objectStatus "@baseboard_fab2_lib.baseboard_fab2(sch_1):page90_i60" )
			)
			( gate "R3D25"
				( objectStatus "@baseboard_fab2_lib.baseboard_fab2(sch_1):page90_i66" )
			)
			( gate "R4P6"
				( objectStatus "@baseboard_fab2_lib.baseboard_fab2(sch_1):page90_i68" )
			)
			( gate "R7P14"
				( objectStatus "@baseboard_fab2_lib.baseboard_fab2(sch_1):page90_i70" )
			)
			( gate "R4P7"
				( objectStatus "@baseboard_fab2_lib.baseboard_fab2(sch_1):page90_i72" )
			)
			( gate "R7P15"
				( objectStatus "@baseboard_fab2_lib.baseboard_fab2(sch_1):page90_i74" )
			)
			( gate "R7P22"
				( objectStatus "@baseboard_fab2_lib.baseboard_fab2(sch_1):page90_i76" )
			)
			( gate "R5P2"
				( objectStatus "@baseboard_fab2_lib.baseboard_fab2(sch_1):page90_i79" )
			)
			( gate "R5P3"
				( objectStatus "@baseboard_fab2_lib.baseboard_fab2(sch_1):page90_i80" )
			)
			( gate "R6D5"
				( objectStatus "@baseboard_fab2_lib.baseboard_fab2(sch_1):page90_i81" )
			)
			( gate "R8P1"
				( objectStatus "@baseboard_fab2_lib.baseboard_fab2(sch_1):page90_i85" )
			)
			( gate "R8P2"
				( objectStatus "@baseboard_fab2_lib.baseboard_fab2(sch_1):page90_i86" )
			)
			( gate "R3D9"
				( objectStatus "@baseboard_fab2_lib.baseboard_fab2(sch_1):page90_i88" )
			)
			( gate "J8B1"
				( objectStatus "@baseboard_fab2_lib.baseboard_fab2(sch_1):page91_i1" )
			)
			( gate "R8B8"
				( objectStatus "@baseboard_fab2_lib.baseboard_fab2(sch_1):page91_i14" )
			)
			( gate "R8B10"
				( objectStatus "@baseboard_fab2_lib.baseboard_fab2(sch_1):page91_i16" )
			)
			( gate "R8B16"
				( objectStatus "@baseboard_fab2_lib.baseboard_fab2(sch_1):page91_i17" )
			)
			( gate "R8B17"
				( objectStatus "@baseboard_fab2_lib.baseboard_fab2(sch_1):page91_i18" )
			)
			( gate "R8B18"
				( objectStatus "@baseboard_fab2_lib.baseboard_fab2(sch_1):page91_i20" )
			)
			( gate "R8B19"
				( objectStatus "@baseboard_fab2_lib.baseboard_fab2(sch_1):page91_i21" )
			)
			( gate "R8B5"
				( objectStatus "@baseboard_fab2_lib.baseboard_fab2(sch_1):page91_i22" )
			)
			( gate "R8B3"
				( objectStatus "@baseboard_fab2_lib.baseboard_fab2(sch_1):page91_i24" )
			)
			( gate "R8B13"
				( objectStatus "@baseboard_fab2_lib.baseboard_fab2(sch_1):page91_i34" )
			)
			( gate "R8B11"
				( objectStatus "@baseboard_fab2_lib.baseboard_fab2(sch_1):page91_i35" )
			)
			( gate "R8B7"
				( objectStatus "@baseboard_fab2_lib.baseboard_fab2(sch_1):page91_i36" )
			)
			( gate "R8B6"
				( objectStatus "@baseboard_fab2_lib.baseboard_fab2(sch_1):page91_i37" )
			)
			( gate "U3P2"
				( objectStatus "@baseboard_fab2_lib.baseboard_fab2(sch_1):page92_i1" )
			)
			( gate "R3P41"
				( objectStatus "@baseboard_fab2_lib.baseboard_fab2(sch_1):page92_i9" )
			)
			( gate "R3P46"
				( objectStatus "@baseboard_fab2_lib.baseboard_fab2(sch_1):page92_i12" )
			)
			( gate "R3P43"
				( objectStatus "@baseboard_fab2_lib.baseboard_fab2(sch_1):page92_i13" )
			)
			( gate "R3P42"
				( objectStatus "@baseboard_fab2_lib.baseboard_fab2(sch_1):page92_i14" )
			)
			( gate "R7E2"
				( objectStatus "@baseboard_fab2_lib.baseboard_fab2(sch_1):page92_i19" )
			)
			( gate "R7D34"
				( objectStatus "@baseboard_fab2_lib.baseboard_fab2(sch_1):page92_i24" )
			)
			( gate "R7D31"
				( objectStatus "@baseboard_fab2_lib.baseboard_fab2(sch_1):page92_i29" )
			)
			( gate "R7D29"
				( objectStatus "@baseboard_fab2_lib.baseboard_fab2(sch_1):page92_i30" )
			)
			( gate "U7D2"
				( objectStatus "@baseboard_fab2_lib.baseboard_fab2(sch_1):page92_i32" )
			)
			( gate "C3P49"
				( objectStatus "@baseboard_fab2_lib.baseboard_fab2(sch_1):page92_i37" )
			)
			( gate "R3P49"
				( objectStatus "@baseboard_fab2_lib.baseboard_fab2(sch_1):page92_i38" )
			)
			( gate "R3P45"
				( objectStatus "@baseboard_fab2_lib.baseboard_fab2(sch_1):page92_i39" )
			)
			( gate "R3R1"
				( objectStatus "@baseboard_fab2_lib.baseboard_fab2(sch_1):page92_i46" )
			)
			( gate "R7D32"
				( objectStatus "@baseboard_fab2_lib.baseboard_fab2(sch_1):page92_i48" )
			)
			( gate "R7D33"
				( objectStatus "@baseboard_fab2_lib.baseboard_fab2(sch_1):page92_i51" )
			)
			( gate "C7D5"
				( objectStatus "@baseboard_fab2_lib.baseboard_fab2(sch_1):page92_i52" )
			)
			( gate "R7D26"
				( objectStatus "@baseboard_fab2_lib.baseboard_fab2(sch_1):page92_i54" )
			)
			( gate "R3R3"
				( objectStatus "@baseboard_fab2_lib.baseboard_fab2(sch_1):page92_i61" )
			)
			( gate "R6D9"
				( objectStatus "@baseboard_fab2_lib.baseboard_fab2(sch_1):page92_i64" )
			)
			( gate "R7P27"
				( objectStatus "@baseboard_fab2_lib.baseboard_fab2(sch_1):page92_i65" )
			)
			( gate "R7D28"
				( objectStatus "@baseboard_fab2_lib.baseboard_fab2(sch_1):page92_i67" )
			)
			( gate "R7D27"
				( objectStatus "@baseboard_fab2_lib.baseboard_fab2(sch_1):page92_i68" )
			)
			( gate "R7D25"
				( objectStatus "@baseboard_fab2_lib.baseboard_fab2(sch_1):page92_i70" )
			)
			( gate "R3R2"
				( objectStatus "@baseboard_fab2_lib.baseboard_fab2(sch_1):page92_i75" )
			)
			( gate "C7D4"
				( objectStatus "@baseboard_fab2_lib.baseboard_fab2(sch_1):page92_i79" )
			)
			( gate "C3P50"
				( objectStatus "@baseboard_fab2_lib.baseboard_fab2(sch_1):page92_i84" )
			)
			( gate "R2T44"
				( objectStatus "@baseboard_fab2_lib.baseboard_fab2(sch_1):page92_i92" )
			)
			( gate "R2T40"
				( objectStatus "@baseboard_fab2_lib.baseboard_fab2(sch_1):page92_i93" )
			)
			( gate "R2T37"
				( objectStatus "@baseboard_fab2_lib.baseboard_fab2(sch_1):page92_i94" )
			)
			( gate "R2T43"
				( objectStatus "@baseboard_fab2_lib.baseboard_fab2(sch_1):page92_i96" )
			)
			( gate "R3P59"
				( objectStatus "@baseboard_fab2_lib.baseboard_fab2(sch_1):page92_i97" )
			)
			( gate "R3P58"
				( objectStatus "@baseboard_fab2_lib.baseboard_fab2(sch_1):page92_i98" )
			)
			( gate "R7P18"
				( objectStatus "@baseboard_fab2_lib.baseboard_fab2(sch_1):page92_i100" )
			)
			( gate "R4R2"
				( objectStatus "@baseboard_fab2_lib.baseboard_fab2(sch_1):page92_i101" )
			)
			( gate "R2T27"
				( objectStatus "@baseboard_fab2_lib.baseboard_fab2(sch_1):page93_i13" )
			)
			( gate "R2T32"
				( objectStatus "@baseboard_fab2_lib.baseboard_fab2(sch_1):page93_i15" )
			)
			( gate "R2T20"
				( objectStatus "@baseboard_fab2_lib.baseboard_fab2(sch_1):page93_i16" )
			)
			( gate "R2T17"
				( objectStatus "@baseboard_fab2_lib.baseboard_fab2(sch_1):page93_i23" )
			)
			( gate "U2T4"
				( objectStatus "@baseboard_fab2_lib.baseboard_fab2(sch_1):page93_i30" )
			)
			( gate "R2T38"
				( objectStatus "@baseboard_fab2_lib.baseboard_fab2(sch_1):page93_i39" )
			)
			( gate "R2T33"
				( objectStatus "@baseboard_fab2_lib.baseboard_fab2(sch_1):page93_i40" )
			)
			( gate "R2T30"
				( objectStatus "@baseboard_fab2_lib.baseboard_fab2(sch_1):page93_i42" )
			)
			( gate "R7D24"
				( objectStatus "@baseboard_fab2_lib.baseboard_fab2(sch_1):page93_i62" )
			)
			( gate "R2T19"
				( objectStatus "@baseboard_fab2_lib.baseboard_fab2(sch_1):page93_i63" )
			)
			( gate "R2T16"
				( objectStatus "@baseboard_fab2_lib.baseboard_fab2(sch_1):page93_i67" )
			)
			( gate "R2T31"
				( objectStatus "@baseboard_fab2_lib.baseboard_fab2(sch_1):page93_i68" )
			)
			( gate "C2T33"
				( objectStatus "@baseboard_fab2_lib.baseboard_fab2(sch_1):page93_i72" )
			)
			( gate "R4R3"
				( objectStatus "@baseboard_fab2_lib.baseboard_fab2(sch_1):page93_i79" )
			)
			( gate "R2T26"
				( objectStatus "@baseboard_fab2_lib.baseboard_fab2(sch_1):page93_i87" )
			)
			( gate "R2T57"
				( objectStatus "@baseboard_fab2_lib.baseboard_fab2(sch_1):page93_i88" )
			)
			( gate "R2T61"
				( objectStatus "@baseboard_fab2_lib.baseboard_fab2(sch_1):page93_i89" )
			)
			( gate "R2T62"
				( objectStatus "@baseboard_fab2_lib.baseboard_fab2(sch_1):page93_i93" )
			)
			( gate "R2T58"
				( objectStatus "@baseboard_fab2_lib.baseboard_fab2(sch_1):page93_i94" )
			)
			( gate "C2T32"
				( objectStatus "@baseboard_fab2_lib.baseboard_fab2(sch_1):page93_i95" )
			)
			( gate "R2T36"
				( objectStatus "@baseboard_fab2_lib.baseboard_fab2(sch_1):page93_i97" )
			)
			( gate "R2T39"
				( objectStatus "@baseboard_fab2_lib.baseboard_fab2(sch_1):page93_i98" )
			)
			( gate "R2T68"
				( objectStatus "@baseboard_fab2_lib.baseboard_fab2(sch_1):page93_i102" )
			)
			( gate "R2T60"
				( objectStatus "@baseboard_fab2_lib.baseboard_fab2(sch_1):page93_i103" )
			)
			( gate "R7P28"
				( objectStatus "@baseboard_fab2_lib.baseboard_fab2(sch_1):page93_i106" )
			)
			( gate "R2T59"
				( objectStatus "@baseboard_fab2_lib.baseboard_fab2(sch_1):page93_i107" )
			)
			( gate "R2T69"
				( objectStatus "@baseboard_fab2_lib.baseboard_fab2(sch_1):page93_i108" )
			)
			( gate "R2T71"
				( objectStatus "@baseboard_fab2_lib.baseboard_fab2(sch_1):page93_i109" )
			)
			( gate "R7D43"
				( objectStatus "@baseboard_fab2_lib.baseboard_fab2(sch_1):page93_i110" )
			)
			( gate "R2T65"
				( objectStatus "@baseboard_fab2_lib.baseboard_fab2(sch_1):page93_i111" )
			)
			( gate "R2T66"
				( objectStatus "@baseboard_fab2_lib.baseboard_fab2(sch_1):page93_i112" )
			)
			( gate "R2T67"
				( objectStatus "@baseboard_fab2_lib.baseboard_fab2(sch_1):page93_i113" )
			)
			( gate "R7D41"
				( objectStatus "@baseboard_fab2_lib.baseboard_fab2(sch_1):page93_i114" )
			)
			( gate "R8F38"
				( objectStatus "@baseboard_fab2_lib.baseboard_fab2(sch_1):page93_i119" )
			)
			( gate "R2T64"
				( objectStatus "@baseboard_fab2_lib.baseboard_fab2(sch_1):page93_i121" )
			)
			( gate "R1T36"
				( objectStatus "@baseboard_fab2_lib.baseboard_fab2(sch_1):page93_i122" )
			)
			( gate "R1T37"
				( objectStatus "@baseboard_fab2_lib.baseboard_fab2(sch_1):page93_i123" )
			)
			( gate "R2T50"
				( objectStatus "@baseboard_fab2_lib.baseboard_fab2(sch_1):page93_i127" )
			)
			( gate "R8F37"
				( objectStatus "@baseboard_fab2_lib.baseboard_fab2(sch_1):page93_i131" )
			)
			( gate "R2T63"
				( objectStatus "@baseboard_fab2_lib.baseboard_fab2(sch_1):page93_i133" )
			)
			( gate "R1T35"
				( objectStatus "@baseboard_fab2_lib.baseboard_fab2(sch_1):page93_i135" )
			)
			( gate "R1T38"
				( objectStatus "@baseboard_fab2_lib.baseboard_fab2(sch_1):page93_i137" )
			)
			( gate "R2T72"
				( objectStatus "@baseboard_fab2_lib.baseboard_fab2(sch_1):page93_i143" )
			)
			( gate "R2T73"
				( objectStatus "@baseboard_fab2_lib.baseboard_fab2(sch_1):page93_i144" )
			)
			( gate "Q3U1"
				( objectStatus "@baseboard_fab2_lib.baseboard_fab2(sch_1):page94_i49" )
			)
			( gate "R7G7"
				( objectStatus "@baseboard_fab2_lib.baseboard_fab2(sch_1):page94_i51" )
			)
			( gate "Q7E1"
				( objectStatus "@baseboard_fab2_lib.baseboard_fab2(sch_1):page94_i60" )
			)
			( gate "Q7E1"
				( objectStatus "@baseboard_fab2_lib.baseboard_fab2(sch_1):page94_i64" )
			)
			( gate "R3R4"
				( objectStatus "@baseboard_fab2_lib.baseboard_fab2(sch_1):page94_i66" )
			)
			( gate "Q7E2"
				( objectStatus "@baseboard_fab2_lib.baseboard_fab2(sch_1):page94_i69" )
			)
			( gate "Q7E2"
				( objectStatus "@baseboard_fab2_lib.baseboard_fab2(sch_1):page94_i75" )
			)
			( gate "Q4B1"
				( objectStatus "@baseboard_fab2_lib.baseboard_fab2(sch_1):page94_i77" )
			)
			( gate "R3R10"
				( objectStatus "@baseboard_fab2_lib.baseboard_fab2(sch_1):page94_i79" )
			)
			( gate "R6M4"
				( objectStatus "@baseboard_fab2_lib.baseboard_fab2(sch_1):page94_i82" )
			)
			( gate "Q4B1"
				( objectStatus "@baseboard_fab2_lib.baseboard_fab2(sch_1):page94_i84" )
			)
			( gate "Q3U1"
				( objectStatus "@baseboard_fab2_lib.baseboard_fab2(sch_1):page94_i89" )
			)
			( gate "R4U1"
				( objectStatus "@baseboard_fab2_lib.baseboard_fab2(sch_1):page94_i91" )
			)
			( gate "R4U3"
				( objectStatus "@baseboard_fab2_lib.baseboard_fab2(sch_1):page94_i94" )
			)
			( gate "Q4U1"
				( objectStatus "@baseboard_fab2_lib.baseboard_fab2(sch_1):page94_i98" )
			)
			( gate "R4U2"
				( objectStatus "@baseboard_fab2_lib.baseboard_fab2(sch_1):page94_i100" )
			)
			( gate "Q4U1"
				( objectStatus "@baseboard_fab2_lib.baseboard_fab2(sch_1):page94_i102" )
			)
			( gate "R4U4"
				( objectStatus "@baseboard_fab2_lib.baseboard_fab2(sch_1):page94_i104" )
			)
			( gate "Q2U1"
				( objectStatus "@baseboard_fab2_lib.baseboard_fab2(sch_1):page95_i28" )
			)
			( gate "Q4B2"
				( objectStatus "@baseboard_fab2_lib.baseboard_fab2(sch_1):page95_i32" )
			)
			( gate "Q4B2"
				( objectStatus "@baseboard_fab2_lib.baseboard_fab2(sch_1):page95_i33" )
			)
			( gate "Q7E3"
				( objectStatus "@baseboard_fab2_lib.baseboard_fab2(sch_1):page95_i51" )
			)
			( gate "Q7E3"
				( objectStatus "@baseboard_fab2_lib.baseboard_fab2(sch_1):page95_i52" )
			)
			( gate "Q7E5"
				( objectStatus "@baseboard_fab2_lib.baseboard_fab2(sch_1):page95_i59" )
			)
			( gate "R7E10"
				( objectStatus "@baseboard_fab2_lib.baseboard_fab2(sch_1):page95_i62" )
			)
			( gate "Q7E6"
				( objectStatus "@baseboard_fab2_lib.baseboard_fab2(sch_1):page95_i69" )
			)
			( gate "R7E11"
				( objectStatus "@baseboard_fab2_lib.baseboard_fab2(sch_1):page95_i72" )
			)
			( gate "C7E3"
				( objectStatus "@baseboard_fab2_lib.baseboard_fab2(sch_1):page95_i92" )
			)
			( gate "Q7E4"
				( objectStatus "@baseboard_fab2_lib.baseboard_fab2(sch_1):page95_i104" )
			)
			( gate "R7E7"
				( objectStatus "@baseboard_fab2_lib.baseboard_fab2(sch_1):page95_i106" )
			)
			( gate "R7E9"
				( objectStatus "@baseboard_fab2_lib.baseboard_fab2(sch_1):page95_i108" )
			)
			( gate "Q7E5"
				( objectStatus "@baseboard_fab2_lib.baseboard_fab2(sch_1):page95_i111" )
			)
			( gate "Q7E6"
				( objectStatus "@baseboard_fab2_lib.baseboard_fab2(sch_1):page95_i112" )
			)
			( gate "Q2U1"
				( objectStatus "@baseboard_fab2_lib.baseboard_fab2(sch_1):page95_i113" )
			)
			( gate "C7E4"
				( objectStatus "@baseboard_fab2_lib.baseboard_fab2(sch_1):page95_i115" )
			)
			( gate "U7E2"
				( objectStatus "@baseboard_fab2_lib.baseboard_fab2(sch_1):page95_i117" )
			)
			( gate "U7E3"
				( objectStatus "@baseboard_fab2_lib.baseboard_fab2(sch_1):page95_i118" )
			)
			( gate "Q7E8"
				( objectStatus "@baseboard_fab2_lib.baseboard_fab2(sch_1):page95_i119" )
			)
			( gate "R6D12"
				( objectStatus "@baseboard_fab2_lib.baseboard_fab2(sch_1):page96_i2" )
			)
			( gate "R6D8"
				( objectStatus "@baseboard_fab2_lib.baseboard_fab2(sch_1):page96_i3" )
			)
			( gate "R3P29"
				( objectStatus "@baseboard_fab2_lib.baseboard_fab2(sch_1):page96_i5" )
			)
			( gate "R3P38"
				( objectStatus "@baseboard_fab2_lib.baseboard_fab2(sch_1):page96_i7" )
			)
			( gate "R3D20"
				( objectStatus "@baseboard_fab2_lib.baseboard_fab2(sch_1):page96_i25" )
			)
			( gate "R3D15"
				( objectStatus "@baseboard_fab2_lib.baseboard_fab2(sch_1):page96_i26" )
			)
			( gate "R7M9"
				( objectStatus "@baseboard_fab2_lib.baseboard_fab2(sch_1):page96_i28" )
			)
			( gate "R3D21"
				( objectStatus "@baseboard_fab2_lib.baseboard_fab2(sch_1):page96_i30" )
			)
			( gate "R3P36"
				( objectStatus "@baseboard_fab2_lib.baseboard_fab2(sch_1):page96_i36" )
			)
			( gate "U3P1"
				( objectStatus "@baseboard_fab2_lib.baseboard_fab2(sch_1):page96_i42" )
			)
			( gate "U4C2"
				( objectStatus "@baseboard_fab2_lib.baseboard_fab2(sch_1):page96_i46" )
			)
			( gate "R4C8"
				( objectStatus "@baseboard_fab2_lib.baseboard_fab2(sch_1):page96_i55" )
			)
			( gate "R4C9"
				( objectStatus "@baseboard_fab2_lib.baseboard_fab2(sch_1):page96_i69" )
			)
			( gate "R3P32"
				( objectStatus "@baseboard_fab2_lib.baseboard_fab2(sch_1):page96_i71" )
			)
			( gate "C3P42"
				( objectStatus "@baseboard_fab2_lib.baseboard_fab2(sch_1):page96_i73" )
			)
			( gate "C4C3"
				( objectStatus "@baseboard_fab2_lib.baseboard_fab2(sch_1):page96_i75" )
			)
			( gate "R3D18"
				( objectStatus "@baseboard_fab2_lib.baseboard_fab2(sch_1):page97_i33" )
			)
			( gate "R4R4"
				( objectStatus "@baseboard_fab2_lib.baseboard_fab2(sch_1):page97_i42" )
			)
			( gate "R7P20"
				( objectStatus "@baseboard_fab2_lib.baseboard_fab2(sch_1):page97_i44" )
			)
			( gate "R4P21"
				( objectStatus "@baseboard_fab2_lib.baseboard_fab2(sch_1):page97_i72" )
			)
			( gate "R4C10"
				( objectStatus "@baseboard_fab2_lib.baseboard_fab2(sch_1):page97_i76" )
			)
			( gate "R4P5"
				( objectStatus "@baseboard_fab2_lib.baseboard_fab2(sch_1):page97_i80" )
			)
			( gate "R7P13"
				( objectStatus "@baseboard_fab2_lib.baseboard_fab2(sch_1):page97_i81" )
			)
			( gate "R4F5"
				( objectStatus "@baseboard_fab2_lib.baseboard_fab2(sch_1):page98_i4" )
			)
			( gate "R4F3"
				( objectStatus "@baseboard_fab2_lib.baseboard_fab2(sch_1):page98_i5" )
			)
			( gate "C4F9"
				( objectStatus "@baseboard_fab2_lib.baseboard_fab2(sch_1):page98_i7" )
			)
			( gate "R6M1"
				( objectStatus "@baseboard_fab2_lib.baseboard_fab2(sch_1):page98_i9" )
			)
			( gate "R6L16"
				( objectStatus "@baseboard_fab2_lib.baseboard_fab2(sch_1):page98_i12" )
			)
			( gate "R6M2"
				( objectStatus "@baseboard_fab2_lib.baseboard_fab2(sch_1):page98_i14" )
			)
			( gate "C6M2"
				( objectStatus "@baseboard_fab2_lib.baseboard_fab2(sch_1):page98_i33" )
			)
			( gate "R4F4"
				( objectStatus "@baseboard_fab2_lib.baseboard_fab2(sch_1):page98_i36" )
			)
			( gate "R4G2"
				( objectStatus "@baseboard_fab2_lib.baseboard_fab2(sch_1):page98_i38" )
			)
			( gate "R4G3"
				( objectStatus "@baseboard_fab2_lib.baseboard_fab2(sch_1):page98_i40" )
			)
			( gate "R4G1"
				( objectStatus "@baseboard_fab2_lib.baseboard_fab2(sch_1):page98_i42" )
			)
			( gate "C4G1"
				( objectStatus "@baseboard_fab2_lib.baseboard_fab2(sch_1):page98_i43" )
			)
			( gate "R4G21"
				( objectStatus "@baseboard_fab2_lib.baseboard_fab2(sch_1):page98_i46" )
			)
			( gate "R4G22"
				( objectStatus "@baseboard_fab2_lib.baseboard_fab2(sch_1):page98_i48" )
			)
			( gate "R4G20"
				( objectStatus "@baseboard_fab2_lib.baseboard_fab2(sch_1):page98_i50" )
			)
			( gate "C4G17"
				( objectStatus "@baseboard_fab2_lib.baseboard_fab2(sch_1):page98_i51" )
			)
			( gate "R6L13"
				( objectStatus "@baseboard_fab2_lib.baseboard_fab2(sch_1):page98_i54" )
			)
			( gate "R6L12"
				( objectStatus "@baseboard_fab2_lib.baseboard_fab2(sch_1):page98_i56" )
			)
			( gate "R6L14"
				( objectStatus "@baseboard_fab2_lib.baseboard_fab2(sch_1):page98_i58" )
			)
			( gate "C6L7"
				( objectStatus "@baseboard_fab2_lib.baseboard_fab2(sch_1):page98_i59" )
			)
			( gate "R6L2"
				( objectStatus "@baseboard_fab2_lib.baseboard_fab2(sch_1):page98_i62" )
			)
			( gate "R6L1"
				( objectStatus "@baseboard_fab2_lib.baseboard_fab2(sch_1):page98_i64" )
			)
			( gate "R6L3"
				( objectStatus "@baseboard_fab2_lib.baseboard_fab2(sch_1):page98_i66" )
			)
			( gate "C6L2"
				( objectStatus "@baseboard_fab2_lib.baseboard_fab2(sch_1):page98_i67" )
			)
			( gate "C6F2"
				( objectStatus "@baseboard_fab2_lib.baseboard_fab2(sch_1):page99_i2" )
			)
			( gate "C6F3"
				( objectStatus "@baseboard_fab2_lib.baseboard_fab2(sch_1):page99_i7" )
			)
			( gate "R4T9"
				( objectStatus "@baseboard_fab2_lib.baseboard_fab2(sch_1):page99_i9" )
			)
			( gate "R4T10"
				( objectStatus "@baseboard_fab2_lib.baseboard_fab2(sch_1):page99_i10" )
			)
			( gate "R4T8"
				( objectStatus "@baseboard_fab2_lib.baseboard_fab2(sch_1):page99_i11" )
			)
			( gate "R4T7"
				( objectStatus "@baseboard_fab2_lib.baseboard_fab2(sch_1):page99_i13" )
			)
			( gate "U6F1"
				( objectStatus "@baseboard_fab2_lib.baseboard_fab2(sch_1):page99_i15" )
			)
			( gate "R4T6"
				( objectStatus "@baseboard_fab2_lib.baseboard_fab2(sch_1):page99_i17" )
			)
			( gate "R4T5"
				( objectStatus "@baseboard_fab2_lib.baseboard_fab2(sch_1):page99_i19" )
			)
			( gate "R4T4"
				( objectStatus "@baseboard_fab2_lib.baseboard_fab2(sch_1):page99_i20" )
			)
			( gate "C7E1"
				( objectStatus "@baseboard_fab2_lib.baseboard_fab2(sch_1):page99_i23" )
			)
			( gate "C4G22"
				( objectStatus "@baseboard_fab2_lib.baseboard_fab2(sch_1):page99_i27" )
			)
			( gate "C7E2"
				( objectStatus "@baseboard_fab2_lib.baseboard_fab2(sch_1):page99_i32" )
			)
			( gate "R3R9"
				( objectStatus "@baseboard_fab2_lib.baseboard_fab2(sch_1):page99_i34" )
			)
			( gate "R3R8"
				( objectStatus "@baseboard_fab2_lib.baseboard_fab2(sch_1):page99_i35" )
			)
			( gate "C4G25"
				( objectStatus "@baseboard_fab2_lib.baseboard_fab2(sch_1):page99_i41" )
			)
			( gate "R6U13"
				( objectStatus "@baseboard_fab2_lib.baseboard_fab2(sch_1):page99_i42" )
			)
			( gate "R6U14"
				( objectStatus "@baseboard_fab2_lib.baseboard_fab2(sch_1):page99_i43" )
			)
			( gate "C3B4"
				( objectStatus "@baseboard_fab2_lib.baseboard_fab2(sch_1):page99_i47" )
			)
			( gate "C3B5"
				( objectStatus "@baseboard_fab2_lib.baseboard_fab2(sch_1):page99_i53" )
			)
			( gate "R7M5"
				( objectStatus "@baseboard_fab2_lib.baseboard_fab2(sch_1):page99_i55" )
			)
			( gate "R7M4"
				( objectStatus "@baseboard_fab2_lib.baseboard_fab2(sch_1):page99_i56" )
			)
			( gate "U7E1"
				( objectStatus "@baseboard_fab2_lib.baseboard_fab2(sch_1):page99_i61" )
			)
			( gate "U4G1"
				( objectStatus "@baseboard_fab2_lib.baseboard_fab2(sch_1):page99_i63" )
			)
			( gate "R3R13"
				( objectStatus "@baseboard_fab2_lib.baseboard_fab2(sch_1):page99_i65" )
			)
			( gate "R3P60"
				( objectStatus "@baseboard_fab2_lib.baseboard_fab2(sch_1):page99_i67" )
			)
			( gate "R6T1"
				( objectStatus "@baseboard_fab2_lib.baseboard_fab2(sch_1):page99_i70" )
			)
			( gate "R6T2"
				( objectStatus "@baseboard_fab2_lib.baseboard_fab2(sch_1):page99_i72" )
			)
			( gate "U3B1"
				( objectStatus "@baseboard_fab2_lib.baseboard_fab2(sch_1):page99_i75" )
			)
			( gate "R7M7"
				( objectStatus "@baseboard_fab2_lib.baseboard_fab2(sch_1):page99_i77" )
			)
			( gate "R7M2"
				( objectStatus "@baseboard_fab2_lib.baseboard_fab2(sch_1):page99_i79" )
			)
			( gate "R4T3"
				( objectStatus "@baseboard_fab2_lib.baseboard_fab2(sch_1):page99_i83" )
			)
			( gate "R3R7"
				( objectStatus "@baseboard_fab2_lib.baseboard_fab2(sch_1):page99_i88" )
			)
			( gate "R6T3"
				( objectStatus "@baseboard_fab2_lib.baseboard_fab2(sch_1):page99_i92" )
			)
			( gate "R7M3"
				( objectStatus "@baseboard_fab2_lib.baseboard_fab2(sch_1):page99_i98" )
			)
			( gate "R3R12"
				( objectStatus "@baseboard_fab2_lib.baseboard_fab2(sch_1):page99_i101" )
			)
			( gate "R3R5"
				( objectStatus "@baseboard_fab2_lib.baseboard_fab2(sch_1):page99_i103" )
			)
			( gate "R6U18"
				( objectStatus "@baseboard_fab2_lib.baseboard_fab2(sch_1):page99_i104" )
			)
			( gate "R6U17"
				( objectStatus "@baseboard_fab2_lib.baseboard_fab2(sch_1):page99_i106" )
			)
			( gate "R7M6"
				( objectStatus "@baseboard_fab2_lib.baseboard_fab2(sch_1):page99_i107" )
			)
			( gate "R7M1"
				( objectStatus "@baseboard_fab2_lib.baseboard_fab2(sch_1):page99_i109" )
			)
			( gate "R3R14"
				( objectStatus "@baseboard_fab2_lib.baseboard_fab2(sch_1):page99_i110" )
			)
			( gate "R6T4"
				( objectStatus "@baseboard_fab2_lib.baseboard_fab2(sch_1):page99_i111" )
			)
			( gate "R7M8"
				( objectStatus "@baseboard_fab2_lib.baseboard_fab2(sch_1):page99_i112" )
			)
			( gate "R1F6"
				( objectStatus "@baseboard_fab2_lib.baseboard_fab2(sch_1):page100_i2" )
			)
			( gate "R9L11"
				( objectStatus "@baseboard_fab2_lib.baseboard_fab2(sch_1):page100_i4" )
			)
			( gate "R1F5"
				( objectStatus "@baseboard_fab2_lib.baseboard_fab2(sch_1):page100_i6" )
			)
			( gate "R1F4"
				( objectStatus "@baseboard_fab2_lib.baseboard_fab2(sch_1):page100_i7" )
			)
			( gate "C1F19"
				( objectStatus "@baseboard_fab2_lib.baseboard_fab2(sch_1):page100_i8" )
			)
			( gate "R9M1"
				( objectStatus "@baseboard_fab2_lib.baseboard_fab2(sch_1):page100_i11" )
			)
			( gate "R9M2"
				( objectStatus "@baseboard_fab2_lib.baseboard_fab2(sch_1):page100_i13" )
			)
			( gate "C9M2"
				( objectStatus "@baseboard_fab2_lib.baseboard_fab2(sch_1):page100_i15" )
			)
			( gate "R1G2"
				( objectStatus "@baseboard_fab2_lib.baseboard_fab2(sch_1):page100_i19" )
			)
			( gate "R1G3"
				( objectStatus "@baseboard_fab2_lib.baseboard_fab2(sch_1):page100_i20" )
			)
			( gate "R9L7"
				( objectStatus "@baseboard_fab2_lib.baseboard_fab2(sch_1):page100_i22" )
			)
			( gate "R9L6"
				( objectStatus "@baseboard_fab2_lib.baseboard_fab2(sch_1):page100_i24" )
			)
			( gate "R1G1"
				( objectStatus "@baseboard_fab2_lib.baseboard_fab2(sch_1):page100_i25" )
			)
			( gate "C1G8"
				( objectStatus "@baseboard_fab2_lib.baseboard_fab2(sch_1):page100_i26" )
			)
			( gate "R9L8"
				( objectStatus "@baseboard_fab2_lib.baseboard_fab2(sch_1):page100_i29" )
			)
			( gate "C9L8"
				( objectStatus "@baseboard_fab2_lib.baseboard_fab2(sch_1):page100_i30" )
			)
			( gate "R1G15"
				( objectStatus "@baseboard_fab2_lib.baseboard_fab2(sch_1):page100_i35" )
			)
			( gate "R1G17"
				( objectStatus "@baseboard_fab2_lib.baseboard_fab2(sch_1):page100_i36" )
			)
			( gate "R9L2"
				( objectStatus "@baseboard_fab2_lib.baseboard_fab2(sch_1):page100_i38" )
			)
			( gate "R9L1"
				( objectStatus "@baseboard_fab2_lib.baseboard_fab2(sch_1):page100_i40" )
			)
			( gate "R1G14"
				( objectStatus "@baseboard_fab2_lib.baseboard_fab2(sch_1):page100_i41" )
			)
			( gate "C1G18"
				( objectStatus "@baseboard_fab2_lib.baseboard_fab2(sch_1):page100_i42" )
			)
			( gate "R9L3"
				( objectStatus "@baseboard_fab2_lib.baseboard_fab2(sch_1):page100_i45" )
			)
			( gate "C9L3"
				( objectStatus "@baseboard_fab2_lib.baseboard_fab2(sch_1):page100_i46" )
			)
			( gate "R8F29"
				( objectStatus "@baseboard_fab2_lib.baseboard_fab2(sch_1):page101_i20" )
			)
			( gate "R8F25"
				( objectStatus "@baseboard_fab2_lib.baseboard_fab2(sch_1):page101_i28" )
			)
			( gate "EU8F2"
				( objectStatus "@baseboard_fab2_lib.baseboard_fab2(sch_1):page101_i34" )
			)
			( gate "R2T25"
				( objectStatus "@baseboard_fab2_lib.baseboard_fab2(sch_1):page101_i48" )
			)
			( gate "C8F18"
				( objectStatus "@baseboard_fab2_lib.baseboard_fab2(sch_1):page101_i49" )
			)
			( gate "Y8F1"
				( objectStatus "@baseboard_fab2_lib.baseboard_fab2(sch_1):page101_i52" )
			)
			( gate "C8F19"
				( objectStatus "@baseboard_fab2_lib.baseboard_fab2(sch_1):page101_i53" )
			)
			( gate "C2T31"
				( objectStatus "@baseboard_fab2_lib.baseboard_fab2(sch_1):page101_i89" )
			)
			( gate "C2T27"
				( objectStatus "@baseboard_fab2_lib.baseboard_fab2(sch_1):page101_i90" )
			)
			( gate "R2T23"
				( objectStatus "@baseboard_fab2_lib.baseboard_fab2(sch_1):page101_i94" )
			)
			( gate "R2T52"
				( objectStatus "@baseboard_fab2_lib.baseboard_fab2(sch_1):page101_i95" )
			)
			( gate "C2T38"
				( objectStatus "@baseboard_fab2_lib.baseboard_fab2(sch_1):page101_i97" )
			)
			( gate "C2T37"
				( objectStatus "@baseboard_fab2_lib.baseboard_fab2(sch_1):page101_i99" )
			)
			( gate "C2T18"
				( objectStatus "@baseboard_fab2_lib.baseboard_fab2(sch_1):page101_i104" )
			)
			( gate "R2T21"
				( objectStatus "@baseboard_fab2_lib.baseboard_fab2(sch_1):page101_i105" )
			)
			( gate "C2T19"
				( objectStatus "@baseboard_fab2_lib.baseboard_fab2(sch_1):page101_i106" )
			)
			( gate "C2T34"
				( objectStatus "@baseboard_fab2_lib.baseboard_fab2(sch_1):page101_i109" )
			)
			( gate "C2T30"
				( objectStatus "@baseboard_fab2_lib.baseboard_fab2(sch_1):page101_i110" )
			)
			( gate "C2T25"
				( objectStatus "@baseboard_fab2_lib.baseboard_fab2(sch_1):page101_i111" )
			)
			( gate "C2T17"
				( objectStatus "@baseboard_fab2_lib.baseboard_fab2(sch_1):page101_i112" )
			)
			( gate "C2T22"
				( objectStatus "@baseboard_fab2_lib.baseboard_fab2(sch_1):page101_i113" )
			)
			( gate "FB2T2"
				( objectStatus "@baseboard_fab2_lib.baseboard_fab2(sch_1):page101_i114" )
			)
			( gate "C2T28"
				( objectStatus "@baseboard_fab2_lib.baseboard_fab2(sch_1):page101_i116" )
			)
			( gate "R2T42"
				( objectStatus "@baseboard_fab2_lib.baseboard_fab2(sch_1):page101_i124" )
			)
			( gate "R2T46"
				( objectStatus "@baseboard_fab2_lib.baseboard_fab2(sch_1):page101_i125" )
			)
			( gate "R8F27"
				( objectStatus "@baseboard_fab2_lib.baseboard_fab2(sch_1):page101_i129" )
			)
			( gate "R2T47"
				( objectStatus "@baseboard_fab2_lib.baseboard_fab2(sch_1):page101_i130" )
			)
			( gate "R8G25"
				( objectStatus "@baseboard_fab2_lib.baseboard_fab2(sch_1):page101_i131" )
			)
			( gate "R8G24"
				( objectStatus "@baseboard_fab2_lib.baseboard_fab2(sch_1):page101_i132" )
			)
			( gate "R8G1"
				( objectStatus "@baseboard_fab2_lib.baseboard_fab2(sch_1):page101_i133" )
			)
			( gate "EU4D2"
				( objectStatus "@baseboard_fab2_lib.baseboard_fab2(sch_1):page102_i1" )
			)
			( gate "FB6P1"
				( objectStatus "@baseboard_fab2_lib.baseboard_fab2(sch_1):page102_i8" )
			)
			( gate "C3D22"
				( objectStatus "@baseboard_fab2_lib.baseboard_fab2(sch_1):page102_i10" )
			)
			( gate "C6P4"
				( objectStatus "@baseboard_fab2_lib.baseboard_fab2(sch_1):page102_i11" )
			)
			( gate "C6P6"
				( objectStatus "@baseboard_fab2_lib.baseboard_fab2(sch_1):page102_i12" )
			)
			( gate "C6P10"
				( objectStatus "@baseboard_fab2_lib.baseboard_fab2(sch_1):page102_i13" )
			)
			( gate "C6P5"
				( objectStatus "@baseboard_fab2_lib.baseboard_fab2(sch_1):page102_i14" )
			)
			( gate "C6P12"
				( objectStatus "@baseboard_fab2_lib.baseboard_fab2(sch_1):page102_i15" )
			)
			( gate "C6P11"
				( objectStatus "@baseboard_fab2_lib.baseboard_fab2(sch_1):page102_i16" )
			)
			( gate "C4D24"
				( objectStatus "@baseboard_fab2_lib.baseboard_fab2(sch_1):page102_i18" )
			)
			( gate "C4D23"
				( objectStatus "@baseboard_fab2_lib.baseboard_fab2(sch_1):page102_i19" )
			)
			( gate "R3D14"
				( objectStatus "@baseboard_fab2_lib.baseboard_fab2(sch_1):page102_i21" )
			)
			( gate "R6P25"
				( objectStatus "@baseboard_fab2_lib.baseboard_fab2(sch_1):page102_i26" )
			)
			( gate "C4D22"
				( objectStatus "@baseboard_fab2_lib.baseboard_fab2(sch_1):page102_i28" )
			)
			( gate "C4D27"
				( objectStatus "@baseboard_fab2_lib.baseboard_fab2(sch_1):page102_i30" )
			)
			( gate "R4D38"
				( objectStatus "@baseboard_fab2_lib.baseboard_fab2(sch_1):page102_i37" )
			)
			( gate "R4D35"
				( objectStatus "@baseboard_fab2_lib.baseboard_fab2(sch_1):page102_i38" )
			)
			( gate "R4D40"
				( objectStatus "@baseboard_fab2_lib.baseboard_fab2(sch_1):page102_i45" )
			)
			( gate "R6P23"
				( objectStatus "@baseboard_fab2_lib.baseboard_fab2(sch_1):page102_i46" )
			)
			( gate "R6P22"
				( objectStatus "@baseboard_fab2_lib.baseboard_fab2(sch_1):page102_i47" )
			)
			( gate "R4D41"
				( objectStatus "@baseboard_fab2_lib.baseboard_fab2(sch_1):page102_i53" )
			)
			( gate "C6P9"
				( objectStatus "@baseboard_fab2_lib.baseboard_fab2(sch_1):page102_i79" )
			)
			( gate "R6P21"
				( objectStatus "@baseboard_fab2_lib.baseboard_fab2(sch_1):page102_i80" )
			)
			( gate "R6P20"
				( objectStatus "@baseboard_fab2_lib.baseboard_fab2(sch_1):page102_i81" )
			)
			( gate "R4D36"
				( objectStatus "@baseboard_fab2_lib.baseboard_fab2(sch_1):page102_i82" )
			)
			( gate "R4D37"
				( objectStatus "@baseboard_fab2_lib.baseboard_fab2(sch_1):page102_i87" )
			)
			( gate "R6P48"
				( objectStatus "@baseboard_fab2_lib.baseboard_fab2(sch_1):page102_i91" )
			)
			( gate "R4D69"
				( objectStatus "@baseboard_fab2_lib.baseboard_fab2(sch_1):page102_i93" )
			)
			( gate "R4D70"
				( objectStatus "@baseboard_fab2_lib.baseboard_fab2(sch_1):page102_i94" )
			)
			( gate "R4D25"
				( objectStatus "@baseboard_fab2_lib.baseboard_fab2(sch_1):page103_i1" )
			)
			( gate "R4D23"
				( objectStatus "@baseboard_fab2_lib.baseboard_fab2(sch_1):page103_i9" )
			)
			( gate "R4D28"
				( objectStatus "@baseboard_fab2_lib.baseboard_fab2(sch_1):page103_i14" )
			)
			( gate "R4D19"
				( objectStatus "@baseboard_fab2_lib.baseboard_fab2(sch_1):page103_i19" )
			)
			( gate "R4D21"
				( objectStatus "@baseboard_fab2_lib.baseboard_fab2(sch_1):page103_i24" )
			)
			( gate "R4D13"
				( objectStatus "@baseboard_fab2_lib.baseboard_fab2(sch_1):page103_i29" )
			)
			( gate "R4D16"
				( objectStatus "@baseboard_fab2_lib.baseboard_fab2(sch_1):page103_i34" )
			)
			( gate "R4D9"
				( objectStatus "@baseboard_fab2_lib.baseboard_fab2(sch_1):page103_i39" )
			)
			( gate "R4D11"
				( objectStatus "@baseboard_fab2_lib.baseboard_fab2(sch_1):page103_i44" )
			)
			( gate "R4D2"
				( objectStatus "@baseboard_fab2_lib.baseboard_fab2(sch_1):page103_i49" )
			)
			( gate "R4D1"
				( objectStatus "@baseboard_fab2_lib.baseboard_fab2(sch_1):page103_i54" )
			)
			( gate "R4D4"
				( objectStatus "@baseboard_fab2_lib.baseboard_fab2(sch_1):page103_i59" )
			)
			( gate "R4D3"
				( objectStatus "@baseboard_fab2_lib.baseboard_fab2(sch_1):page103_i64" )
			)
			( gate "R4D29"
				( objectStatus "@baseboard_fab2_lib.baseboard_fab2(sch_1):page103_i69" )
			)
			( gate "R4D6"
				( objectStatus "@baseboard_fab2_lib.baseboard_fab2(sch_1):page103_i74" )
			)
			( gate "R4D5"
				( objectStatus "@baseboard_fab2_lib.baseboard_fab2(sch_1):page103_i79" )
			)
			( gate "R4D8"
				( objectStatus "@baseboard_fab2_lib.baseboard_fab2(sch_1):page103_i84" )
			)
			( gate "R4D7"
				( objectStatus "@baseboard_fab2_lib.baseboard_fab2(sch_1):page103_i89" )
			)
			( gate "R4D12"
				( objectStatus "@baseboard_fab2_lib.baseboard_fab2(sch_1):page103_i94" )
			)
			( gate "R4D10"
				( objectStatus "@baseboard_fab2_lib.baseboard_fab2(sch_1):page103_i99" )
			)
			( gate "R4D17"
				( objectStatus "@baseboard_fab2_lib.baseboard_fab2(sch_1):page103_i104" )
			)
			( gate "R4D14"
				( objectStatus "@baseboard_fab2_lib.baseboard_fab2(sch_1):page103_i109" )
			)
			( gate "R4D22"
				( objectStatus "@baseboard_fab2_lib.baseboard_fab2(sch_1):page103_i114" )
			)
			( gate "R4D20"
				( objectStatus "@baseboard_fab2_lib.baseboard_fab2(sch_1):page103_i119" )
			)
			( gate "R7P9"
				( objectStatus "@baseboard_fab2_lib.baseboard_fab2(sch_1):page103_i121" )
			)
			( gate "R7P12"
				( objectStatus "@baseboard_fab2_lib.baseboard_fab2(sch_1):page103_i123" )
			)
			( gate "R7P6"
				( objectStatus "@baseboard_fab2_lib.baseboard_fab2(sch_1):page103_i125" )
			)
			( gate "R7P7"
				( objectStatus "@baseboard_fab2_lib.baseboard_fab2(sch_1):page103_i127" )
			)
			( gate "R7P3"
				( objectStatus "@baseboard_fab2_lib.baseboard_fab2(sch_1):page103_i129" )
			)
			( gate "R7P4"
				( objectStatus "@baseboard_fab2_lib.baseboard_fab2(sch_1):page103_i131" )
			)
			( gate "R7P1"
				( objectStatus "@baseboard_fab2_lib.baseboard_fab2(sch_1):page103_i133" )
			)
			( gate "R7P2"
				( objectStatus "@baseboard_fab2_lib.baseboard_fab2(sch_1):page103_i135" )
			)
			( gate "R6P7"
				( objectStatus "@baseboard_fab2_lib.baseboard_fab2(sch_1):page103_i137" )
			)
			( gate "R6P8"
				( objectStatus "@baseboard_fab2_lib.baseboard_fab2(sch_1):page103_i139" )
			)
			( gate "R6P5"
				( objectStatus "@baseboard_fab2_lib.baseboard_fab2(sch_1):page103_i141" )
			)
			( gate "R6P6"
				( objectStatus "@baseboard_fab2_lib.baseboard_fab2(sch_1):page103_i143" )
			)
			( gate "R6P3"
				( objectStatus "@baseboard_fab2_lib.baseboard_fab2(sch_1):page103_i145" )
			)
			( gate "R6P4"
				( objectStatus "@baseboard_fab2_lib.baseboard_fab2(sch_1):page103_i147" )
			)
			( gate "R6P1"
				( objectStatus "@baseboard_fab2_lib.baseboard_fab2(sch_1):page103_i149" )
			)
			( gate "R6P2"
				( objectStatus "@baseboard_fab2_lib.baseboard_fab2(sch_1):page103_i151" )
			)
			( gate "R6P11"
				( objectStatus "@baseboard_fab2_lib.baseboard_fab2(sch_1):page103_i153" )
			)
			( gate "R6P9"
				( objectStatus "@baseboard_fab2_lib.baseboard_fab2(sch_1):page103_i155" )
			)
			( gate "R6P13"
				( objectStatus "@baseboard_fab2_lib.baseboard_fab2(sch_1):page103_i157" )
			)
			( gate "R6P12"
				( objectStatus "@baseboard_fab2_lib.baseboard_fab2(sch_1):page103_i159" )
			)
			( gate "R4D24"
				( objectStatus "@baseboard_fab2_lib.baseboard_fab2(sch_1):page103_i161" )
			)
			( gate "R4D18"
				( objectStatus "@baseboard_fab2_lib.baseboard_fab2(sch_1):page103_i163" )
			)
			( gate "R6P17"
				( objectStatus "@baseboard_fab2_lib.baseboard_fab2(sch_1):page103_i165" )
			)
			( gate "R6P15"
				( objectStatus "@baseboard_fab2_lib.baseboard_fab2(sch_1):page103_i167" )
			)
			( gate "C6F1"
				( objectStatus "@baseboard_fab2_lib.baseboard_fab2(sch_1):page104_i25" )
			)
			( gate "C3F2"
				( objectStatus "@baseboard_fab2_lib.baseboard_fab2(sch_1):page104_i34" )
			)
			( gate "R6F8"
				( objectStatus "@baseboard_fab2_lib.baseboard_fab2(sch_1):page104_i37" )
			)
			( gate "R6F6"
				( objectStatus "@baseboard_fab2_lib.baseboard_fab2(sch_1):page104_i41" )
			)
			( gate "R3F1"
				( objectStatus "@baseboard_fab2_lib.baseboard_fab2(sch_1):page104_i51" )
			)
			( gate "R3F3"
				( objectStatus "@baseboard_fab2_lib.baseboard_fab2(sch_1):page104_i53" )
			)
			( gate "R6F7"
				( objectStatus "@baseboard_fab2_lib.baseboard_fab2(sch_1):page104_i67" )
			)
			( gate "R6F9"
				( objectStatus "@baseboard_fab2_lib.baseboard_fab2(sch_1):page104_i68" )
			)
			( gate "R3F2"
				( objectStatus "@baseboard_fab2_lib.baseboard_fab2(sch_1):page104_i69" )
			)
			( gate "R3F4"
				( objectStatus "@baseboard_fab2_lib.baseboard_fab2(sch_1):page104_i70" )
			)
			( gate "Y6F1"
				( objectStatus "@baseboard_fab2_lib.baseboard_fab2(sch_1):page104_i71" )
			)
			( gate "Y3F1"
				( objectStatus "@baseboard_fab2_lib.baseboard_fab2(sch_1):page104_i72" )
			)
			( gate "R6F10"
				( objectStatus "@baseboard_fab2_lib.baseboard_fab2(sch_1):page104_i78" )
			)
			( gate "R6F11"
				( objectStatus "@baseboard_fab2_lib.baseboard_fab2(sch_1):page104_i79" )
			)
			( gate "R3F5"
				( objectStatus "@baseboard_fab2_lib.baseboard_fab2(sch_1):page104_i84" )
			)
			( gate "R3F6"
				( objectStatus "@baseboard_fab2_lib.baseboard_fab2(sch_1):page104_i88" )
			)
			( gate "R8D43"
				( objectStatus "@baseboard_fab2_lib.baseboard_fab2(sch_1):page104_i93" )
			)
			( gate "R7D40"
				( objectStatus "@baseboard_fab2_lib.baseboard_fab2(sch_1):page104_i94" )
			)
			( gate "R7D39"
				( objectStatus "@baseboard_fab2_lib.baseboard_fab2(sch_1):page104_i95" )
			)
			( gate "R7D36"
				( objectStatus "@baseboard_fab2_lib.baseboard_fab2(sch_1):page104_i96" )
			)
			( gate "R7D38"
				( objectStatus "@baseboard_fab2_lib.baseboard_fab2(sch_1):page104_i97" )
			)
			( gate "R7D37"
				( objectStatus "@baseboard_fab2_lib.baseboard_fab2(sch_1):page104_i98" )
			)
			( gate "C7G24"
				( objectStatus "@baseboard_fab2_lib.baseboard_fab2(sch_1):page105_i1" )
			)
			( gate "C7G6"
				( objectStatus "@baseboard_fab2_lib.baseboard_fab2(sch_1):page105_i6" )
			)
			( gate "C7G7"
				( objectStatus "@baseboard_fab2_lib.baseboard_fab2(sch_1):page105_i7" )
			)
			( gate "C7G10"
				( objectStatus "@baseboard_fab2_lib.baseboard_fab2(sch_1):page105_i8" )
			)
			( gate "C7G12"
				( objectStatus "@baseboard_fab2_lib.baseboard_fab2(sch_1):page105_i12" )
			)
			( gate "C7G13"
				( objectStatus "@baseboard_fab2_lib.baseboard_fab2(sch_1):page105_i13" )
			)
			( gate "C7G5"
				( objectStatus "@baseboard_fab2_lib.baseboard_fab2(sch_1):page105_i20" )
			)
			( gate "C7G9"
				( objectStatus "@baseboard_fab2_lib.baseboard_fab2(sch_1):page105_i21" )
			)
			( gate "C7G8"
				( objectStatus "@baseboard_fab2_lib.baseboard_fab2(sch_1):page105_i22" )
			)
			( gate "C7G11"
				( objectStatus "@baseboard_fab2_lib.baseboard_fab2(sch_1):page105_i27" )
			)
			( gate "C7G14"
				( objectStatus "@baseboard_fab2_lib.baseboard_fab2(sch_1):page105_i28" )
			)
			( gate "C7G16"
				( objectStatus "@baseboard_fab2_lib.baseboard_fab2(sch_1):page105_i31" )
			)
			( gate "C7G18"
				( objectStatus "@baseboard_fab2_lib.baseboard_fab2(sch_1):page105_i32" )
			)
			( gate "C7G20"
				( objectStatus "@baseboard_fab2_lib.baseboard_fab2(sch_1):page105_i34" )
			)
			( gate "C7G22"
				( objectStatus "@baseboard_fab2_lib.baseboard_fab2(sch_1):page105_i37" )
			)
			( gate "C7G17"
				( objectStatus "@baseboard_fab2_lib.baseboard_fab2(sch_1):page105_i44" )
			)
			( gate "C7G15"
				( objectStatus "@baseboard_fab2_lib.baseboard_fab2(sch_1):page105_i45" )
			)
			( gate "C7G19"
				( objectStatus "@baseboard_fab2_lib.baseboard_fab2(sch_1):page105_i46" )
			)
			( gate "C7G21"
				( objectStatus "@baseboard_fab2_lib.baseboard_fab2(sch_1):page105_i51" )
			)
			( gate "C7G23"
				( objectStatus "@baseboard_fab2_lib.baseboard_fab2(sch_1):page105_i52" )
			)
			( gate "C7G26"
				( objectStatus "@baseboard_fab2_lib.baseboard_fab2(sch_1):page105_i55" )
			)
			( gate "C8G4"
				( objectStatus "@baseboard_fab2_lib.baseboard_fab2(sch_1):page105_i56" )
			)
			( gate "C8G2"
				( objectStatus "@baseboard_fab2_lib.baseboard_fab2(sch_1):page105_i58" )
			)
			( gate "C8G6"
				( objectStatus "@baseboard_fab2_lib.baseboard_fab2(sch_1):page105_i61" )
			)
			( gate "C8G7"
				( objectStatus "@baseboard_fab2_lib.baseboard_fab2(sch_1):page105_i62" )
			)
			( gate "C7G25"
				( objectStatus "@baseboard_fab2_lib.baseboard_fab2(sch_1):page105_i69" )
			)
			( gate "C8G1"
				( objectStatus "@baseboard_fab2_lib.baseboard_fab2(sch_1):page105_i70" )
			)
			( gate "C8G3"
				( objectStatus "@baseboard_fab2_lib.baseboard_fab2(sch_1):page105_i71" )
			)
			( gate "C8G5"
				( objectStatus "@baseboard_fab2_lib.baseboard_fab2(sch_1):page105_i75" )
			)
			( gate "C8G8"
				( objectStatus "@baseboard_fab2_lib.baseboard_fab2(sch_1):page105_i76" )
			)
			( gate "C8G9"
				( objectStatus "@baseboard_fab2_lib.baseboard_fab2(sch_1):page105_i93" )
			)
			( gate "C8G10"
				( objectStatus "@baseboard_fab2_lib.baseboard_fab2(sch_1):page105_i96" )
			)
			( gate "C6B18"
				( objectStatus "@baseboard_fab2_lib.baseboard_fab2(sch_1):page105_i153" )
			)
			( gate "C6B19"
				( objectStatus "@baseboard_fab2_lib.baseboard_fab2(sch_1):page105_i160" )
			)
			( gate "C6B15"
				( objectStatus "@baseboard_fab2_lib.baseboard_fab2(sch_1):page105_i163" )
			)
			( gate "C6B11"
				( objectStatus "@baseboard_fab2_lib.baseboard_fab2(sch_1):page105_i166" )
			)
			( gate "C6B6"
				( objectStatus "@baseboard_fab2_lib.baseboard_fab2(sch_1):page105_i169" )
			)
			( gate "C6B20"
				( objectStatus "@baseboard_fab2_lib.baseboard_fab2(sch_1):page105_i173" )
			)
			( gate "C6B17"
				( objectStatus "@baseboard_fab2_lib.baseboard_fab2(sch_1):page105_i175" )
			)
			( gate "C6B16"
				( objectStatus "@baseboard_fab2_lib.baseboard_fab2(sch_1):page105_i180" )
			)
			( gate "C6B14"
				( objectStatus "@baseboard_fab2_lib.baseboard_fab2(sch_1):page105_i181" )
			)
			( gate "C6B9"
				( objectStatus "@baseboard_fab2_lib.baseboard_fab2(sch_1):page105_i185" )
			)
			( gate "C6B12"
				( objectStatus "@baseboard_fab2_lib.baseboard_fab2(sch_1):page105_i187" )
			)
			( gate "C6B13"
				( objectStatus "@baseboard_fab2_lib.baseboard_fab2(sch_1):page105_i189" )
			)
			( gate "C6B10"
				( objectStatus "@baseboard_fab2_lib.baseboard_fab2(sch_1):page105_i193" )
			)
			( gate "C6B4"
				( objectStatus "@baseboard_fab2_lib.baseboard_fab2(sch_1):page105_i196" )
			)
			( gate "C6B8"
				( objectStatus "@baseboard_fab2_lib.baseboard_fab2(sch_1):page105_i198" )
			)
			( gate "C6B5"
				( objectStatus "@baseboard_fab2_lib.baseboard_fab2(sch_1):page105_i201" )
			)
			( gate "C3M25"
				( objectStatus "@baseboard_fab2_lib.baseboard_fab2(sch_1):page105_i205" )
			)
			( gate "C3M34"
				( objectStatus "@baseboard_fab2_lib.baseboard_fab2(sch_1):page105_i206" )
			)
			( gate "C3M28"
				( objectStatus "@baseboard_fab2_lib.baseboard_fab2(sch_1):page105_i212" )
			)
			( gate "C3M33"
				( objectStatus "@baseboard_fab2_lib.baseboard_fab2(sch_1):page105_i217" )
			)
			( gate "C3M36"
				( objectStatus "@baseboard_fab2_lib.baseboard_fab2(sch_1):page105_i218" )
			)
			( gate "C3M32"
				( objectStatus "@baseboard_fab2_lib.baseboard_fab2(sch_1):page105_i223" )
			)
			( gate "C3M35"
				( objectStatus "@baseboard_fab2_lib.baseboard_fab2(sch_1):page105_i225" )
			)
			( gate "C3M26"
				( objectStatus "@baseboard_fab2_lib.baseboard_fab2(sch_1):page105_i229" )
			)
			( gate "C3M3"
				( objectStatus "@baseboard_fab2_lib.baseboard_fab2(sch_1):page105_i232" )
			)
			( gate "C3M11"
				( objectStatus "@baseboard_fab2_lib.baseboard_fab2(sch_1):page105_i234" )
			)
			( gate "C3M13"
				( objectStatus "@baseboard_fab2_lib.baseboard_fab2(sch_1):page105_i239" )
			)
			( gate "C3M4"
				( objectStatus "@baseboard_fab2_lib.baseboard_fab2(sch_1):page105_i244" )
			)
			( gate "C3M12"
				( objectStatus "@baseboard_fab2_lib.baseboard_fab2(sch_1):page105_i246" )
			)
			( gate "C3M2"
				( objectStatus "@baseboard_fab2_lib.baseboard_fab2(sch_1):page105_i247" )
			)
			( gate "C3M14"
				( objectStatus "@baseboard_fab2_lib.baseboard_fab2(sch_1):page105_i253" )
			)
			( gate "C3M1"
				( objectStatus "@baseboard_fab2_lib.baseboard_fab2(sch_1):page105_i255" )
			)
			( gate "C1R2"
				( objectStatus "@baseboard_fab2_lib.baseboard_fab2(sch_1):page106_i10" )
			)
			( gate "C1R4"
				( objectStatus "@baseboard_fab2_lib.baseboard_fab2(sch_1):page106_i26" )
			)
			( gate "C1R1"
				( objectStatus "@baseboard_fab2_lib.baseboard_fab2(sch_1):page106_i29" )
			)
			( gate "C1R3"
				( objectStatus "@baseboard_fab2_lib.baseboard_fab2(sch_1):page106_i37" )
			)
			( gate "C1R6"
				( objectStatus "@baseboard_fab2_lib.baseboard_fab2(sch_1):page106_i40" )
			)
			( gate "C1R8"
				( objectStatus "@baseboard_fab2_lib.baseboard_fab2(sch_1):page106_i55" )
			)
			( gate "C1R5"
				( objectStatus "@baseboard_fab2_lib.baseboard_fab2(sch_1):page106_i59" )
			)
			( gate "C1R7"
				( objectStatus "@baseboard_fab2_lib.baseboard_fab2(sch_1):page106_i70" )
			)
			( gate "C2M14"
				( objectStatus "@baseboard_fab2_lib.baseboard_fab2(sch_1):page106_i76" )
			)
			( gate "C1M18"
				( objectStatus "@baseboard_fab2_lib.baseboard_fab2(sch_1):page106_i78" )
			)
			( gate "C1M16"
				( objectStatus "@baseboard_fab2_lib.baseboard_fab2(sch_1):page106_i82" )
			)
			( gate "C1M14"
				( objectStatus "@baseboard_fab2_lib.baseboard_fab2(sch_1):page106_i85" )
			)
			( gate "C2M15"
				( objectStatus "@baseboard_fab2_lib.baseboard_fab2(sch_1):page106_i86" )
			)
			( gate "C1M19"
				( objectStatus "@baseboard_fab2_lib.baseboard_fab2(sch_1):page106_i90" )
			)
			( gate "C1M17"
				( objectStatus "@baseboard_fab2_lib.baseboard_fab2(sch_1):page106_i92" )
			)
			( gate "C1M15"
				( objectStatus "@baseboard_fab2_lib.baseboard_fab2(sch_1):page106_i95" )
			)
			( gate "C1M12"
				( objectStatus "@baseboard_fab2_lib.baseboard_fab2(sch_1):page106_i100" )
			)
			( gate "C1M10"
				( objectStatus "@baseboard_fab2_lib.baseboard_fab2(sch_1):page106_i102" )
			)
			( gate "C1M8"
				( objectStatus "@baseboard_fab2_lib.baseboard_fab2(sch_1):page106_i105" )
			)
			( gate "C1M6"
				( objectStatus "@baseboard_fab2_lib.baseboard_fab2(sch_1):page106_i109" )
			)
			( gate "C1M13"
				( objectStatus "@baseboard_fab2_lib.baseboard_fab2(sch_1):page106_i111" )
			)
			( gate "C1M9"
				( objectStatus "@baseboard_fab2_lib.baseboard_fab2(sch_1):page106_i114" )
			)
			( gate "C1M11"
				( objectStatus "@baseboard_fab2_lib.baseboard_fab2(sch_1):page106_i117" )
			)
			( gate "C1M7"
				( objectStatus "@baseboard_fab2_lib.baseboard_fab2(sch_1):page106_i122" )
			)
			( gate "C2R7"
				( objectStatus "@baseboard_fab2_lib.baseboard_fab2(sch_1):page106_i123" )
			)
			( gate "C1R10"
				( objectStatus "@baseboard_fab2_lib.baseboard_fab2(sch_1):page106_i128" )
			)
			( gate "C2R14"
				( objectStatus "@baseboard_fab2_lib.baseboard_fab2(sch_1):page106_i130" )
			)
			( gate "C1R9"
				( objectStatus "@baseboard_fab2_lib.baseboard_fab2(sch_1):page106_i134" )
			)
			( gate "C2R13"
				( objectStatus "@baseboard_fab2_lib.baseboard_fab2(sch_1):page106_i137" )
			)
			( gate "C2R8"
				( objectStatus "@baseboard_fab2_lib.baseboard_fab2(sch_1):page106_i141" )
			)
			( gate "C2R10"
				( objectStatus "@baseboard_fab2_lib.baseboard_fab2(sch_1):page106_i142" )
			)
			( gate "C2R9"
				( objectStatus "@baseboard_fab2_lib.baseboard_fab2(sch_1):page106_i147" )
			)
			( gate "C3P13"
				( objectStatus "@baseboard_fab2_lib.baseboard_fab2(sch_1):page107_i207" )
			)
			( gate "C3P17"
				( objectStatus "@baseboard_fab2_lib.baseboard_fab2(sch_1):page107_i208" )
			)
			( gate "C3P11"
				( objectStatus "@baseboard_fab2_lib.baseboard_fab2(sch_1):page107_i212" )
			)
			( gate "C3P20"
				( objectStatus "@baseboard_fab2_lib.baseboard_fab2(sch_1):page107_i215" )
			)
			( gate "C3P25"
				( objectStatus "@baseboard_fab2_lib.baseboard_fab2(sch_1):page107_i216" )
			)
			( gate "C3P18"
				( objectStatus "@baseboard_fab2_lib.baseboard_fab2(sch_1):page107_i219" )
			)
			( gate "C3P27"
				( objectStatus "@baseboard_fab2_lib.baseboard_fab2(sch_1):page107_i223" )
			)
			( gate "C3P15"
				( objectStatus "@baseboard_fab2_lib.baseboard_fab2(sch_1):page107_i226" )
			)
			( gate "C3P23"
				( objectStatus "@baseboard_fab2_lib.baseboard_fab2(sch_1):page107_i229" )
			)
			( gate "C3P28"
				( objectStatus "@baseboard_fab2_lib.baseboard_fab2(sch_1):page107_i232" )
			)
			( gate "C3P32"
				( objectStatus "@baseboard_fab2_lib.baseboard_fab2(sch_1):page107_i234" )
			)
			( gate "C3P37"
				( objectStatus "@baseboard_fab2_lib.baseboard_fab2(sch_1):page107_i235" )
			)
			( gate "C3P35"
				( objectStatus "@baseboard_fab2_lib.baseboard_fab2(sch_1):page107_i240" )
			)
			( gate "C3P40"
				( objectStatus "@baseboard_fab2_lib.baseboard_fab2(sch_1):page107_i241" )
			)
			( gate "C3P30"
				( objectStatus "@baseboard_fab2_lib.baseboard_fab2(sch_1):page107_i245" )
			)
			( gate "C3P39"
				( objectStatus "@baseboard_fab2_lib.baseboard_fab2(sch_1):page107_i248" )
			)
			( gate "C2U4"
				( objectStatus "@baseboard_fab2_lib.baseboard_fab2(sch_1):page107_i257" )
			)
			( gate "C2U6"
				( objectStatus "@baseboard_fab2_lib.baseboard_fab2(sch_1):page107_i260" )
			)
			( gate "C2U8"
				( objectStatus "@baseboard_fab2_lib.baseboard_fab2(sch_1):page107_i264" )
			)
			( gate "C2U12"
				( objectStatus "@baseboard_fab2_lib.baseboard_fab2(sch_1):page107_i265" )
			)
			( gate "C2U10"
				( objectStatus "@baseboard_fab2_lib.baseboard_fab2(sch_1):page107_i267" )
			)
			( gate "C2U3"
				( objectStatus "@baseboard_fab2_lib.baseboard_fab2(sch_1):page107_i272" )
			)
			( gate "C2U5"
				( objectStatus "@baseboard_fab2_lib.baseboard_fab2(sch_1):page107_i274" )
			)
			( gate "C2U7"
				( objectStatus "@baseboard_fab2_lib.baseboard_fab2(sch_1):page107_i277" )
			)
			( gate "C2U11"
				( objectStatus "@baseboard_fab2_lib.baseboard_fab2(sch_1):page107_i278" )
			)
			( gate "C2U9"
				( objectStatus "@baseboard_fab2_lib.baseboard_fab2(sch_1):page107_i279" )
			)
			( gate "C2U16"
				( objectStatus "@baseboard_fab2_lib.baseboard_fab2(sch_1):page107_i286" )
			)
			( gate "C2U14"
				( objectStatus "@baseboard_fab2_lib.baseboard_fab2(sch_1):page107_i287" )
			)
			( gate "C2U18"
				( objectStatus "@baseboard_fab2_lib.baseboard_fab2(sch_1):page107_i294" )
			)
			( gate "C2U15"
				( objectStatus "@baseboard_fab2_lib.baseboard_fab2(sch_1):page107_i296" )
			)
			( gate "C2U13"
				( objectStatus "@baseboard_fab2_lib.baseboard_fab2(sch_1):page107_i297" )
			)
			( gate "C2U17"
				( objectStatus "@baseboard_fab2_lib.baseboard_fab2(sch_1):page107_i300" )
			)
			( gate "C3P12"
				( objectStatus "@baseboard_fab2_lib.baseboard_fab2(sch_1):page107_i415" )
			)
			( gate "C3P10"
				( objectStatus "@baseboard_fab2_lib.baseboard_fab2(sch_1):page107_i417" )
			)
			( gate "C3P16"
				( objectStatus "@baseboard_fab2_lib.baseboard_fab2(sch_1):page107_i422" )
			)
			( gate "C3P21"
				( objectStatus "@baseboard_fab2_lib.baseboard_fab2(sch_1):page107_i423" )
			)
			( gate "C3P24"
				( objectStatus "@baseboard_fab2_lib.baseboard_fab2(sch_1):page107_i424" )
			)
			( gate "C3P19"
				( objectStatus "@baseboard_fab2_lib.baseboard_fab2(sch_1):page107_i427" )
			)
			( gate "C3P14"
				( objectStatus "@baseboard_fab2_lib.baseboard_fab2(sch_1):page107_i431" )
			)
			( gate "C3P22"
				( objectStatus "@baseboard_fab2_lib.baseboard_fab2(sch_1):page107_i435" )
			)
			( gate "C3P29"
				( objectStatus "@baseboard_fab2_lib.baseboard_fab2(sch_1):page107_i437" )
			)
			( gate "C3P36"
				( objectStatus "@baseboard_fab2_lib.baseboard_fab2(sch_1):page107_i438" )
			)
			( gate "C3P33"
				( objectStatus "@baseboard_fab2_lib.baseboard_fab2(sch_1):page107_i439" )
			)
			( gate "C3P26"
				( objectStatus "@baseboard_fab2_lib.baseboard_fab2(sch_1):page107_i444" )
			)
			( gate "C3P34"
				( objectStatus "@baseboard_fab2_lib.baseboard_fab2(sch_1):page107_i447" )
			)
			( gate "C3P41"
				( objectStatus "@baseboard_fab2_lib.baseboard_fab2(sch_1):page107_i448" )
			)
			( gate "C3P31"
				( objectStatus "@baseboard_fab2_lib.baseboard_fab2(sch_1):page107_i452" )
			)
			( gate "C3P38"
				( objectStatus "@baseboard_fab2_lib.baseboard_fab2(sch_1):page107_i455" )
			)
			( gate "R2U29"
				( objectStatus "@baseboard_fab2_lib.baseboard_fab2(sch_1):page107_i458" )
			)
			( gate "R2U27"
				( objectStatus "@baseboard_fab2_lib.baseboard_fab2(sch_1):page107_i459" )
			)
			( gate "R2U25"
				( objectStatus "@baseboard_fab2_lib.baseboard_fab2(sch_1):page107_i460" )
			)
			( gate "R2U23"
				( objectStatus "@baseboard_fab2_lib.baseboard_fab2(sch_1):page107_i461" )
			)
			( gate "R2U21"
				( objectStatus "@baseboard_fab2_lib.baseboard_fab2(sch_1):page107_i462" )
			)
			( gate "R2U19"
				( objectStatus "@baseboard_fab2_lib.baseboard_fab2(sch_1):page107_i463" )
			)
			( gate "R2U17"
				( objectStatus "@baseboard_fab2_lib.baseboard_fab2(sch_1):page107_i464" )
			)
			( gate "R2U15"
				( objectStatus "@baseboard_fab2_lib.baseboard_fab2(sch_1):page107_i465" )
			)
			( gate "R2U14"
				( objectStatus "@baseboard_fab2_lib.baseboard_fab2(sch_1):page107_i466" )
			)
			( gate "R2U16"
				( objectStatus "@baseboard_fab2_lib.baseboard_fab2(sch_1):page107_i467" )
			)
			( gate "R2U18"
				( objectStatus "@baseboard_fab2_lib.baseboard_fab2(sch_1):page107_i468" )
			)
			( gate "R2U20"
				( objectStatus "@baseboard_fab2_lib.baseboard_fab2(sch_1):page107_i469" )
			)
			( gate "R2U22"
				( objectStatus "@baseboard_fab2_lib.baseboard_fab2(sch_1):page107_i470" )
			)
			( gate "R2U24"
				( objectStatus "@baseboard_fab2_lib.baseboard_fab2(sch_1):page107_i471" )
			)
			( gate "R2U26"
				( objectStatus "@baseboard_fab2_lib.baseboard_fab2(sch_1):page107_i472" )
			)
			( gate "R2U28"
				( objectStatus "@baseboard_fab2_lib.baseboard_fab2(sch_1):page107_i473" )
			)
			( gate "C2U20"
				( objectStatus "@baseboard_fab2_lib.baseboard_fab2(sch_1):page108_i1" )
			)
			( gate "C2U24"
				( objectStatus "@baseboard_fab2_lib.baseboard_fab2(sch_1):page108_i2" )
			)
			( gate "C2U21"
				( objectStatus "@baseboard_fab2_lib.baseboard_fab2(sch_1):page108_i5" )
			)
			( gate "C2U25"
				( objectStatus "@baseboard_fab2_lib.baseboard_fab2(sch_1):page108_i7" )
			)
			( gate "R2U37"
				( objectStatus "@baseboard_fab2_lib.baseboard_fab2(sch_1):page108_i173" )
			)
			( gate "J8G1"
				( objectStatus "@baseboard_fab2_lib.baseboard_fab2(sch_1):page108_i258" )
			)
			( gate "C2U23"
				( objectStatus "@baseboard_fab2_lib.baseboard_fab2(sch_1):page108_i315" )
			)
			( gate "C2U22"
				( objectStatus "@baseboard_fab2_lib.baseboard_fab2(sch_1):page108_i318" )
			)
			( gate "R2U35"
				( objectStatus "@baseboard_fab2_lib.baseboard_fab2(sch_1):page108_i320" )
			)
			( gate "R2U31"
				( objectStatus "@baseboard_fab2_lib.baseboard_fab2(sch_1):page108_i330" )
			)
			( gate "R2U32"
				( objectStatus "@baseboard_fab2_lib.baseboard_fab2(sch_1):page108_i339" )
			)
			( gate "R2U36"
				( objectStatus "@baseboard_fab2_lib.baseboard_fab2(sch_1):page108_i340" )
			)
			( gate "R7E22"
				( objectStatus "@baseboard_fab2_lib.baseboard_fab2(sch_1):page108_i341" )
			)
			( gate "R7E21"
				( objectStatus "@baseboard_fab2_lib.baseboard_fab2(sch_1):page108_i343" )
			)
			( gate "TC9F1"
				( objectStatus "@baseboard_fab2_lib.baseboard_fab2(sch_1):page110_i1" )
			)
			( gate "TC1G1"
				( objectStatus "@baseboard_fab2_lib.baseboard_fab2(sch_1):page110_i3" )
			)
			( gate "TC1A1"
				( objectStatus "@baseboard_fab2_lib.baseboard_fab2(sch_1):page110_i7" )
			)
			( gate "TC9A1"
				( objectStatus "@baseboard_fab2_lib.baseboard_fab2(sch_1):page110_i9" )
			)
			( gate "LB2F1"
				( objectStatus "@baseboard_fab2_lib.baseboard_fab2(sch_1):page110_i11" )
			)
			( gate "LB5F1"
				( objectStatus "@baseboard_fab2_lib.baseboard_fab2(sch_1):page110_i12" )
			)
			( gate "LB2B1"
				( objectStatus "@baseboard_fab2_lib.baseboard_fab2(sch_1):page110_i13" )
			)
			( gate "LB5B1"
				( objectStatus "@baseboard_fab2_lib.baseboard_fab2(sch_1):page110_i14" )
			)
			( gate "LB6T1"
				( objectStatus "@baseboard_fab2_lib.baseboard_fab2(sch_1):page110_i15" )
			)
			( gate "R1L13"
				( objectStatus "@baseboard_fab2_lib.baseboard_fab2(sch_1):page111_i6" )
			)
			( gate "C9A2"
				( objectStatus "@baseboard_fab2_lib.baseboard_fab2(sch_1):page111_i10" )
			)
			( gate "R9A14"
				( objectStatus "@baseboard_fab2_lib.baseboard_fab2(sch_1):page111_i11" )
			)
			( gate "C9A5"
				( objectStatus "@baseboard_fab2_lib.baseboard_fab2(sch_1):page111_i12" )
			)
			( gate "R1L23"
				( objectStatus "@baseboard_fab2_lib.baseboard_fab2(sch_1):page111_i13" )
			)
			( gate "C1L8"
				( objectStatus "@baseboard_fab2_lib.baseboard_fab2(sch_1):page111_i14" )
			)
			( gate "C9A6"
				( objectStatus "@baseboard_fab2_lib.baseboard_fab2(sch_1):page111_i25" )
			)
			( gate "J9A3"
				( objectStatus "@baseboard_fab2_lib.baseboard_fab2(sch_1):page111_i26" )
			)
			( gate "C1L5"
				( objectStatus "@baseboard_fab2_lib.baseboard_fab2(sch_1):page111_i30" )
			)
			( gate "R2P2"
				( objectStatus "@baseboard_fab2_lib.baseboard_fab2(sch_1):page111_i37" )
			)
			( gate "R9A4"
				( objectStatus "@baseboard_fab2_lib.baseboard_fab2(sch_1):page111_i55" )
			)
			( gate "R1L17"
				( objectStatus "@baseboard_fab2_lib.baseboard_fab2(sch_1):page111_i56" )
			)
			( gate "R9A17"
				( objectStatus "@baseboard_fab2_lib.baseboard_fab2(sch_1):page111_i57" )
			)
			( gate "C9A4"
				( objectStatus "@baseboard_fab2_lib.baseboard_fab2(sch_1):page111_i59" )
			)
			( gate "R9A15"
				( objectStatus "@baseboard_fab2_lib.baseboard_fab2(sch_1):page111_i60" )
			)
			( gate "R1L28"
				( objectStatus "@baseboard_fab2_lib.baseboard_fab2(sch_1):page111_i66" )
			)
			( gate "R1L29"
				( objectStatus "@baseboard_fab2_lib.baseboard_fab2(sch_1):page111_i68" )
			)
			( gate "R9A3"
				( objectStatus "@baseboard_fab2_lib.baseboard_fab2(sch_1):page111_i74" )
			)
			( gate "R9A2"
				( objectStatus "@baseboard_fab2_lib.baseboard_fab2(sch_1):page111_i83" )
			)
			( gate "U1L4"
				( objectStatus "@baseboard_fab2_lib.baseboard_fab2(sch_1):page111_i85" )
			)
			( gate "C1L11"
				( objectStatus "@baseboard_fab2_lib.baseboard_fab2(sch_1):page111_i87" )
			)
			( gate "R8E2"
				( objectStatus "@baseboard_fab2_lib.baseboard_fab2(sch_1):page111_i89" )
			)
			( gate "Q9A1"
				( objectStatus "@baseboard_fab2_lib.baseboard_fab2(sch_1):page111_i93" )
			)
			( gate "Q9A1"
				( objectStatus "@baseboard_fab2_lib.baseboard_fab2(sch_1):page111_i94" )
			)
			( gate "R9A1"
				( objectStatus "@baseboard_fab2_lib.baseboard_fab2(sch_1):page111_i95" )
			)
			( gate "U1M7"
				( objectStatus "@baseboard_fab2_lib.baseboard_fab2(sch_1):page112_i40" )
			)
			( gate "C1M36"
				( objectStatus "@baseboard_fab2_lib.baseboard_fab2(sch_1):page112_i42" )
			)
			( gate "C1M37"
				( objectStatus "@baseboard_fab2_lib.baseboard_fab2(sch_1):page112_i47" )
			)
			( gate "R6P46"
				( objectStatus "@baseboard_fab2_lib.baseboard_fab2(sch_1):page112_i49" )
			)
			( gate "R7P30"
				( objectStatus "@baseboard_fab2_lib.baseboard_fab2(sch_1):page112_i50" )
			)
			( gate "R1M3"
				( objectStatus "@baseboard_fab2_lib.baseboard_fab2(sch_1):page112_i51" )
			)
			( gate "R4P15"
				( objectStatus "@baseboard_fab2_lib.baseboard_fab2(sch_1):page112_i53" )
			)
			( gate "R1M4"
				( objectStatus "@baseboard_fab2_lib.baseboard_fab2(sch_1):page112_i54" )
			)
			( gate "R6T7"
				( objectStatus "@baseboard_fab2_lib.baseboard_fab2(sch_1):page112_i55" )
			)
			( gate "R6T6"
				( objectStatus "@baseboard_fab2_lib.baseboard_fab2(sch_1):page112_i56" )
			)
			( gate "R4P12"
				( objectStatus "@baseboard_fab2_lib.baseboard_fab2(sch_1):page112_i57" )
			)
			( gate "R4P23"
				( objectStatus "@baseboard_fab2_lib.baseboard_fab2(sch_1):page112_i58" )
			)
			( gate "R4P24"
				( objectStatus "@baseboard_fab2_lib.baseboard_fab2(sch_1):page112_i59" )
			)
			( gate "R1L15"
				( objectStatus "@baseboard_fab2_lib.baseboard_fab2(sch_1):page112_i60" )
			)
			( gate "R7P29"
				( objectStatus "@baseboard_fab2_lib.baseboard_fab2(sch_1):page112_i61" )
			)
			( gate "R6T5"
				( objectStatus "@baseboard_fab2_lib.baseboard_fab2(sch_1):page112_i62" )
			)
			( gate "R1L39"
				( objectStatus "@baseboard_fab2_lib.baseboard_fab2(sch_1):page112_i76" )
			)
			( gate "R1L41"
				( objectStatus "@baseboard_fab2_lib.baseboard_fab2(sch_1):page112_i77" )
			)
			( gate "R9A11"
				( objectStatus "@baseboard_fab2_lib.baseboard_fab2(sch_1):page112_i78" )
			)
			( gate "R8A13"
				( objectStatus "@baseboard_fab2_lib.baseboard_fab2(sch_1):page112_i79" )
			)
			( gate "R8A14"
				( objectStatus "@baseboard_fab2_lib.baseboard_fab2(sch_1):page112_i80" )
			)
			( gate "R3M10"
				( objectStatus "@baseboard_fab2_lib.baseboard_fab2(sch_1):page112_i85" )
			)
			( gate "R8B2"
				( objectStatus "@baseboard_fab2_lib.baseboard_fab2(sch_1):page112_i94" )
			)
			( gate "R8B1"
				( objectStatus "@baseboard_fab2_lib.baseboard_fab2(sch_1):page112_i95" )
			)
			( gate "U1L1"
				( objectStatus "@baseboard_fab2_lib.baseboard_fab2(sch_1):page112_i108" )
			)
			( gate "U1L5"
				( objectStatus "@baseboard_fab2_lib.baseboard_fab2(sch_1):page112_i109" )
			)
			( gate "R6T9"
				( objectStatus "@baseboard_fab2_lib.baseboard_fab2(sch_1):page112_i120" )
			)
			( gate "R6T8"
				( objectStatus "@baseboard_fab2_lib.baseboard_fab2(sch_1):page112_i121" )
			)
			( gate "U1M4"
				( objectStatus "@baseboard_fab2_lib.baseboard_fab2(sch_1):page112_i127" )
			)
			( gate "C1M30"
				( objectStatus "@baseboard_fab2_lib.baseboard_fab2(sch_1):page112_i131" )
			)
			( gate "C1L1"
				( objectStatus "@baseboard_fab2_lib.baseboard_fab2(sch_1):page112_i136" )
			)
			( gate "C1L19"
				( objectStatus "@baseboard_fab2_lib.baseboard_fab2(sch_1):page112_i140" )
			)
			( gate "U1M2"
				( objectStatus "@baseboard_fab2_lib.baseboard_fab2(sch_1):page113_i107" )
			)
			( gate "C1M31"
				( objectStatus "@baseboard_fab2_lib.baseboard_fab2(sch_1):page113_i116" )
			)
			( gate "C1M32"
				( objectStatus "@baseboard_fab2_lib.baseboard_fab2(sch_1):page113_i117" )
			)
			( gate "C1M28"
				( objectStatus "@baseboard_fab2_lib.baseboard_fab2(sch_1):page113_i119" )
			)
			( gate "U1M6"
				( objectStatus "@baseboard_fab2_lib.baseboard_fab2(sch_1):page113_i127" )
			)
			( gate "R4R6"
				( objectStatus "@baseboard_fab2_lib.baseboard_fab2(sch_1):page113_i134" )
			)
			( gate "C1M29"
				( objectStatus "@baseboard_fab2_lib.baseboard_fab2(sch_1):page113_i147" )
			)
			( gate "R9B14"
				( objectStatus "@baseboard_fab2_lib.baseboard_fab2(sch_1):page113_i168" )
			)
			( gate "J9B4"
				( objectStatus "@baseboard_fab2_lib.baseboard_fab2(sch_1):page113_i175" )
			)
			( gate "R9B9"
				( objectStatus "@baseboard_fab2_lib.baseboard_fab2(sch_1):page113_i179" )
			)
			( gate "R9B10"
				( objectStatus "@baseboard_fab2_lib.baseboard_fab2(sch_1):page113_i180" )
			)
			( gate "U9A5"
				( objectStatus "@baseboard_fab2_lib.baseboard_fab2(sch_1):page113_i185" )
			)
			( gate "R6M8"
				( objectStatus "@baseboard_fab2_lib.baseboard_fab2(sch_1):page113_i188" )
			)
			( gate "U6M1"
				( objectStatus "@baseboard_fab2_lib.baseboard_fab2(sch_1):page113_i190" )
			)
			( gate "R1M22"
				( objectStatus "@baseboard_fab2_lib.baseboard_fab2(sch_1):page113_i195" )
			)
			( gate "U1M5"
				( objectStatus "@baseboard_fab2_lib.baseboard_fab2(sch_1):page113_i196" )
			)
			( gate "R1M23"
				( objectStatus "@baseboard_fab2_lib.baseboard_fab2(sch_1):page113_i199" )
			)
			( gate "R1M19"
				( objectStatus "@baseboard_fab2_lib.baseboard_fab2(sch_1):page113_i202" )
			)
			( gate "R9B12"
				( objectStatus "@baseboard_fab2_lib.baseboard_fab2(sch_1):page113_i203" )
			)
			( gate "R1M20"
				( objectStatus "@baseboard_fab2_lib.baseboard_fab2(sch_1):page113_i204" )
			)
			( gate "R1M21"
				( objectStatus "@baseboard_fab2_lib.baseboard_fab2(sch_1):page113_i205" )
			)
			( gate "U4R1"
				( objectStatus "@baseboard_fab2_lib.baseboard_fab2(sch_1):page113_i206" )
			)
			( gate "R9B11"
				( objectStatus "@baseboard_fab2_lib.baseboard_fab2(sch_1):page113_i239" )
			)
			( gate "R9B13"
				( objectStatus "@baseboard_fab2_lib.baseboard_fab2(sch_1):page113_i240" )
			)
			( gate "C4R2"
				( objectStatus "@baseboard_fab2_lib.baseboard_fab2(sch_1):page113_i246" )
			)
			( gate "C1M33"
				( objectStatus "@baseboard_fab2_lib.baseboard_fab2(sch_1):page113_i248" )
			)
			( gate "C6M6"
				( objectStatus "@baseboard_fab2_lib.baseboard_fab2(sch_1):page113_i250" )
			)
			( gate "U2M1"
				( objectStatus "@baseboard_fab2_lib.baseboard_fab2(sch_1):page113_i255" )
			)
			( gate "C1M34"
				( objectStatus "@baseboard_fab2_lib.baseboard_fab2(sch_1):page113_i265" )
			)
			( gate "C1M35"
				( objectStatus "@baseboard_fab2_lib.baseboard_fab2(sch_1):page113_i266" )
			)
			( gate "C1L20"
				( objectStatus "@baseboard_fab2_lib.baseboard_fab2(sch_1):page113_i267" )
			)
			( gate "U7C1"
				( objectStatus "@baseboard_fab2_lib.baseboard_fab2(sch_1):page114_i40" )
			)
			( gate "C7C15"
				( objectStatus "@baseboard_fab2_lib.baseboard_fab2(sch_1):page114_i46" )
			)
			( gate "C7C5"
				( objectStatus "@baseboard_fab2_lib.baseboard_fab2(sch_1):page114_i47" )
			)
			( gate "R7C1"
				( objectStatus "@baseboard_fab2_lib.baseboard_fab2(sch_1):page114_i48" )
			)
			( gate "Y7C1"
				( objectStatus "@baseboard_fab2_lib.baseboard_fab2(sch_1):page114_i49" )
			)
			( gate "C7C4"
				( objectStatus "@baseboard_fab2_lib.baseboard_fab2(sch_1):page114_i50" )
			)
			( gate "R7C6"
				( objectStatus "@baseboard_fab2_lib.baseboard_fab2(sch_1):page114_i54" )
			)
			( gate "Y7C2"
				( objectStatus "@baseboard_fab2_lib.baseboard_fab2(sch_1):page114_i55" )
			)
			( gate "C7C13"
				( objectStatus "@baseboard_fab2_lib.baseboard_fab2(sch_1):page114_i56" )
			)
			( gate "R8B20"
				( objectStatus "@baseboard_fab2_lib.baseboard_fab2(sch_1):page114_i110" )
			)
			( gate "R8B21"
				( objectStatus "@baseboard_fab2_lib.baseboard_fab2(sch_1):page114_i124" )
			)
			( gate "R7C2"
				( objectStatus "@baseboard_fab2_lib.baseboard_fab2(sch_1):page114_i141" )
			)
			( gate "R7C4"
				( objectStatus "@baseboard_fab2_lib.baseboard_fab2(sch_1):page114_i142" )
			)
			( gate "R3N1"
				( objectStatus "@baseboard_fab2_lib.baseboard_fab2(sch_1):page114_i149" )
			)
			( gate "U7C1"
				( objectStatus "@baseboard_fab2_lib.baseboard_fab2(sch_1):page115_i74" )
			)
			( gate "R8B9"
				( objectStatus "@baseboard_fab2_lib.baseboard_fab2(sch_1):page115_i90" )
			)
			( gate "R8B32"
				( objectStatus "@baseboard_fab2_lib.baseboard_fab2(sch_1):page115_i114" )
			)
			( gate "R3M11"
				( objectStatus "@baseboard_fab2_lib.baseboard_fab2(sch_1):page116_i108" )
			)
			( gate "R3M12"
				( objectStatus "@baseboard_fab2_lib.baseboard_fab2(sch_1):page116_i181" )
			)
			( gate "C2M4"
				( objectStatus "@baseboard_fab2_lib.baseboard_fab2(sch_1):page116_i182" )
			)
			( gate "C2M3"
				( objectStatus "@baseboard_fab2_lib.baseboard_fab2(sch_1):page116_i183" )
			)
			( gate "U7C1"
				( objectStatus "@baseboard_fab2_lib.baseboard_fab2(sch_1):page116_i220" )
			)
			( gate "R7B8"
				( objectStatus "@baseboard_fab2_lib.baseboard_fab2(sch_1):page116_i229" )
			)
			( gate "R7B7"
				( objectStatus "@baseboard_fab2_lib.baseboard_fab2(sch_1):page116_i230" )
			)
			( gate "R3M9"
				( objectStatus "@baseboard_fab2_lib.baseboard_fab2(sch_1):page116_i234" )
			)
			( gate "R3M8"
				( objectStatus "@baseboard_fab2_lib.baseboard_fab2(sch_1):page116_i235" )
			)
			( gate "U7C1"
				( objectStatus "@baseboard_fab2_lib.baseboard_fab2(sch_1):page117_i9" )
			)
			( gate "R3N9"
				( objectStatus "@baseboard_fab2_lib.baseboard_fab2(sch_1):page118_i66" )
			)
			( gate "R3N14"
				( objectStatus "@baseboard_fab2_lib.baseboard_fab2(sch_1):page118_i67" )
			)
			( gate "R3N13"
				( objectStatus "@baseboard_fab2_lib.baseboard_fab2(sch_1):page118_i71" )
			)
			( gate "U7C1"
				( objectStatus "@baseboard_fab2_lib.baseboard_fab2(sch_1):page118_i73" )
			)
			( gate "Y8C1"
				( objectStatus "@baseboard_fab2_lib.baseboard_fab2(sch_1):page118_i76" )
			)
			( gate "C8C2"
				( objectStatus "@baseboard_fab2_lib.baseboard_fab2(sch_1):page118_i77" )
			)
			( gate "C8C1"
				( objectStatus "@baseboard_fab2_lib.baseboard_fab2(sch_1):page118_i79" )
			)
			( gate "R2N4"
				( objectStatus "@baseboard_fab2_lib.baseboard_fab2(sch_1):page118_i96" )
			)
			( gate "R2M6"
				( objectStatus "@baseboard_fab2_lib.baseboard_fab2(sch_1):page118_i99" )
			)
			( gate "R8C24"
				( objectStatus "@baseboard_fab2_lib.baseboard_fab2(sch_1):page118_i120" )
			)
			( gate "R8C23"
				( objectStatus "@baseboard_fab2_lib.baseboard_fab2(sch_1):page118_i125" )
			)
			( gate "R2N6"
				( objectStatus "@baseboard_fab2_lib.baseboard_fab2(sch_1):page118_i128" )
			)
			( gate "R7D23"
				( objectStatus "@baseboard_fab2_lib.baseboard_fab2(sch_1):page118_i131" )
			)
			( gate "C7D1"
				( objectStatus "@baseboard_fab2_lib.baseboard_fab2(sch_1):page118_i136" )
			)
			( gate "U7D1"
				( objectStatus "@baseboard_fab2_lib.baseboard_fab2(sch_1):page118_i142" )
			)
			( gate "R7C23"
				( objectStatus "@baseboard_fab2_lib.baseboard_fab2(sch_1):page118_i144" )
			)
			( gate "U7C1"
				( objectStatus "@baseboard_fab2_lib.baseboard_fab2(sch_1):page119_i115" )
			)
			( gate "R2M3"
				( objectStatus "@baseboard_fab2_lib.baseboard_fab2(sch_1):page119_i172" )
			)
			( gate "R2N1"
				( objectStatus "@baseboard_fab2_lib.baseboard_fab2(sch_1):page119_i173" )
			)
			( gate "R2M7"
				( objectStatus "@baseboard_fab2_lib.baseboard_fab2(sch_1):page119_i174" )
			)
			( gate "Q9A2"
				( objectStatus "@baseboard_fab2_lib.baseboard_fab2(sch_1):page119_i175" )
			)
			( gate "R9A20"
				( objectStatus "@baseboard_fab2_lib.baseboard_fab2(sch_1):page119_i178" )
			)
			( gate "DS9A5"
				( objectStatus "@baseboard_fab2_lib.baseboard_fab2(sch_1):page119_i179" )
			)
			( gate "Q9A2"
				( objectStatus "@baseboard_fab2_lib.baseboard_fab2(sch_1):page119_i180" )
			)
			( gate "R9A18"
				( objectStatus "@baseboard_fab2_lib.baseboard_fab2(sch_1):page119_i183" )
			)
			( gate "R9A21"
				( objectStatus "@baseboard_fab2_lib.baseboard_fab2(sch_1):page119_i186" )
			)
			( gate "R7C26"
				( objectStatus "@baseboard_fab2_lib.baseboard_fab2(sch_1):page119_i189" )
			)
			( gate "R2U48"
				( objectStatus "@baseboard_fab2_lib.baseboard_fab2(sch_1):page119_i213" )
			)
			( gate "R2U50"
				( objectStatus "@baseboard_fab2_lib.baseboard_fab2(sch_1):page119_i215" )
			)
			( gate "U7C1"
				( objectStatus "@baseboard_fab2_lib.baseboard_fab2(sch_1):page120_i147" )
			)
			( gate "R8C21"
				( objectStatus "@baseboard_fab2_lib.baseboard_fab2(sch_1):page120_i148" )
			)
			( gate "R2M1"
				( objectStatus "@baseboard_fab2_lib.baseboard_fab2(sch_1):page120_i218" )
			)
			( gate "R2N26"
				( objectStatus "@baseboard_fab2_lib.baseboard_fab2(sch_1):page120_i219" )
			)
			( gate "R7C15"
				( objectStatus "@baseboard_fab2_lib.baseboard_fab2(sch_1):page121_i31" )
			)
			( gate "R7C16"
				( objectStatus "@baseboard_fab2_lib.baseboard_fab2(sch_1):page121_i33" )
			)
			( gate "U7C1"
				( objectStatus "@baseboard_fab2_lib.baseboard_fab2(sch_1):page121_i34" )
			)
			( gate "R8C26"
				( objectStatus "@baseboard_fab2_lib.baseboard_fab2(sch_1):page121_i35" )
			)
			( gate "R3N10"
				( objectStatus "@baseboard_fab2_lib.baseboard_fab2(sch_1):page121_i37" )
			)
			( gate "R7C20"
				( objectStatus "@baseboard_fab2_lib.baseboard_fab2(sch_1):page121_i73" )
			)
			( gate "R3P3"
				( objectStatus "@baseboard_fab2_lib.baseboard_fab2(sch_1):page121_i89" )
			)
			( gate "R3P2"
				( objectStatus "@baseboard_fab2_lib.baseboard_fab2(sch_1):page121_i90" )
			)
			( gate "R2P1"
				( objectStatus "@baseboard_fab2_lib.baseboard_fab2(sch_1):page121_i91" )
			)
			( gate "R7C14"
				( objectStatus "@baseboard_fab2_lib.baseboard_fab2(sch_1):page121_i98" )
			)
			( gate "R8D11"
				( objectStatus "@baseboard_fab2_lib.baseboard_fab2(sch_1):page121_i101" )
			)
			( gate "U7C1"
				( objectStatus "@baseboard_fab2_lib.baseboard_fab2(sch_1):page122_i63" )
			)
			( gate "U7C1"
				( objectStatus "@baseboard_fab2_lib.baseboard_fab2(sch_1):page123_i13" )
			)
			( gate "U7C1"
				( objectStatus "@baseboard_fab2_lib.baseboard_fab2(sch_1):page123_i21" )
			)
			( gate "U7C1"
				( objectStatus "@baseboard_fab2_lib.baseboard_fab2(sch_1):page124_i15" )
			)
			( gate "U7C1"
				( objectStatus "@baseboard_fab2_lib.baseboard_fab2(sch_1):page124_i16" )
			)
			( gate "U7C1"
				( objectStatus "@baseboard_fab2_lib.baseboard_fab2(sch_1):page124_i17" )
			)
			( gate "R2R11"
				( objectStatus "@baseboard_fab2_lib.baseboard_fab2(sch_1):page125_i11" )
			)
			( gate "R2T1"
				( objectStatus "@baseboard_fab2_lib.baseboard_fab2(sch_1):page125_i15" )
			)
			( gate "R8E6"
				( objectStatus "@baseboard_fab2_lib.baseboard_fab2(sch_1):page125_i21" )
			)
			( gate "R8E4"
				( objectStatus "@baseboard_fab2_lib.baseboard_fab2(sch_1):page125_i24" )
			)
			( gate "R8C18"
				( objectStatus "@baseboard_fab2_lib.baseboard_fab2(sch_1):page125_i40" )
			)
			( gate "R8C17"
				( objectStatus "@baseboard_fab2_lib.baseboard_fab2(sch_1):page125_i41" )
			)
			( gate "R8D5"
				( objectStatus "@baseboard_fab2_lib.baseboard_fab2(sch_1):page125_i50" )
			)
			( gate "R8D13"
				( objectStatus "@baseboard_fab2_lib.baseboard_fab2(sch_1):page125_i52" )
			)
			( gate "R7D13"
				( objectStatus "@baseboard_fab2_lib.baseboard_fab2(sch_1):page125_i60" )
			)
			( gate "R7D1"
				( objectStatus "@baseboard_fab2_lib.baseboard_fab2(sch_1):page125_i70" )
			)
			( gate "R8D16"
				( objectStatus "@baseboard_fab2_lib.baseboard_fab2(sch_1):page125_i71" )
			)
			( gate "R3N2"
				( objectStatus "@baseboard_fab2_lib.baseboard_fab2(sch_1):page125_i72" )
			)
			( gate "R2U30"
				( objectStatus "@baseboard_fab2_lib.baseboard_fab2(sch_1):page125_i76" )
			)
			( gate "R3N17"
				( objectStatus "@baseboard_fab2_lib.baseboard_fab2(sch_1):page125_i78" )
			)
			( gate "R2N14"
				( objectStatus "@baseboard_fab2_lib.baseboard_fab2(sch_1):page125_i83" )
			)
			( gate "R7D19"
				( objectStatus "@baseboard_fab2_lib.baseboard_fab2(sch_1):page126_i6" )
			)
			( gate "R2N10"
				( objectStatus "@baseboard_fab2_lib.baseboard_fab2(sch_1):page126_i10" )
			)
			( gate "R1D35"
				( objectStatus "@baseboard_fab2_lib.baseboard_fab2(sch_1):page126_i12" )
			)
			( gate "Q8E2"
				( objectStatus "@baseboard_fab2_lib.baseboard_fab2(sch_1):page126_i13" )
			)
			( gate "R8C9"
				( objectStatus "@baseboard_fab2_lib.baseboard_fab2(sch_1):page126_i20" )
			)
			( gate "R3P62"
				( objectStatus "@baseboard_fab2_lib.baseboard_fab2(sch_1):page126_i22" )
			)
			( gate "R3P64"
				( objectStatus "@baseboard_fab2_lib.baseboard_fab2(sch_1):page126_i23" )
			)
			( gate "FB3M1"
				( objectStatus "@baseboard_fab2_lib.baseboard_fab2(sch_1):page127_i8" )
			)
			( gate "C3M21"
				( objectStatus "@baseboard_fab2_lib.baseboard_fab2(sch_1):page127_i9" )
			)
			( gate "FB3M2"
				( objectStatus "@baseboard_fab2_lib.baseboard_fab2(sch_1):page127_i17" )
			)
			( gate "C3M22"
				( objectStatus "@baseboard_fab2_lib.baseboard_fab2(sch_1):page127_i18" )
			)
			( gate "FB3M3"
				( objectStatus "@baseboard_fab2_lib.baseboard_fab2(sch_1):page127_i26" )
			)
			( gate "C3M30"
				( objectStatus "@baseboard_fab2_lib.baseboard_fab2(sch_1):page127_i27" )
			)
			( gate "C2M5"
				( objectStatus "@baseboard_fab2_lib.baseboard_fab2(sch_1):page127_i43" )
			)
			( gate "C2M7"
				( objectStatus "@baseboard_fab2_lib.baseboard_fab2(sch_1):page127_i44" )
			)
			( gate "FB2M1"
				( objectStatus "@baseboard_fab2_lib.baseboard_fab2(sch_1):page127_i46" )
			)
			( gate "C2M10"
				( objectStatus "@baseboard_fab2_lib.baseboard_fab2(sch_1):page127_i49" )
			)
			( gate "C2M9"
				( objectStatus "@baseboard_fab2_lib.baseboard_fab2(sch_1):page127_i50" )
			)
			( gate "FB3M4"
				( objectStatus "@baseboard_fab2_lib.baseboard_fab2(sch_1):page127_i56" )
			)
			( gate "C3M31"
				( objectStatus "@baseboard_fab2_lib.baseboard_fab2(sch_1):page127_i57" )
			)
			( gate "C2N6"
				( objectStatus "@baseboard_fab2_lib.baseboard_fab2(sch_1):page127_i64" )
			)
			( gate "C2N5"
				( objectStatus "@baseboard_fab2_lib.baseboard_fab2(sch_1):page127_i65" )
			)
			( gate "FB2M2"
				( objectStatus "@baseboard_fab2_lib.baseboard_fab2(sch_1):page127_i69" )
			)
			( gate "L2M1"
				( objectStatus "@baseboard_fab2_lib.baseboard_fab2(sch_1):page127_i71" )
			)
			( gate "C2M8"
				( objectStatus "@baseboard_fab2_lib.baseboard_fab2(sch_1):page127_i74" )
			)
			( gate "C2M6"
				( objectStatus "@baseboard_fab2_lib.baseboard_fab2(sch_1):page127_i76" )
			)
			( gate "C2M25"
				( objectStatus "@baseboard_fab2_lib.baseboard_fab2(sch_1):page127_i78" )
			)
			( gate "C3M29"
				( objectStatus "@baseboard_fab2_lib.baseboard_fab2(sch_1):page127_i80" )
			)
			( gate "C3M24"
				( objectStatus "@baseboard_fab2_lib.baseboard_fab2(sch_1):page127_i81" )
			)
			( gate "C3M23"
				( objectStatus "@baseboard_fab2_lib.baseboard_fab2(sch_1):page127_i82" )
			)
			( gate "C3M27"
				( objectStatus "@baseboard_fab2_lib.baseboard_fab2(sch_1):page127_i83" )
			)
			( gate "C3M20"
				( objectStatus "@baseboard_fab2_lib.baseboard_fab2(sch_1):page127_i84" )
			)
			( gate "C3M18"
				( objectStatus "@baseboard_fab2_lib.baseboard_fab2(sch_1):page127_i85" )
			)
			( gate "C3M17"
				( objectStatus "@baseboard_fab2_lib.baseboard_fab2(sch_1):page127_i86" )
			)
			( gate "C3M19"
				( objectStatus "@baseboard_fab2_lib.baseboard_fab2(sch_1):page127_i87" )
			)
			( gate "C7B25"
				( objectStatus "@baseboard_fab2_lib.baseboard_fab2(sch_1):page129_i35" )
			)
			( gate "C7B27"
				( objectStatus "@baseboard_fab2_lib.baseboard_fab2(sch_1):page129_i69" )
			)
			( gate "C7B28"
				( objectStatus "@baseboard_fab2_lib.baseboard_fab2(sch_1):page129_i70" )
			)
			( gate "C7C2"
				( objectStatus "@baseboard_fab2_lib.baseboard_fab2(sch_1):page129_i71" )
			)
			( gate "C3M40"
				( objectStatus "@baseboard_fab2_lib.baseboard_fab2(sch_1):page129_i72" )
			)
			( gate "C3M37"
				( objectStatus "@baseboard_fab2_lib.baseboard_fab2(sch_1):page129_i73" )
			)
			( gate "C3N9"
				( objectStatus "@baseboard_fab2_lib.baseboard_fab2(sch_1):page129_i74" )
			)
			( gate "C3N8"
				( objectStatus "@baseboard_fab2_lib.baseboard_fab2(sch_1):page129_i75" )
			)
			( gate "C7C3"
				( objectStatus "@baseboard_fab2_lib.baseboard_fab2(sch_1):page129_i76" )
			)
			( gate "C7C1"
				( objectStatus "@baseboard_fab2_lib.baseboard_fab2(sch_1):page129_i77" )
			)
			( gate "C7B29"
				( objectStatus "@baseboard_fab2_lib.baseboard_fab2(sch_1):page129_i78" )
			)
			( gate "C7B26"
				( objectStatus "@baseboard_fab2_lib.baseboard_fab2(sch_1):page129_i79" )
			)
			( gate "C3M44"
				( objectStatus "@baseboard_fab2_lib.baseboard_fab2(sch_1):page129_i80" )
			)
			( gate "C3M41"
				( objectStatus "@baseboard_fab2_lib.baseboard_fab2(sch_1):page129_i81" )
			)
			( gate "C3M45"
				( objectStatus "@baseboard_fab2_lib.baseboard_fab2(sch_1):page129_i82" )
			)
			( gate "C3N13"
				( objectStatus "@baseboard_fab2_lib.baseboard_fab2(sch_1):page129_i83" )
			)
			( gate "C7D2"
				( objectStatus "@baseboard_fab2_lib.baseboard_fab2(sch_1):page130_i2" )
			)
			( gate "C2N26"
				( objectStatus "@baseboard_fab2_lib.baseboard_fab2(sch_1):page130_i4" )
			)
			( gate "C2N19"
				( objectStatus "@baseboard_fab2_lib.baseboard_fab2(sch_1):page130_i7" )
			)
			( gate "C2N24"
				( objectStatus "@baseboard_fab2_lib.baseboard_fab2(sch_1):page130_i8" )
			)
			( gate "C2N22"
				( objectStatus "@baseboard_fab2_lib.baseboard_fab2(sch_1):page130_i9" )
			)
			( gate "C2N20"
				( objectStatus "@baseboard_fab2_lib.baseboard_fab2(sch_1):page130_i12" )
			)
			( gate "C2N21"
				( objectStatus "@baseboard_fab2_lib.baseboard_fab2(sch_1):page130_i15" )
			)
			( gate "C3N29"
				( objectStatus "@baseboard_fab2_lib.baseboard_fab2(sch_1):page130_i16" )
			)
			( gate "C8C3"
				( objectStatus "@baseboard_fab2_lib.baseboard_fab2(sch_1):page130_i19" )
			)
			( gate "C8C4"
				( objectStatus "@baseboard_fab2_lib.baseboard_fab2(sch_1):page130_i20" )
			)
			( gate "C8C5"
				( objectStatus "@baseboard_fab2_lib.baseboard_fab2(sch_1):page130_i21" )
			)
			( gate "C8C6"
				( objectStatus "@baseboard_fab2_lib.baseboard_fab2(sch_1):page130_i22" )
			)
			( gate "C2N23"
				( objectStatus "@baseboard_fab2_lib.baseboard_fab2(sch_1):page130_i24" )
			)
			( gate "C2N14"
				( objectStatus "@baseboard_fab2_lib.baseboard_fab2(sch_1):page130_i25" )
			)
			( gate "C2N17"
				( objectStatus "@baseboard_fab2_lib.baseboard_fab2(sch_1):page130_i28" )
			)
			( gate "C2N18"
				( objectStatus "@baseboard_fab2_lib.baseboard_fab2(sch_1):page130_i29" )
			)
			( gate "C8B2"
				( objectStatus "@baseboard_fab2_lib.baseboard_fab2(sch_1):page130_i30" )
			)
			( gate "C8B3"
				( objectStatus "@baseboard_fab2_lib.baseboard_fab2(sch_1):page130_i32" )
			)
			( gate "C2N25"
				( objectStatus "@baseboard_fab2_lib.baseboard_fab2(sch_1):page130_i34" )
			)
			( gate "C2M16"
				( objectStatus "@baseboard_fab2_lib.baseboard_fab2(sch_1):page130_i37" )
			)
			( gate "C7D3"
				( objectStatus "@baseboard_fab2_lib.baseboard_fab2(sch_1):page130_i38" )
			)
			( gate "C8B4"
				( objectStatus "@baseboard_fab2_lib.baseboard_fab2(sch_1):page130_i39" )
			)
			( gate "C8B1"
				( objectStatus "@baseboard_fab2_lib.baseboard_fab2(sch_1):page130_i41" )
			)
			( gate "C3N23"
				( objectStatus "@baseboard_fab2_lib.baseboard_fab2(sch_1):page130_i42" )
			)
			( gate "C2M1"
				( objectStatus "@baseboard_fab2_lib.baseboard_fab2(sch_1):page130_i43" )
			)
			( gate "C2M2"
				( objectStatus "@baseboard_fab2_lib.baseboard_fab2(sch_1):page130_i45" )
			)
			( gate "C2N15"
				( objectStatus "@baseboard_fab2_lib.baseboard_fab2(sch_1):page130_i47" )
			)
			( gate "C3N21"
				( objectStatus "@baseboard_fab2_lib.baseboard_fab2(sch_1):page130_i49" )
			)
			( gate "C3N25"
				( objectStatus "@baseboard_fab2_lib.baseboard_fab2(sch_1):page130_i50" )
			)
			( gate "C2N16"
				( objectStatus "@baseboard_fab2_lib.baseboard_fab2(sch_1):page130_i52" )
			)
			( gate "C3N22"
				( objectStatus "@baseboard_fab2_lib.baseboard_fab2(sch_1):page130_i53" )
			)
			( gate "C7B15"
				( objectStatus "@baseboard_fab2_lib.baseboard_fab2(sch_1):page131_i1" )
			)
			( gate "C7B19"
				( objectStatus "@baseboard_fab2_lib.baseboard_fab2(sch_1):page131_i2" )
			)
			( gate "C7B16"
				( objectStatus "@baseboard_fab2_lib.baseboard_fab2(sch_1):page131_i3" )
			)
			( gate "C7B21"
				( objectStatus "@baseboard_fab2_lib.baseboard_fab2(sch_1):page131_i4" )
			)
			( gate "C7B20"
				( objectStatus "@baseboard_fab2_lib.baseboard_fab2(sch_1):page131_i6" )
			)
			( gate "C7B23"
				( objectStatus "@baseboard_fab2_lib.baseboard_fab2(sch_1):page131_i7" )
			)
			( gate "C8B10"
				( objectStatus "@baseboard_fab2_lib.baseboard_fab2(sch_1):page131_i8" )
			)
			( gate "C7B22"
				( objectStatus "@baseboard_fab2_lib.baseboard_fab2(sch_1):page131_i10" )
			)
			( gate "C7B24"
				( objectStatus "@baseboard_fab2_lib.baseboard_fab2(sch_1):page131_i11" )
			)
			( gate "C7B18"
				( objectStatus "@baseboard_fab2_lib.baseboard_fab2(sch_1):page131_i12" )
			)
			( gate "C8B9"
				( objectStatus "@baseboard_fab2_lib.baseboard_fab2(sch_1):page131_i14" )
			)
			( gate "C8B11"
				( objectStatus "@baseboard_fab2_lib.baseboard_fab2(sch_1):page131_i15" )
			)
			( gate "C8B14"
				( objectStatus "@baseboard_fab2_lib.baseboard_fab2(sch_1):page131_i16" )
			)
			( gate "C7B17"
				( objectStatus "@baseboard_fab2_lib.baseboard_fab2(sch_1):page131_i18" )
			)
			( gate "C8B13"
				( objectStatus "@baseboard_fab2_lib.baseboard_fab2(sch_1):page131_i20" )
			)
			( gate "C8B16"
				( objectStatus "@baseboard_fab2_lib.baseboard_fab2(sch_1):page131_i22" )
			)
			( gate "C8B15"
				( objectStatus "@baseboard_fab2_lib.baseboard_fab2(sch_1):page131_i24" )
			)
			( gate "C2M22"
				( objectStatus "@baseboard_fab2_lib.baseboard_fab2(sch_1):page131_i27" )
			)
			( gate "C2M21"
				( objectStatus "@baseboard_fab2_lib.baseboard_fab2(sch_1):page131_i28" )
			)
			( gate "C2M18"
				( objectStatus "@baseboard_fab2_lib.baseboard_fab2(sch_1):page131_i29" )
			)
			( gate "C2M19"
				( objectStatus "@baseboard_fab2_lib.baseboard_fab2(sch_1):page131_i31" )
			)
			( gate "C3M38"
				( objectStatus "@baseboard_fab2_lib.baseboard_fab2(sch_1):page131_i32" )
			)
			( gate "C2M17"
				( objectStatus "@baseboard_fab2_lib.baseboard_fab2(sch_1):page131_i34" )
			)
			( gate "C2M11"
				( objectStatus "@baseboard_fab2_lib.baseboard_fab2(sch_1):page131_i35" )
			)
			( gate "C8A13"
				( objectStatus "@baseboard_fab2_lib.baseboard_fab2(sch_1):page131_i37" )
			)
			( gate "C2M20"
				( objectStatus "@baseboard_fab2_lib.baseboard_fab2(sch_1):page131_i39" )
			)
			( gate "C2N13"
				( objectStatus "@baseboard_fab2_lib.baseboard_fab2(sch_1):page131_i40" )
			)
			( gate "C2N2"
				( objectStatus "@baseboard_fab2_lib.baseboard_fab2(sch_1):page131_i41" )
			)
			( gate "C3M43"
				( objectStatus "@baseboard_fab2_lib.baseboard_fab2(sch_1):page131_i42" )
			)
			( gate "C2N7"
				( objectStatus "@baseboard_fab2_lib.baseboard_fab2(sch_1):page131_i43" )
			)
			( gate "C3M39"
				( objectStatus "@baseboard_fab2_lib.baseboard_fab2(sch_1):page131_i44" )
			)
			( gate "C3M42"
				( objectStatus "@baseboard_fab2_lib.baseboard_fab2(sch_1):page131_i45" )
			)
			( gate "C2N8"
				( objectStatus "@baseboard_fab2_lib.baseboard_fab2(sch_1):page131_i47" )
			)
			( gate "C2M13"
				( objectStatus "@baseboard_fab2_lib.baseboard_fab2(sch_1):page131_i48" )
			)
			( gate "C2N10"
				( objectStatus "@baseboard_fab2_lib.baseboard_fab2(sch_1):page131_i50" )
			)
			( gate "C2M12"
				( objectStatus "@baseboard_fab2_lib.baseboard_fab2(sch_1):page131_i52" )
			)
			( gate "C3L25"
				( objectStatus "@baseboard_fab2_lib.baseboard_fab2(sch_1):page132_i1" )
			)
			( gate "C3M7"
				( objectStatus "@baseboard_fab2_lib.baseboard_fab2(sch_1):page132_i2" )
			)
			( gate "C3L26"
				( objectStatus "@baseboard_fab2_lib.baseboard_fab2(sch_1):page132_i3" )
			)
			( gate "C3L27"
				( objectStatus "@baseboard_fab2_lib.baseboard_fab2(sch_1):page132_i4" )
			)
			( gate "C3M6"
				( objectStatus "@baseboard_fab2_lib.baseboard_fab2(sch_1):page132_i6" )
			)
			( gate "C7C9"
				( objectStatus "@baseboard_fab2_lib.baseboard_fab2(sch_1):page132_i7" )
			)
			( gate "C3N27"
				( objectStatus "@baseboard_fab2_lib.baseboard_fab2(sch_1):page132_i8" )
			)
			( gate "C3N30"
				( objectStatus "@baseboard_fab2_lib.baseboard_fab2(sch_1):page132_i9" )
			)
			( gate "C7A36"
				( objectStatus "@baseboard_fab2_lib.baseboard_fab2(sch_1):page132_i11" )
			)
			( gate "C3N12"
				( objectStatus "@baseboard_fab2_lib.baseboard_fab2(sch_1):page132_i12" )
			)
			( gate "C3N10"
				( objectStatus "@baseboard_fab2_lib.baseboard_fab2(sch_1):page132_i13" )
			)
			( gate "C3N24"
				( objectStatus "@baseboard_fab2_lib.baseboard_fab2(sch_1):page132_i16" )
			)
			( gate "C3N28"
				( objectStatus "@baseboard_fab2_lib.baseboard_fab2(sch_1):page132_i17" )
			)
			( gate "C3N11"
				( objectStatus "@baseboard_fab2_lib.baseboard_fab2(sch_1):page132_i19" )
			)
			( gate "C3N31"
				( objectStatus "@baseboard_fab2_lib.baseboard_fab2(sch_1):page132_i20" )
			)
			( gate "C7A33"
				( objectStatus "@baseboard_fab2_lib.baseboard_fab2(sch_1):page132_i23" )
			)
			( gate "C7B4"
				( objectStatus "@baseboard_fab2_lib.baseboard_fab2(sch_1):page132_i24" )
			)
			( gate "C2N9"
				( objectStatus "@baseboard_fab2_lib.baseboard_fab2(sch_1):page132_i26" )
			)
			( gate "C2N3"
				( objectStatus "@baseboard_fab2_lib.baseboard_fab2(sch_1):page132_i27" )
			)
			( gate "C2N4"
				( objectStatus "@baseboard_fab2_lib.baseboard_fab2(sch_1):page132_i28" )
			)
			( gate "C2N12"
				( objectStatus "@baseboard_fab2_lib.baseboard_fab2(sch_1):page132_i29" )
			)
			( gate "C2N11"
				( objectStatus "@baseboard_fab2_lib.baseboard_fab2(sch_1):page132_i30" )
			)
			( gate "C3N19"
				( objectStatus "@baseboard_fab2_lib.baseboard_fab2(sch_1):page132_i31" )
			)
			( gate "C3N3"
				( objectStatus "@baseboard_fab2_lib.baseboard_fab2(sch_1):page132_i32" )
			)
			( gate "C3N1"
				( objectStatus "@baseboard_fab2_lib.baseboard_fab2(sch_1):page132_i34" )
			)
			( gate "C3N7"
				( objectStatus "@baseboard_fab2_lib.baseboard_fab2(sch_1):page132_i35" )
			)
			( gate "C3N16"
				( objectStatus "@baseboard_fab2_lib.baseboard_fab2(sch_1):page132_i36" )
			)
			( gate "C7A32"
				( objectStatus "@baseboard_fab2_lib.baseboard_fab2(sch_1):page132_i38" )
			)
			( gate "C7A31"
				( objectStatus "@baseboard_fab2_lib.baseboard_fab2(sch_1):page132_i40" )
			)
			( gate "C3N18"
				( objectStatus "@baseboard_fab2_lib.baseboard_fab2(sch_1):page132_i42" )
			)
			( gate "C3N2"
				( objectStatus "@baseboard_fab2_lib.baseboard_fab2(sch_1):page132_i43" )
			)
			( gate "C3N6"
				( objectStatus "@baseboard_fab2_lib.baseboard_fab2(sch_1):page132_i44" )
			)
			( gate "C3N17"
				( objectStatus "@baseboard_fab2_lib.baseboard_fab2(sch_1):page132_i45" )
			)
			( gate "C3N4"
				( objectStatus "@baseboard_fab2_lib.baseboard_fab2(sch_1):page132_i46" )
			)
			( gate "C3N5"
				( objectStatus "@baseboard_fab2_lib.baseboard_fab2(sch_1):page132_i48" )
			)
			( gate "C3N15"
				( objectStatus "@baseboard_fab2_lib.baseboard_fab2(sch_1):page132_i49" )
			)
			( gate "C3N20"
				( objectStatus "@baseboard_fab2_lib.baseboard_fab2(sch_1):page132_i51" )
			)
			( gate "C3L23"
				( objectStatus "@baseboard_fab2_lib.baseboard_fab2(sch_1):page132_i52" )
			)
			( gate "C3L22"
				( objectStatus "@baseboard_fab2_lib.baseboard_fab2(sch_1):page132_i54" )
			)
			( gate "C3L24"
				( objectStatus "@baseboard_fab2_lib.baseboard_fab2(sch_1):page132_i56" )
			)
			( gate "R3N3"
				( objectStatus "@baseboard_fab2_lib.baseboard_fab2(sch_1):page133_i120" )
			)
			( gate "R2N12"
				( objectStatus "@baseboard_fab2_lib.baseboard_fab2(sch_1):page133_i122" )
			)
			( gate "R7D8"
				( objectStatus "@baseboard_fab2_lib.baseboard_fab2(sch_1):page133_i200" )
			)
			( gate "R7D10"
				( objectStatus "@baseboard_fab2_lib.baseboard_fab2(sch_1):page133_i202" )
			)
			( gate "R7D12"
				( objectStatus "@baseboard_fab2_lib.baseboard_fab2(sch_1):page133_i237" )
			)
			( gate "R7D3"
				( objectStatus "@baseboard_fab2_lib.baseboard_fab2(sch_1):page133_i243" )
			)
			( gate "R7D4"
				( objectStatus "@baseboard_fab2_lib.baseboard_fab2(sch_1):page133_i245" )
			)
			( gate "R2N16"
				( objectStatus "@baseboard_fab2_lib.baseboard_fab2(sch_1):page133_i247" )
			)
			( gate "R2R5"
				( objectStatus "@baseboard_fab2_lib.baseboard_fab2(sch_1):page133_i258" )
			)
			( gate "R2N9"
				( objectStatus "@baseboard_fab2_lib.baseboard_fab2(sch_1):page133_i267" )
			)
			( gate "R8B23"
				( objectStatus "@baseboard_fab2_lib.baseboard_fab2(sch_1):page133_i280" )
			)
			( gate "R8B30"
				( objectStatus "@baseboard_fab2_lib.baseboard_fab2(sch_1):page133_i282" )
			)
			( gate "R2M4"
				( objectStatus "@baseboard_fab2_lib.baseboard_fab2(sch_1):page133_i284" )
			)
			( gate "R8C4"
				( objectStatus "@baseboard_fab2_lib.baseboard_fab2(sch_1):page133_i286" )
			)
			( gate "R7B6"
				( objectStatus "@baseboard_fab2_lib.baseboard_fab2(sch_1):page133_i295" )
			)
			( gate "R7C8"
				( objectStatus "@baseboard_fab2_lib.baseboard_fab2(sch_1):page133_i296" )
			)
			( gate "R7C5"
				( objectStatus "@baseboard_fab2_lib.baseboard_fab2(sch_1):page133_i297" )
			)
			( gate "R8D14"
				( objectStatus "@baseboard_fab2_lib.baseboard_fab2(sch_1):page133_i301" )
			)
			( gate "R8C6"
				( objectStatus "@baseboard_fab2_lib.baseboard_fab2(sch_1):page133_i303" )
			)
			( gate "R8C2"
				( objectStatus "@baseboard_fab2_lib.baseboard_fab2(sch_1):page133_i304" )
			)
			( gate "R7D6"
				( objectStatus "@baseboard_fab2_lib.baseboard_fab2(sch_1):page133_i306" )
			)
			( gate "R8B31"
				( objectStatus "@baseboard_fab2_lib.baseboard_fab2(sch_1):page133_i307" )
			)
			( gate "R2N7"
				( objectStatus "@baseboard_fab2_lib.baseboard_fab2(sch_1):page133_i309" )
			)
			( gate "R3P7"
				( objectStatus "@baseboard_fab2_lib.baseboard_fab2(sch_1):page133_i315" )
			)
			( gate "R3P5"
				( objectStatus "@baseboard_fab2_lib.baseboard_fab2(sch_1):page133_i316" )
			)
			( gate "R3P6"
				( objectStatus "@baseboard_fab2_lib.baseboard_fab2(sch_1):page133_i317" )
			)
			( gate "R3N15"
				( objectStatus "@baseboard_fab2_lib.baseboard_fab2(sch_1):page133_i318" )
			)
			( gate "R3N16"
				( objectStatus "@baseboard_fab2_lib.baseboard_fab2(sch_1):page133_i321" )
			)
			( gate "R3P8"
				( objectStatus "@baseboard_fab2_lib.baseboard_fab2(sch_1):page133_i322" )
			)
			( gate "R8C1"
				( objectStatus "@baseboard_fab2_lib.baseboard_fab2(sch_1):page133_i326" )
			)
			( gate "R8C7"
				( objectStatus "@baseboard_fab2_lib.baseboard_fab2(sch_1):page133_i327" )
			)
			( gate "R7D7"
				( objectStatus "@baseboard_fab2_lib.baseboard_fab2(sch_1):page133_i331" )
			)
			( gate "R7D2"
				( objectStatus "@baseboard_fab2_lib.baseboard_fab2(sch_1):page133_i332" )
			)
			( gate "R8C25"
				( objectStatus "@baseboard_fab2_lib.baseboard_fab2(sch_1):page133_i333" )
			)
			( gate "R2N32"
				( objectStatus "@baseboard_fab2_lib.baseboard_fab2(sch_1):page133_i341" )
			)
			( gate "R2M8"
				( objectStatus "@baseboard_fab2_lib.baseboard_fab2(sch_1):page133_i349" )
			)
			( gate "R2N29"
				( objectStatus "@baseboard_fab2_lib.baseboard_fab2(sch_1):page133_i352" )
			)
			( gate "R8E3"
				( objectStatus "@baseboard_fab2_lib.baseboard_fab2(sch_1):page133_i355" )
			)
			( gate "R7D44"
				( objectStatus "@baseboard_fab2_lib.baseboard_fab2(sch_1):page133_i356" )
			)
			( gate "R3P53"
				( objectStatus "@baseboard_fab2_lib.baseboard_fab2(sch_1):page133_i357" )
			)
			( gate "R2P22"
				( objectStatus "@baseboard_fab2_lib.baseboard_fab2(sch_1):page133_i360" )
			)
			( gate "R8D44"
				( objectStatus "@baseboard_fab2_lib.baseboard_fab2(sch_1):page133_i362" )
			)
			( gate "R2P17"
				( objectStatus "@baseboard_fab2_lib.baseboard_fab2(sch_1):page134_i3" )
			)
			( gate "Q8D2"
				( objectStatus "@baseboard_fab2_lib.baseboard_fab2(sch_1):page134_i4" )
			)
			( gate "R7C21"
				( objectStatus "@baseboard_fab2_lib.baseboard_fab2(sch_1):page134_i9" )
			)
			( gate "Q7D1"
				( objectStatus "@baseboard_fab2_lib.baseboard_fab2(sch_1):page134_i10" )
			)
			( gate "R7D18"
				( objectStatus "@baseboard_fab2_lib.baseboard_fab2(sch_1):page134_i11" )
			)
			( gate "R2P19"
				( objectStatus "@baseboard_fab2_lib.baseboard_fab2(sch_1):page135_i107" )
			)
			( gate "R2N23"
				( objectStatus "@baseboard_fab2_lib.baseboard_fab2(sch_1):page135_i112" )
			)
			( gate "R2N24"
				( objectStatus "@baseboard_fab2_lib.baseboard_fab2(sch_1):page135_i113" )
			)
			( gate "R9A12"
				( objectStatus "@baseboard_fab2_lib.baseboard_fab2(sch_1):page135_i117" )
			)
			( gate "R9A13"
				( objectStatus "@baseboard_fab2_lib.baseboard_fab2(sch_1):page135_i118" )
			)
			( gate "R8D21"
				( objectStatus "@baseboard_fab2_lib.baseboard_fab2(sch_1):page135_i120" )
			)
			( gate "R7D30"
				( objectStatus "@baseboard_fab2_lib.baseboard_fab2(sch_1):page135_i121" )
			)
			( gate "J8G2"
				( objectStatus "@baseboard_fab2_lib.baseboard_fab2(sch_1):page135_i124" )
			)
			( gate "R9A16"
				( objectStatus "@baseboard_fab2_lib.baseboard_fab2(sch_1):page135_i129" )
			)
			( gate "J9A1"
				( objectStatus "@baseboard_fab2_lib.baseboard_fab2(sch_1):page135_i131" )
			)
			( gate "R7G26"
				( objectStatus "@baseboard_fab2_lib.baseboard_fab2(sch_1):page136_i101" )
			)
			( gate "R7G28"
				( objectStatus "@baseboard_fab2_lib.baseboard_fab2(sch_1):page136_i102" )
			)
			( gate "R8E20"
				( objectStatus "@baseboard_fab2_lib.baseboard_fab2(sch_1):page136_i126" )
			)
			( gate "C8E8"
				( objectStatus "@baseboard_fab2_lib.baseboard_fab2(sch_1):page136_i128" )
			)
			( gate "U8E3"
				( objectStatus "@baseboard_fab2_lib.baseboard_fab2(sch_1):page136_i130" )
			)
			( gate "R8E14"
				( objectStatus "@baseboard_fab2_lib.baseboard_fab2(sch_1):page136_i133" )
			)
			( gate "Q8E1"
				( objectStatus "@baseboard_fab2_lib.baseboard_fab2(sch_1):page136_i134" )
			)
			( gate "R7G31"
				( objectStatus "@baseboard_fab2_lib.baseboard_fab2(sch_1):page136_i139" )
			)
			( gate "R8E16"
				( objectStatus "@baseboard_fab2_lib.baseboard_fab2(sch_1):page136_i140" )
			)
			( gate "R2N28"
				( objectStatus "@baseboard_fab2_lib.baseboard_fab2(sch_1):page136_i147" )
			)
			( gate "R7G29"
				( objectStatus "@baseboard_fab2_lib.baseboard_fab2(sch_1):page136_i148" )
			)
			( gate "R7G27"
				( objectStatus "@baseboard_fab2_lib.baseboard_fab2(sch_1):page136_i155" )
			)
			( gate "R3T14"
				( objectStatus "@baseboard_fab2_lib.baseboard_fab2(sch_1):page136_i156" )
			)
			( gate "J7G3"
				( objectStatus "@baseboard_fab2_lib.baseboard_fab2(sch_1):page136_i174" )
			)
			( gate "R7C11"
				( objectStatus "@baseboard_fab2_lib.baseboard_fab2(sch_1):page137_i11" )
			)
			( gate "R7C10"
				( objectStatus "@baseboard_fab2_lib.baseboard_fab2(sch_1):page137_i13" )
			)
			( gate "C7C19"
				( objectStatus "@baseboard_fab2_lib.baseboard_fab2(sch_1):page137_i14" )
			)
			( gate "R1U63"
				( objectStatus "@baseboard_fab2_lib.baseboard_fab2(sch_1):page137_i15" )
			)
			( gate "R3N4"
				( objectStatus "@baseboard_fab2_lib.baseboard_fab2(sch_1):page137_i19" )
			)
			( gate "C3N32"
				( objectStatus "@baseboard_fab2_lib.baseboard_fab2(sch_1):page137_i20" )
			)
			( gate "R7C13"
				( objectStatus "@baseboard_fab2_lib.baseboard_fab2(sch_1):page137_i67" )
			)
			( gate "R1U64"
				( objectStatus "@baseboard_fab2_lib.baseboard_fab2(sch_1):page137_i69" )
			)
			( gate "J9G1"
				( objectStatus "@baseboard_fab2_lib.baseboard_fab2(sch_1):page137_i128" )
			)
			( gate "R2T53"
				( objectStatus "@baseboard_fab2_lib.baseboard_fab2(sch_1):page138_i83" )
			)
			( gate "R2T54"
				( objectStatus "@baseboard_fab2_lib.baseboard_fab2(sch_1):page138_i84" )
			)
			( gate "R8D17"
				( objectStatus "@baseboard_fab2_lib.baseboard_fab2(sch_1):page138_i87" )
			)
			( gate "R8D15"
				( objectStatus "@baseboard_fab2_lib.baseboard_fab2(sch_1):page138_i88" )
			)
			( gate "R2N8"
				( objectStatus "@baseboard_fab2_lib.baseboard_fab2(sch_1):page138_i89" )
			)
			( gate "R2N5"
				( objectStatus "@baseboard_fab2_lib.baseboard_fab2(sch_1):page138_i90" )
			)
			( gate "R8C16"
				( objectStatus "@baseboard_fab2_lib.baseboard_fab2(sch_1):page138_i91" )
			)
			( gate "R8C15"
				( objectStatus "@baseboard_fab2_lib.baseboard_fab2(sch_1):page138_i92" )
			)
			( gate "R8B24"
				( objectStatus "@baseboard_fab2_lib.baseboard_fab2(sch_1):page138_i95" )
			)
			( gate "R8B26"
				( objectStatus "@baseboard_fab2_lib.baseboard_fab2(sch_1):page138_i96" )
			)
			( gate "R2U11"
				( objectStatus "@baseboard_fab2_lib.baseboard_fab2(sch_1):page138_i97" )
			)
			( gate "R2U3"
				( objectStatus "@baseboard_fab2_lib.baseboard_fab2(sch_1):page138_i98" )
			)
			( gate "R2T55"
				( objectStatus "@baseboard_fab2_lib.baseboard_fab2(sch_1):page138_i116" )
			)
			( gate "R2U8"
				( objectStatus "@baseboard_fab2_lib.baseboard_fab2(sch_1):page138_i158" )
			)
			( gate "R2U12"
				( objectStatus "@baseboard_fab2_lib.baseboard_fab2(sch_1):page138_i159" )
			)
			( gate "R2T56"
				( objectStatus "@baseboard_fab2_lib.baseboard_fab2(sch_1):page138_i160" )
			)
			( gate "R8D3"
				( objectStatus "@baseboard_fab2_lib.baseboard_fab2(sch_1):page138_i161" )
			)
			( gate "R8D6"
				( objectStatus "@baseboard_fab2_lib.baseboard_fab2(sch_1):page138_i162" )
			)
			( gate "R8D7"
				( objectStatus "@baseboard_fab2_lib.baseboard_fab2(sch_1):page138_i163" )
			)
			( gate "R8D4"
				( objectStatus "@baseboard_fab2_lib.baseboard_fab2(sch_1):page138_i164" )
			)
			( gate "R2U9"
				( objectStatus "@baseboard_fab2_lib.baseboard_fab2(sch_1):page138_i165" )
			)
			( gate "R2U6"
				( objectStatus "@baseboard_fab2_lib.baseboard_fab2(sch_1):page138_i166" )
			)
			( gate "R8C20"
				( objectStatus "@baseboard_fab2_lib.baseboard_fab2(sch_1):page138_i167" )
			)
			( gate "R8C14"
				( objectStatus "@baseboard_fab2_lib.baseboard_fab2(sch_1):page138_i168" )
			)
			( gate "R8C11"
				( objectStatus "@baseboard_fab2_lib.baseboard_fab2(sch_1):page138_i169" )
			)
			( gate "R8C12"
				( objectStatus "@baseboard_fab2_lib.baseboard_fab2(sch_1):page138_i170" )
			)
			( gate "R2N20"
				( objectStatus "@baseboard_fab2_lib.baseboard_fab2(sch_1):page138_i171" )
			)
			( gate "R8B27"
				( objectStatus "@baseboard_fab2_lib.baseboard_fab2(sch_1):page138_i173" )
			)
			( gate "R8B28"
				( objectStatus "@baseboard_fab2_lib.baseboard_fab2(sch_1):page138_i174" )
			)
			( gate "R2N21"
				( objectStatus "@baseboard_fab2_lib.baseboard_fab2(sch_1):page138_i175" )
			)
			( gate "EU9E1"
				( objectStatus "@baseboard_fab2_lib.baseboard_fab2(sch_1):page139_i72" )
			)
			( gate "C9E7"
				( objectStatus "@baseboard_fab2_lib.baseboard_fab2(sch_1):page139_i76" )
			)
			( gate "C9E5"
				( objectStatus "@baseboard_fab2_lib.baseboard_fab2(sch_1):page139_i87" )
			)
			( gate "C9E4"
				( objectStatus "@baseboard_fab2_lib.baseboard_fab2(sch_1):page139_i88" )
			)
			( gate "C2M23"
				( objectStatus "@baseboard_fab2_lib.baseboard_fab2(sch_1):page139_i89" )
			)
			( gate "C2M24"
				( objectStatus "@baseboard_fab2_lib.baseboard_fab2(sch_1):page139_i90" )
			)
			( gate "Y9E1"
				( objectStatus "@baseboard_fab2_lib.baseboard_fab2(sch_1):page139_i109" )
			)
			( gate "R9E20"
				( objectStatus "@baseboard_fab2_lib.baseboard_fab2(sch_1):page139_i110" )
			)
			( gate "C9E8"
				( objectStatus "@baseboard_fab2_lib.baseboard_fab2(sch_1):page139_i111" )
			)
			( gate "C9E9"
				( objectStatus "@baseboard_fab2_lib.baseboard_fab2(sch_1):page139_i112" )
			)
			( gate "R9E9"
				( objectStatus "@baseboard_fab2_lib.baseboard_fab2(sch_1):page139_i128" )
			)
			( gate "R9E5"
				( objectStatus "@baseboard_fab2_lib.baseboard_fab2(sch_1):page139_i129" )
			)
			( gate "R9E8"
				( objectStatus "@baseboard_fab2_lib.baseboard_fab2(sch_1):page139_i130" )
			)
			( gate "C1T4"
				( objectStatus "@baseboard_fab2_lib.baseboard_fab2(sch_1):page139_i134" )
			)
			( gate "C1R30"
				( objectStatus "@baseboard_fab2_lib.baseboard_fab2(sch_1):page139_i135" )
			)
			( gate "C1R22"
				( objectStatus "@baseboard_fab2_lib.baseboard_fab2(sch_1):page139_i136" )
			)
			( gate "C9F2"
				( objectStatus "@baseboard_fab2_lib.baseboard_fab2(sch_1):page139_i140" )
			)
			( gate "C1R13"
				( objectStatus "@baseboard_fab2_lib.baseboard_fab2(sch_1):page139_i142" )
			)
			( gate "C1R20"
				( objectStatus "@baseboard_fab2_lib.baseboard_fab2(sch_1):page139_i143" )
			)
			( gate "C1T3"
				( objectStatus "@baseboard_fab2_lib.baseboard_fab2(sch_1):page139_i144" )
			)
			( gate "C1R14"
				( objectStatus "@baseboard_fab2_lib.baseboard_fab2(sch_1):page139_i145" )
			)
			( gate "C1R21"
				( objectStatus "@baseboard_fab2_lib.baseboard_fab2(sch_1):page139_i146" )
			)
			( gate "C1R26"
				( objectStatus "@baseboard_fab2_lib.baseboard_fab2(sch_1):page139_i149" )
			)
			( gate "C1R29"
				( objectStatus "@baseboard_fab2_lib.baseboard_fab2(sch_1):page139_i150" )
			)
			( gate "C1R19"
				( objectStatus "@baseboard_fab2_lib.baseboard_fab2(sch_1):page139_i151" )
			)
			( gate "C1R31"
				( objectStatus "@baseboard_fab2_lib.baseboard_fab2(sch_1):page139_i152" )
			)
			( gate "C1R17"
				( objectStatus "@baseboard_fab2_lib.baseboard_fab2(sch_1):page139_i153" )
			)
			( gate "C9E6"
				( objectStatus "@baseboard_fab2_lib.baseboard_fab2(sch_1):page139_i155" )
			)
			( gate "C1R18"
				( objectStatus "@baseboard_fab2_lib.baseboard_fab2(sch_1):page139_i157" )
			)
			( gate "C1T5"
				( objectStatus "@baseboard_fab2_lib.baseboard_fab2(sch_1):page139_i158" )
			)
			( gate "C1R24"
				( objectStatus "@baseboard_fab2_lib.baseboard_fab2(sch_1):page139_i159" )
			)
			( gate "C1R15"
				( objectStatus "@baseboard_fab2_lib.baseboard_fab2(sch_1):page139_i160" )
			)
			( gate "C1R16"
				( objectStatus "@baseboard_fab2_lib.baseboard_fab2(sch_1):page139_i161" )
			)
			( gate "C9E1"
				( objectStatus "@baseboard_fab2_lib.baseboard_fab2(sch_1):page139_i163" )
			)
			( gate "R9F5"
				( objectStatus "@baseboard_fab2_lib.baseboard_fab2(sch_1):page139_i173" )
			)
			( gate "R9E23"
				( objectStatus "@baseboard_fab2_lib.baseboard_fab2(sch_1):page139_i174" )
			)
			( gate "R9E2"
				( objectStatus "@baseboard_fab2_lib.baseboard_fab2(sch_1):page139_i177" )
			)
			( gate "R9E3"
				( objectStatus "@baseboard_fab2_lib.baseboard_fab2(sch_1):page139_i178" )
			)
			( gate "R9E1"
				( objectStatus "@baseboard_fab2_lib.baseboard_fab2(sch_1):page139_i179" )
			)
			( gate "R9E22"
				( objectStatus "@baseboard_fab2_lib.baseboard_fab2(sch_1):page139_i181" )
			)
			( gate "R9E7"
				( objectStatus "@baseboard_fab2_lib.baseboard_fab2(sch_1):page139_i193" )
			)
			( gate "R1R1"
				( objectStatus "@baseboard_fab2_lib.baseboard_fab2(sch_1):page139_i195" )
			)
			( gate "R9E4"
				( objectStatus "@baseboard_fab2_lib.baseboard_fab2(sch_1):page139_i200" )
			)
			( gate "R9E18"
				( objectStatus "@baseboard_fab2_lib.baseboard_fab2(sch_1):page139_i201" )
			)
			( gate "R9E13"
				( objectStatus "@baseboard_fab2_lib.baseboard_fab2(sch_1):page139_i212" )
			)
			( gate "R1R12"
				( objectStatus "@baseboard_fab2_lib.baseboard_fab2(sch_1):page139_i213" )
			)
			( gate "R1T1"
				( objectStatus "@baseboard_fab2_lib.baseboard_fab2(sch_1):page139_i214" )
			)
			( gate "R9F1"
				( objectStatus "@baseboard_fab2_lib.baseboard_fab2(sch_1):page139_i225" )
			)
			( gate "R9E19"
				( objectStatus "@baseboard_fab2_lib.baseboard_fab2(sch_1):page139_i228" )
			)
			( gate "R9E17"
				( objectStatus "@baseboard_fab2_lib.baseboard_fab2(sch_1):page139_i229" )
			)
			( gate "R9E16"
				( objectStatus "@baseboard_fab2_lib.baseboard_fab2(sch_1):page139_i235" )
			)
			( gate "R1R15"
				( objectStatus "@baseboard_fab2_lib.baseboard_fab2(sch_1):page139_i237" )
			)
			( gate "R1T32"
				( objectStatus "@baseboard_fab2_lib.baseboard_fab2(sch_1):page139_i238" )
			)
			( gate "R1T34"
				( objectStatus "@baseboard_fab2_lib.baseboard_fab2(sch_1):page139_i239" )
			)
			( gate "R1T33"
				( objectStatus "@baseboard_fab2_lib.baseboard_fab2(sch_1):page139_i240" )
			)
			( gate "C9E12"
				( objectStatus "@baseboard_fab2_lib.baseboard_fab2(sch_1):page139_i241" )
			)
			( gate "U9E1"
				( objectStatus "@baseboard_fab2_lib.baseboard_fab2(sch_1):page140_i1" )
			)
			( gate "C1R25"
				( objectStatus "@baseboard_fab2_lib.baseboard_fab2(sch_1):page140_i3" )
			)
			( gate "R1R9"
				( objectStatus "@baseboard_fab2_lib.baseboard_fab2(sch_1):page140_i10" )
			)
			( gate "R1R3"
				( objectStatus "@baseboard_fab2_lib.baseboard_fab2(sch_1):page140_i11" )
			)
			( gate "R1R7"
				( objectStatus "@baseboard_fab2_lib.baseboard_fab2(sch_1):page140_i12" )
			)
			( gate "R1R6"
				( objectStatus "@baseboard_fab2_lib.baseboard_fab2(sch_1):page140_i14" )
			)
			( gate "R9E6"
				( objectStatus "@baseboard_fab2_lib.baseboard_fab2(sch_1):page140_i17" )
			)
			( gate "R9G3"
				( objectStatus "@baseboard_fab2_lib.baseboard_fab2(sch_1):page141_i28" )
			)
			( gate "R9G2"
				( objectStatus "@baseboard_fab2_lib.baseboard_fab2(sch_1):page141_i30" )
			)
			( gate "C9G7"
				( objectStatus "@baseboard_fab2_lib.baseboard_fab2(sch_1):page141_i33" )
			)
			( gate "C9G2"
				( objectStatus "@baseboard_fab2_lib.baseboard_fab2(sch_1):page141_i36" )
			)
			( gate "C9G4"
				( objectStatus "@baseboard_fab2_lib.baseboard_fab2(sch_1):page141_i46" )
			)
			( gate "C9G6"
				( objectStatus "@baseboard_fab2_lib.baseboard_fab2(sch_1):page141_i47" )
			)
			( gate "C9G5"
				( objectStatus "@baseboard_fab2_lib.baseboard_fab2(sch_1):page141_i48" )
			)
			( gate "R9G1"
				( objectStatus "@baseboard_fab2_lib.baseboard_fab2(sch_1):page141_i54" )
			)
			( gate "R9G4"
				( objectStatus "@baseboard_fab2_lib.baseboard_fab2(sch_1):page141_i56" )
			)
			( gate "C9G1"
				( objectStatus "@baseboard_fab2_lib.baseboard_fab2(sch_1):page141_i58" )
			)
			( gate "C9G3"
				( objectStatus "@baseboard_fab2_lib.baseboard_fab2(sch_1):page141_i59" )
			)
			( gate "C9F22"
				( objectStatus "@baseboard_fab2_lib.baseboard_fab2(sch_1):page141_i60" )
			)
			( gate "R9G9"
				( objectStatus "@baseboard_fab2_lib.baseboard_fab2(sch_1):page141_i75" )
			)
			( gate "R9G11"
				( objectStatus "@baseboard_fab2_lib.baseboard_fab2(sch_1):page141_i76" )
			)
			( gate "R9G18"
				( objectStatus "@baseboard_fab2_lib.baseboard_fab2(sch_1):page141_i77" )
			)
			( gate "R9G17"
				( objectStatus "@baseboard_fab2_lib.baseboard_fab2(sch_1):page141_i78" )
			)
			( gate "R9G19"
				( objectStatus "@baseboard_fab2_lib.baseboard_fab2(sch_1):page141_i79" )
			)
			( gate "R9G20"
				( objectStatus "@baseboard_fab2_lib.baseboard_fab2(sch_1):page141_i80" )
			)
			( gate "R9G24"
				( objectStatus "@baseboard_fab2_lib.baseboard_fab2(sch_1):page141_i81" )
			)
			( gate "R9G22"
				( objectStatus "@baseboard_fab2_lib.baseboard_fab2(sch_1):page141_i82" )
			)
			( gate "C9G9"
				( objectStatus "@baseboard_fab2_lib.baseboard_fab2(sch_1):page141_i99" )
			)
			( gate "C9G12"
				( objectStatus "@baseboard_fab2_lib.baseboard_fab2(sch_1):page141_i100" )
			)
			( gate "C9G16"
				( objectStatus "@baseboard_fab2_lib.baseboard_fab2(sch_1):page141_i101" )
			)
			( gate "C9G13"
				( objectStatus "@baseboard_fab2_lib.baseboard_fab2(sch_1):page141_i102" )
			)
			( gate "JA9G1"
				( objectStatus "@baseboard_fab2_lib.baseboard_fab2(sch_1):page141_i109" )
			)
			( gate "R1U51"
				( objectStatus "@baseboard_fab2_lib.baseboard_fab2(sch_1):page141_i112" )
			)
			( gate "R1U3"
				( objectStatus "@baseboard_fab2_lib.baseboard_fab2(sch_1):page141_i114" )
			)
			( gate "U8E4"
				( objectStatus "@baseboard_fab2_lib.baseboard_fab2(sch_1):page142_i1" )
			)
			( gate "R8E17"
				( objectStatus "@baseboard_fab2_lib.baseboard_fab2(sch_1):page142_i2" )
			)
			( gate "R8E23"
				( objectStatus "@baseboard_fab2_lib.baseboard_fab2(sch_1):page142_i3" )
			)
			( gate "R8E29"
				( objectStatus "@baseboard_fab2_lib.baseboard_fab2(sch_1):page142_i18" )
			)
			( gate "C8E5"
				( objectStatus "@baseboard_fab2_lib.baseboard_fab2(sch_1):page142_i20" )
			)
			( gate "R8E30"
				( objectStatus "@baseboard_fab2_lib.baseboard_fab2(sch_1):page142_i23" )
			)
			( gate "R8E36"
				( objectStatus "@baseboard_fab2_lib.baseboard_fab2(sch_1):page142_i28" )
			)
			( gate "R8E26"
				( objectStatus "@baseboard_fab2_lib.baseboard_fab2(sch_1):page142_i30" )
			)
			( gate "R8E28"
				( objectStatus "@baseboard_fab2_lib.baseboard_fab2(sch_1):page142_i31" )
			)
			( gate "R8E27"
				( objectStatus "@baseboard_fab2_lib.baseboard_fab2(sch_1):page142_i32" )
			)
			( gate "R8E21"
				( objectStatus "@baseboard_fab2_lib.baseboard_fab2(sch_1):page142_i33" )
			)
			( gate "C25W24"
				( objectStatus "@baseboard_fab2_lib.baseboard_fab2(sch_1):page150_i73" )
			)
			( gate "R25W36"
				( objectStatus "@baseboard_fab2_lib.baseboard_fab2(sch_1):page149_i195" )
			)
			( gate "U25W4"
				( objectStatus "@baseboard_fab2_lib.baseboard_fab2(sch_1):page145_i117" )
			)
			( gate "FB2T3"
				( objectStatus "@baseboard_fab2_lib.baseboard_fab2(sch_1):page150_i76" )
			)
			( gate "C25W23"
				( objectStatus "@baseboard_fab2_lib.baseboard_fab2(sch_1):page150_i75" )
			)
			( gate "C25W47"
				( objectStatus "@baseboard_fab2_lib.baseboard_fab2(sch_1):page150_i54" )
			)
			( gate "C25W46"
				( objectStatus "@baseboard_fab2_lib.baseboard_fab2(sch_1):page150_i55" )
			)
			( gate "R25W30"
				( objectStatus "@baseboard_fab2_lib.baseboard_fab2(sch_1):page149_i188" )
			)
			( gate "R25W29"
				( objectStatus "@baseboard_fab2_lib.baseboard_fab2(sch_1):page149_i189" )
			)
			( gate "R25W31"
				( objectStatus "@baseboard_fab2_lib.baseboard_fab2(sch_1):page149_i190" )
			)
			( gate "R1T27"
				( objectStatus "@baseboard_fab2_lib.baseboard_fab2(sch_1):page143_i58" )
			)
			( gate "R25W28"
				( objectStatus "@baseboard_fab2_lib.baseboard_fab2(sch_1):page149_i187" )
			)
			( gate "R25W27"
				( objectStatus "@baseboard_fab2_lib.baseboard_fab2(sch_1):page149_i186" )
			)
			( gate "C8W1"
				( objectStatus "@baseboard_fab2_lib.baseboard_fab2(sch_1):page249_i32" )
			)
			( gate "R8B25"
				( objectStatus "@baseboard_fab2_lib.baseboard_fab2(sch_1):page149_i156" )
			)
			( gate "C25W10"
				( objectStatus "@baseboard_fab2_lib.baseboard_fab2(sch_1):page149_i158" )
			)
			( gate "R25W40"
				( objectStatus "@baseboard_fab2_lib.baseboard_fab2(sch_1):page149_i200" )
			)
			( gate "R25W41"
				( objectStatus "@baseboard_fab2_lib.baseboard_fab2(sch_1):page149_i199" )
			)
			( gate "R25W39"
				( objectStatus "@baseboard_fab2_lib.baseboard_fab2(sch_1):page149_i198" )
			)
			( gate "R25W38"
				( objectStatus "@baseboard_fab2_lib.baseboard_fab2(sch_1):page149_i197" )
			)
			( gate "R25W37"
				( objectStatus "@baseboard_fab2_lib.baseboard_fab2(sch_1):page149_i196" )
			)
			( gate "C25W29"
				( objectStatus "@baseboard_fab2_lib.baseboard_fab2(sch_1):page150_i45" )
			)
			( gate "C25W28"
				( objectStatus "@baseboard_fab2_lib.baseboard_fab2(sch_1):page150_i46" )
			)
			( gate "C25W27"
				( objectStatus "@baseboard_fab2_lib.baseboard_fab2(sch_1):page150_i48" )
			)
			( gate "C25W36"
				( objectStatus "@baseboard_fab2_lib.baseboard_fab2(sch_1):page150_i50" )
			)
			( gate "C25W35"
				( objectStatus "@baseboard_fab2_lib.baseboard_fab2(sch_1):page150_i51" )
			)
			( gate "C25W34"
				( objectStatus "@baseboard_fab2_lib.baseboard_fab2(sch_1):page150_i53" )
			)
			( gate "R3W5"
				( objectStatus "@baseboard_fab2_lib.baseboard_fab2(sch_1):page249_i33" )
			)
			( gate "R9A5"
				( objectStatus "@baseboard_fab2_lib.baseboard_fab2(sch_1):page155_i195" )
			)
			( gate "C25W40"
				( objectStatus "@baseboard_fab2_lib.baseboard_fab2(sch_1):page150_i82" )
			)
			( gate "R9F20"
				( objectStatus "@baseboard_fab2_lib.baseboard_fab2(sch_1):page145_i22" )
			)
			( gate "R25W70"
				( objectStatus "@baseboard_fab2_lib.baseboard_fab2(sch_1):page146_i64" )
			)
			( gate "R6W12"
				( objectStatus "@baseboard_fab2_lib.baseboard_fab2(sch_1):page247_i68" )
			)
			( gate "R6W11"
				( objectStatus "@baseboard_fab2_lib.baseboard_fab2(sch_1):page247_i67" )
			)
			( gate "C25W1"
				( objectStatus "@baseboard_fab2_lib.baseboard_fab2(sch_1):page149_i71" )
			)
			( gate "C25W19"
				( objectStatus "@baseboard_fab2_lib.baseboard_fab2(sch_1):page149_i69" )
			)
			( gate "C25W18"
				( objectStatus "@baseboard_fab2_lib.baseboard_fab2(sch_1):page149_i68" )
			)
			( gate "C25W13"
				( objectStatus "@baseboard_fab2_lib.baseboard_fab2(sch_1):page149_i65" )
			)
			( gate "R25W117"
				( objectStatus "@baseboard_fab2_lib.baseboard_fab2(sch_1):page149_i55" )
			)
			( gate "C25W14"
				( objectStatus "@baseboard_fab2_lib.baseboard_fab2(sch_1):page149_i44" )
			)
			( gate "C25W11"
				( objectStatus "@baseboard_fab2_lib.baseboard_fab2(sch_1):page149_i159" )
			)
			( gate "U9G1"
				( objectStatus "@baseboard_fab2_lib.baseboard_fab2(sch_1):page152_i1" )
			)
			( gate "R1U30"
				( objectStatus "@baseboard_fab2_lib.baseboard_fab2(sch_1):page152_i2" )
			)
			( gate "R1U46"
				( objectStatus "@baseboard_fab2_lib.baseboard_fab2(sch_1):page152_i6" )
			)
			( gate "R9G31"
				( objectStatus "@baseboard_fab2_lib.baseboard_fab2(sch_1):page152_i14" )
			)
			( gate "R1U36"
				( objectStatus "@baseboard_fab2_lib.baseboard_fab2(sch_1):page152_i15" )
			)
			( gate "R1U34"
				( objectStatus "@baseboard_fab2_lib.baseboard_fab2(sch_1):page152_i16" )
			)
			( gate "C1U19"
				( objectStatus "@baseboard_fab2_lib.baseboard_fab2(sch_1):page152_i18" )
			)
			( gate "R1U43"
				( objectStatus "@baseboard_fab2_lib.baseboard_fab2(sch_1):page152_i25" )
			)
			( gate "R1U37"
				( objectStatus "@baseboard_fab2_lib.baseboard_fab2(sch_1):page152_i26" )
			)
			( gate "C1U22"
				( objectStatus "@baseboard_fab2_lib.baseboard_fab2(sch_1):page152_i27" )
			)
			( gate "R9G34"
				( objectStatus "@baseboard_fab2_lib.baseboard_fab2(sch_1):page152_i45" )
			)
			( gate "R9G27"
				( objectStatus "@baseboard_fab2_lib.baseboard_fab2(sch_1):page152_i47" )
			)
			( gate "R1U58"
				( objectStatus "@baseboard_fab2_lib.baseboard_fab2(sch_1):page152_i49" )
			)
			( gate "R1U56"
				( objectStatus "@baseboard_fab2_lib.baseboard_fab2(sch_1):page152_i50" )
			)
			( gate "R2U51"
				( objectStatus "@baseboard_fab2_lib.baseboard_fab2(sch_1):page152_i51" )
			)
			( gate "R2U40"
				( objectStatus "@baseboard_fab2_lib.baseboard_fab2(sch_1):page152_i53" )
			)
			( gate "R2U41"
				( objectStatus "@baseboard_fab2_lib.baseboard_fab2(sch_1):page152_i54" )
			)
			( gate "R1U41"
				( objectStatus "@baseboard_fab2_lib.baseboard_fab2(sch_1):page152_i56" )
			)
			( gate "R1U35"
				( objectStatus "@baseboard_fab2_lib.baseboard_fab2(sch_1):page152_i57" )
			)
			( gate "R4P17"
				( objectStatus "@baseboard_fab2_lib.baseboard_fab2(sch_1):page152_i58" )
			)
			( gate "R4P20"
				( objectStatus "@baseboard_fab2_lib.baseboard_fab2(sch_1):page152_i59" )
			)
			( gate "R7P5"
				( objectStatus "@baseboard_fab2_lib.baseboard_fab2(sch_1):page152_i61" )
			)
			( gate "R7P21"
				( objectStatus "@baseboard_fab2_lib.baseboard_fab2(sch_1):page152_i62" )
			)
			( gate "R1U53"
				( objectStatus "@baseboard_fab2_lib.baseboard_fab2(sch_1):page152_i64" )
			)
			( gate "R1U60"
				( objectStatus "@baseboard_fab2_lib.baseboard_fab2(sch_1):page152_i65" )
			)
			( gate "R2U49"
				( objectStatus "@baseboard_fab2_lib.baseboard_fab2(sch_1):page152_i66" )
			)
			( gate "R1U55"
				( objectStatus "@baseboard_fab2_lib.baseboard_fab2(sch_1):page152_i67" )
			)
			( gate "R1U62"
				( objectStatus "@baseboard_fab2_lib.baseboard_fab2(sch_1):page152_i68" )
			)
			( gate "R1U57"
				( objectStatus "@baseboard_fab2_lib.baseboard_fab2(sch_1):page152_i69" )
			)
			( gate "R1U61"
				( objectStatus "@baseboard_fab2_lib.baseboard_fab2(sch_1):page152_i70" )
			)
			( gate "R9G28"
				( objectStatus "@baseboard_fab2_lib.baseboard_fab2(sch_1):page152_i71" )
			)
			( gate "R9G32"
				( objectStatus "@baseboard_fab2_lib.baseboard_fab2(sch_1):page152_i72" )
			)
			( gate "R9G33"
				( objectStatus "@baseboard_fab2_lib.baseboard_fab2(sch_1):page152_i73" )
			)
			( gate "R1U59"
				( objectStatus "@baseboard_fab2_lib.baseboard_fab2(sch_1):page152_i74" )
			)
			( gate "R2U47"
				( objectStatus "@baseboard_fab2_lib.baseboard_fab2(sch_1):page152_i79" )
			)
			( gate "R9G29"
				( objectStatus "@baseboard_fab2_lib.baseboard_fab2(sch_1):page152_i92" )
			)
			( gate "R1U54"
				( objectStatus "@baseboard_fab2_lib.baseboard_fab2(sch_1):page152_i93" )
			)
			( gate "R2U46"
				( objectStatus "@baseboard_fab2_lib.baseboard_fab2(sch_1):page152_i94" )
			)
			( gate "R3N30"
				( objectStatus "@baseboard_fab2_lib.baseboard_fab2(sch_1):page152_i95" )
			)
			( gate "R9G30"
				( objectStatus "@baseboard_fab2_lib.baseboard_fab2(sch_1):page152_i98" )
			)
			( gate "R3P63"
				( objectStatus "@baseboard_fab2_lib.baseboard_fab2(sch_1):page152_i100" )
			)
			( gate "R2U45"
				( objectStatus "@baseboard_fab2_lib.baseboard_fab2(sch_1):page152_i102" )
			)
			( gate "R7F6"
				( objectStatus "@baseboard_fab2_lib.baseboard_fab2(sch_1):page153_i90" )
			)
			( gate "R7F5"
				( objectStatus "@baseboard_fab2_lib.baseboard_fab2(sch_1):page153_i94" )
			)
			( gate "R7F4"
				( objectStatus "@baseboard_fab2_lib.baseboard_fab2(sch_1):page153_i98" )
			)
			( gate "R7F37"
				( objectStatus "@baseboard_fab2_lib.baseboard_fab2(sch_1):page153_i108" )
			)
			( gate "R7F3"
				( objectStatus "@baseboard_fab2_lib.baseboard_fab2(sch_1):page153_i109" )
			)
			( gate "C7F2"
				( objectStatus "@baseboard_fab2_lib.baseboard_fab2(sch_1):page153_i130" )
			)
			( gate "C7F1"
				( objectStatus "@baseboard_fab2_lib.baseboard_fab2(sch_1):page153_i131" )
			)
			( gate "C3T5"
				( objectStatus "@baseboard_fab2_lib.baseboard_fab2(sch_1):page153_i136" )
			)
			( gate "C3T4"
				( objectStatus "@baseboard_fab2_lib.baseboard_fab2(sch_1):page153_i138" )
			)
			( gate "R7F32"
				( objectStatus "@baseboard_fab2_lib.baseboard_fab2(sch_1):page153_i140" )
			)
			( gate "U7F1"
				( objectStatus "@baseboard_fab2_lib.baseboard_fab2(sch_1):page153_i146" )
			)
			( gate "R3T3"
				( objectStatus "@baseboard_fab2_lib.baseboard_fab2(sch_1):page153_i150" )
			)
			( gate "R3T5"
				( objectStatus "@baseboard_fab2_lib.baseboard_fab2(sch_1):page153_i152" )
			)
			( gate "R3T2"
				( objectStatus "@baseboard_fab2_lib.baseboard_fab2(sch_1):page153_i155" )
			)
			( gate "R3U1"
				( objectStatus "@baseboard_fab2_lib.baseboard_fab2(sch_1):page153_i156" )
			)
			( gate "R3T1"
				( objectStatus "@baseboard_fab2_lib.baseboard_fab2(sch_1):page153_i157" )
			)
			( gate "U3T1"
				( objectStatus "@baseboard_fab2_lib.baseboard_fab2(sch_1):page153_i165" )
			)
			( gate "R8F8"
				( objectStatus "@baseboard_fab2_lib.baseboard_fab2(sch_1):page153_i166" )
			)
			( gate "R8F7"
				( objectStatus "@baseboard_fab2_lib.baseboard_fab2(sch_1):page153_i167" )
			)
			( gate "R7F28"
				( objectStatus "@baseboard_fab2_lib.baseboard_fab2(sch_1):page153_i168" )
			)
			( gate "R7F30"
				( objectStatus "@baseboard_fab2_lib.baseboard_fab2(sch_1):page153_i170" )
			)
			( gate "R3T4"
				( objectStatus "@baseboard_fab2_lib.baseboard_fab2(sch_1):page153_i174" )
			)
			( gate "R3T12"
				( objectStatus "@baseboard_fab2_lib.baseboard_fab2(sch_1):page153_i178" )
			)
			( gate "R3T9"
				( objectStatus "@baseboard_fab2_lib.baseboard_fab2(sch_1):page153_i179" )
			)
			( gate "R7F29"
				( objectStatus "@baseboard_fab2_lib.baseboard_fab2(sch_1):page153_i181" )
			)
			( gate "R3T10"
				( objectStatus "@baseboard_fab2_lib.baseboard_fab2(sch_1):page153_i184" )
			)
			( gate "C8E18"
				( objectStatus "@baseboard_fab2_lib.baseboard_fab2(sch_1):page154_i14" )
			)
			( gate "R2T9"
				( objectStatus "@baseboard_fab2_lib.baseboard_fab2(sch_1):page154_i62" )
			)
			( gate "U8F1"
				( objectStatus "@baseboard_fab2_lib.baseboard_fab2(sch_1):page154_i74" )
			)
			( gate "U2T1"
				( objectStatus "@baseboard_fab2_lib.baseboard_fab2(sch_1):page154_i75" )
			)
			( gate "R2T2"
				( objectStatus "@baseboard_fab2_lib.baseboard_fab2(sch_1):page154_i92" )
			)
			( gate "R2R12"
				( objectStatus "@baseboard_fab2_lib.baseboard_fab2(sch_1):page154_i93" )
			)
			( gate "C2T1"
				( objectStatus "@baseboard_fab2_lib.baseboard_fab2(sch_1):page154_i94" )
			)
			( gate "U2T3"
				( objectStatus "@baseboard_fab2_lib.baseboard_fab2(sch_1):page154_i99" )
			)
			( gate "U2T2"
				( objectStatus "@baseboard_fab2_lib.baseboard_fab2(sch_1):page154_i100" )
			)
			( gate "R2T13"
				( objectStatus "@baseboard_fab2_lib.baseboard_fab2(sch_1):page154_i101" )
			)
			( gate "R2T11"
				( objectStatus "@baseboard_fab2_lib.baseboard_fab2(sch_1):page154_i105" )
			)
			( gate "R2T8"
				( objectStatus "@baseboard_fab2_lib.baseboard_fab2(sch_1):page154_i106" )
			)
			( gate "R8F6"
				( objectStatus "@baseboard_fab2_lib.baseboard_fab2(sch_1):page154_i119" )
			)
			( gate "Q8F1"
				( objectStatus "@baseboard_fab2_lib.baseboard_fab2(sch_1):page154_i126" )
			)
			( gate "R2T6"
				( objectStatus "@baseboard_fab2_lib.baseboard_fab2(sch_1):page154_i127" )
			)
			( gate "R1U6"
				( objectStatus "@baseboard_fab2_lib.baseboard_fab2(sch_1):page154_i128" )
			)
			( gate "C2T12"
				( objectStatus "@baseboard_fab2_lib.baseboard_fab2(sch_1):page154_i132" )
			)
			( gate "C2T8"
				( objectStatus "@baseboard_fab2_lib.baseboard_fab2(sch_1):page154_i135" )
			)
			( gate "R9A8"
				( objectStatus "@baseboard_fab2_lib.baseboard_fab2(sch_1):page155_i53" )
			)
			( gate "R1L32"
				( objectStatus "@baseboard_fab2_lib.baseboard_fab2(sch_1):page155_i65" )
			)
			( gate "R1L30"
				( objectStatus "@baseboard_fab2_lib.baseboard_fab2(sch_1):page155_i66" )
			)
			( gate "R1L25"
				( objectStatus "@baseboard_fab2_lib.baseboard_fab2(sch_1):page155_i67" )
			)
			( gate "R1L24"
				( objectStatus "@baseboard_fab2_lib.baseboard_fab2(sch_1):page155_i68" )
			)
			( gate "R1L20"
				( objectStatus "@baseboard_fab2_lib.baseboard_fab2(sch_1):page155_i73" )
			)
			( gate "R1L18"
				( objectStatus "@baseboard_fab2_lib.baseboard_fab2(sch_1):page155_i74" )
			)
			( gate "R1L14"
				( objectStatus "@baseboard_fab2_lib.baseboard_fab2(sch_1):page155_i75" )
			)
			( gate "R1L11"
				( objectStatus "@baseboard_fab2_lib.baseboard_fab2(sch_1):page155_i76" )
			)
			( gate "R9A7"
				( objectStatus "@baseboard_fab2_lib.baseboard_fab2(sch_1):page155_i80" )
			)
			( gate "C9A1"
				( objectStatus "@baseboard_fab2_lib.baseboard_fab2(sch_1):page155_i127" )
			)
			( gate "F1L1"
				( objectStatus "@baseboard_fab2_lib.baseboard_fab2(sch_1):page155_i129" )
			)
			( gate "R1L9"
				( objectStatus "@baseboard_fab2_lib.baseboard_fab2(sch_1):page155_i130" )
			)
			( gate "U6W10"
				( objectStatus "@baseboard_fab2_lib.baseboard_fab2(sch_1):page176_i122" )
			)
			( gate "J9A2"
				( objectStatus "@baseboard_fab2_lib.baseboard_fab2(sch_1):page155_i171" )
			)
			( gate "U9A1"
				( objectStatus "@baseboard_fab2_lib.baseboard_fab2(sch_1):page155_i178" )
			)
			( gate "C1T56"
				( objectStatus "@baseboard_fab2_lib.baseboard_fab2(sch_1):page155_i184" )
			)
			( gate "R1L2"
				( objectStatus "@baseboard_fab2_lib.baseboard_fab2(sch_1):page155_i186" )
			)
			( gate "Q1L2"
				( objectStatus "@baseboard_fab2_lib.baseboard_fab2(sch_1):page155_i187" )
			)
			( gate "Q1L2"
				( objectStatus "@baseboard_fab2_lib.baseboard_fab2(sch_1):page155_i188" )
			)
			( gate "R9A6"
				( objectStatus "@baseboard_fab2_lib.baseboard_fab2(sch_1):page155_i191" )
			)
			( gate "U8F3"
				( objectStatus "@baseboard_fab2_lib.baseboard_fab2(sch_1):page156_i201" )
			)
			( gate "R2T34"
				( objectStatus "@baseboard_fab2_lib.baseboard_fab2(sch_1):page156_i206" )
			)
			( gate "R2T35"
				( objectStatus "@baseboard_fab2_lib.baseboard_fab2(sch_1):page156_i207" )
			)
			( gate "R2T22"
				( objectStatus "@baseboard_fab2_lib.baseboard_fab2(sch_1):page156_i210" )
			)
			( gate "R8F26"
				( objectStatus "@baseboard_fab2_lib.baseboard_fab2(sch_1):page156_i211" )
			)
			( gate "R8E24"
				( objectStatus "@baseboard_fab2_lib.baseboard_fab2(sch_1):page156_i214" )
			)
			( gate "R8E22"
				( objectStatus "@baseboard_fab2_lib.baseboard_fab2(sch_1):page156_i215" )
			)
			( gate "R2U2"
				( objectStatus "@baseboard_fab2_lib.baseboard_fab2(sch_1):page156_i265" )
			)
			( gate "R8G2"
				( objectStatus "@baseboard_fab2_lib.baseboard_fab2(sch_1):page156_i267" )
			)
			( gate "U8G1"
				( objectStatus "@baseboard_fab2_lib.baseboard_fab2(sch_1):page156_i269" )
			)
			( gate "C2T35"
				( objectStatus "@baseboard_fab2_lib.baseboard_fab2(sch_1):page156_i273" )
			)
			( gate "C8F16"
				( objectStatus "@baseboard_fab2_lib.baseboard_fab2(sch_1):page156_i275" )
			)
			( gate "R8E11"
				( objectStatus "@baseboard_fab2_lib.baseboard_fab2(sch_1):page156_i279" )
			)
			( gate "J9B2"
				( objectStatus "@baseboard_fab2_lib.baseboard_fab2(sch_1):page156_i281" )
			)
			( gate "J8C1"
				( objectStatus "@baseboard_fab2_lib.baseboard_fab2(sch_1):page156_i285" )
			)
			( gate "R2T18"
				( objectStatus "@baseboard_fab2_lib.baseboard_fab2(sch_1):page156_i288" )
			)
			( gate "R2T28"
				( objectStatus "@baseboard_fab2_lib.baseboard_fab2(sch_1):page156_i289" )
			)
			( gate "R6D16"
				( objectStatus "@baseboard_fab2_lib.baseboard_fab2(sch_1):page156_i299" )
			)
			( gate "R3D31"
				( objectStatus "@baseboard_fab2_lib.baseboard_fab2(sch_1):page156_i300" )
			)
			( gate "R6N14"
				( objectStatus "@baseboard_fab2_lib.baseboard_fab2(sch_1):page156_i302" )
			)
			( gate "R6N13"
				( objectStatus "@baseboard_fab2_lib.baseboard_fab2(sch_1):page156_i303" )
			)
			( gate "R6N15"
				( objectStatus "@baseboard_fab2_lib.baseboard_fab2(sch_1):page156_i304" )
			)
			( gate "R1C32"
				( objectStatus "@baseboard_fab2_lib.baseboard_fab2(sch_1):page156_i312" )
			)
			( gate "R1C33"
				( objectStatus "@baseboard_fab2_lib.baseboard_fab2(sch_1):page156_i313" )
			)
			( gate "R1C34"
				( objectStatus "@baseboard_fab2_lib.baseboard_fab2(sch_1):page156_i320" )
			)
			( gate "R9M21"
				( objectStatus "@baseboard_fab2_lib.baseboard_fab2(sch_1):page156_i321" )
			)
			( gate "R4A8"
				( objectStatus "@baseboard_fab2_lib.baseboard_fab2(sch_1):page156_i322" )
			)
			( gate "R9M20"
				( objectStatus "@baseboard_fab2_lib.baseboard_fab2(sch_1):page156_i323" )
			)
			( gate "R4A9"
				( objectStatus "@baseboard_fab2_lib.baseboard_fab2(sch_1):page156_i324" )
			)
			( gate "R3P54"
				( objectStatus "@baseboard_fab2_lib.baseboard_fab2(sch_1):page156_i331" )
			)
			( gate "R3P56"
				( objectStatus "@baseboard_fab2_lib.baseboard_fab2(sch_1):page156_i333" )
			)
			( gate "R1C35"
				( objectStatus "@baseboard_fab2_lib.baseboard_fab2(sch_1):page156_i336" )
			)
			( gate "R1C36"
				( objectStatus "@baseboard_fab2_lib.baseboard_fab2(sch_1):page156_i337" )
			)
			( gate "R2N27"
				( objectStatus "@baseboard_fab2_lib.baseboard_fab2(sch_1):page157_i97" )
			)
			( gate "R8F23"
				( objectStatus "@baseboard_fab2_lib.baseboard_fab2(sch_1):page157_i296" )
			)
			( gate "R2T29"
				( objectStatus "@baseboard_fab2_lib.baseboard_fab2(sch_1):page157_i298" )
			)
			( gate "R2N25"
				( objectStatus "@baseboard_fab2_lib.baseboard_fab2(sch_1):page157_i302" )
			)
			( gate "R8F24"
				( objectStatus "@baseboard_fab2_lib.baseboard_fab2(sch_1):page157_i316" )
			)
			( gate "R2T5"
				( objectStatus "@baseboard_fab2_lib.baseboard_fab2(sch_1):page157_i326" )
			)
			( gate "R2T7"
				( objectStatus "@baseboard_fab2_lib.baseboard_fab2(sch_1):page157_i327" )
			)
			( gate "Q2T1"
				( objectStatus "@baseboard_fab2_lib.baseboard_fab2(sch_1):page157_i330" )
			)
			( gate "R8D25"
				( objectStatus "@baseboard_fab2_lib.baseboard_fab2(sch_1):page157_i335" )
			)
			( gate "Q2T2"
				( objectStatus "@baseboard_fab2_lib.baseboard_fab2(sch_1):page157_i340" )
			)
			( gate "R3N12"
				( objectStatus "@baseboard_fab2_lib.baseboard_fab2(sch_1):page157_i342" )
			)
			( gate "R3N11"
				( objectStatus "@baseboard_fab2_lib.baseboard_fab2(sch_1):page157_i344" )
			)
			( gate "R2M2"
				( objectStatus "@baseboard_fab2_lib.baseboard_fab2(sch_1):page157_i346" )
			)
			( gate "R2M5"
				( objectStatus "@baseboard_fab2_lib.baseboard_fab2(sch_1):page157_i348" )
			)
			( gate "S8E1"
				( objectStatus "@baseboard_fab2_lib.baseboard_fab2(sch_1):page157_i351" )
			)
			( gate "R2R9"
				( objectStatus "@baseboard_fab2_lib.baseboard_fab2(sch_1):page157_i352" )
			)
			( gate "C2R12"
				( objectStatus "@baseboard_fab2_lib.baseboard_fab2(sch_1):page157_i353" )
			)
			( gate "U2R1"
				( objectStatus "@baseboard_fab2_lib.baseboard_fab2(sch_1):page157_i356" )
			)
			( gate "U2R1"
				( objectStatus "@baseboard_fab2_lib.baseboard_fab2(sch_1):page157_i357" )
			)
			( gate "R2R10"
				( objectStatus "@baseboard_fab2_lib.baseboard_fab2(sch_1):page157_i358" )
			)
			( gate "R8E19"
				( objectStatus "@baseboard_fab2_lib.baseboard_fab2(sch_1):page157_i361" )
			)
			( gate "R2U4"
				( objectStatus "@baseboard_fab2_lib.baseboard_fab2(sch_1):page157_i367" )
			)
			( gate "R4R1"
				( objectStatus "@baseboard_fab2_lib.baseboard_fab2(sch_1):page157_i368" )
			)
			( gate "C2T3"
				( objectStatus "@baseboard_fab2_lib.baseboard_fab2(sch_1):page157_i370" )
			)
			( gate "U8D2"
				( objectStatus "@baseboard_fab2_lib.baseboard_fab2(sch_1):page157_i374" )
			)
			( gate "C8D1"
				( objectStatus "@baseboard_fab2_lib.baseboard_fab2(sch_1):page157_i376" )
			)
			( gate "R9E14"
				( objectStatus "@baseboard_fab2_lib.baseboard_fab2(sch_1):page157_i379" )
			)
			( gate "R1L7"
				( objectStatus "@baseboard_fab2_lib.baseboard_fab2(sch_1):page157_i382" )
			)
			( gate "R8E32"
				( objectStatus "@baseboard_fab2_lib.baseboard_fab2(sch_1):page157_i385" )
			)
			( gate "R8D22"
				( objectStatus "@baseboard_fab2_lib.baseboard_fab2(sch_1):page157_i386" )
			)
			( gate "R8D36"
				( objectStatus "@baseboard_fab2_lib.baseboard_fab2(sch_1):page157_i388" )
			)
			( gate "C1T10"
				( objectStatus "@baseboard_fab2_lib.baseboard_fab2(sch_1):page158_i70" )
			)
			( gate "U9F2"
				( objectStatus "@baseboard_fab2_lib.baseboard_fab2(sch_1):page158_i74" )
			)
			( gate "U9F1"
				( objectStatus "@baseboard_fab2_lib.baseboard_fab2(sch_1):page158_i75" )
			)
			( gate "R9F25"
				( objectStatus "@baseboard_fab2_lib.baseboard_fab2(sch_1):page158_i86" )
			)
			( gate "R9F27"
				( objectStatus "@baseboard_fab2_lib.baseboard_fab2(sch_1):page158_i91" )
			)
			( gate "C1T11"
				( objectStatus "@baseboard_fab2_lib.baseboard_fab2(sch_1):page158_i97" )
			)
			( gate "R9F26"
				( objectStatus "@baseboard_fab2_lib.baseboard_fab2(sch_1):page158_i99" )
			)
			( gate "R9F24"
				( objectStatus "@baseboard_fab2_lib.baseboard_fab2(sch_1):page158_i100" )
			)
			( gate "DS9A4"
				( objectStatus "@baseboard_fab2_lib.baseboard_fab2(sch_1):page158_i130" )
			)
			( gate "R1L43"
				( objectStatus "@baseboard_fab2_lib.baseboard_fab2(sch_1):page158_i131" )
			)
			( gate "DS9A7"
				( objectStatus "@baseboard_fab2_lib.baseboard_fab2(sch_1):page158_i134" )
			)
			( gate "R1L44"
				( objectStatus "@baseboard_fab2_lib.baseboard_fab2(sch_1):page158_i136" )
			)
			( gate "R9F31"
				( objectStatus "@baseboard_fab2_lib.baseboard_fab2(sch_1):page239_i98" )
			)
			( gate "R9F67"
				( objectStatus "@baseboard_fab2_lib.baseboard_fab2(sch_1):page181_i279" )
			)
			( gate "R8G3"
				( objectStatus "@baseboard_fab2_lib.baseboard_fab2(sch_1):page159_i210" )
			)
			( gate "R8G6"
				( objectStatus "@baseboard_fab2_lib.baseboard_fab2(sch_1):page159_i212" )
			)
			( gate "R2U5"
				( objectStatus "@baseboard_fab2_lib.baseboard_fab2(sch_1):page159_i214" )
			)
			( gate "R2U13"
				( objectStatus "@baseboard_fab2_lib.baseboard_fab2(sch_1):page159_i216" )
			)
			( gate "R2U1"
				( objectStatus "@baseboard_fab2_lib.baseboard_fab2(sch_1):page159_i218" )
			)
			( gate "R2T49"
				( objectStatus "@baseboard_fab2_lib.baseboard_fab2(sch_1):page159_i219" )
			)
			( gate "R2U7"
				( objectStatus "@baseboard_fab2_lib.baseboard_fab2(sch_1):page159_i220" )
			)
			( gate "R2U10"
				( objectStatus "@baseboard_fab2_lib.baseboard_fab2(sch_1):page159_i221" )
			)
			( gate "R1U11"
				( objectStatus "@baseboard_fab2_lib.baseboard_fab2(sch_1):page159_i222" )
			)
			( gate "R1U8"
				( objectStatus "@baseboard_fab2_lib.baseboard_fab2(sch_1):page159_i223" )
			)
			( gate "R9G12"
				( objectStatus "@baseboard_fab2_lib.baseboard_fab2(sch_1):page159_i224" )
			)
			( gate "R1U20"
				( objectStatus "@baseboard_fab2_lib.baseboard_fab2(sch_1):page159_i225" )
			)
			( gate "R1U19"
				( objectStatus "@baseboard_fab2_lib.baseboard_fab2(sch_1):page159_i226" )
			)
			( gate "R9G13"
				( objectStatus "@baseboard_fab2_lib.baseboard_fab2(sch_1):page159_i227" )
			)
			( gate "R8G5"
				( objectStatus "@baseboard_fab2_lib.baseboard_fab2(sch_1):page159_i228" )
			)
			( gate "R8G4"
				( objectStatus "@baseboard_fab2_lib.baseboard_fab2(sch_1):page159_i229" )
			)
			( gate "R2U34"
				( objectStatus "@baseboard_fab2_lib.baseboard_fab2(sch_1):page159_i230" )
			)
			( gate "R2U33"
				( objectStatus "@baseboard_fab2_lib.baseboard_fab2(sch_1):page159_i231" )
			)
			( gate "R1U9"
				( objectStatus "@baseboard_fab2_lib.baseboard_fab2(sch_1):page159_i232" )
			)
			( gate "R1U10"
				( objectStatus "@baseboard_fab2_lib.baseboard_fab2(sch_1):page159_i233" )
			)
			( gate "R1T8"
				( objectStatus "@baseboard_fab2_lib.baseboard_fab2(sch_1):page160_i4" )
			)
			( gate "R1T3"
				( objectStatus "@baseboard_fab2_lib.baseboard_fab2(sch_1):page160_i46" )
			)
			( gate "R1T2"
				( objectStatus "@baseboard_fab2_lib.baseboard_fab2(sch_1):page160_i49" )
			)
			( gate "R1T7"
				( objectStatus "@baseboard_fab2_lib.baseboard_fab2(sch_1):page160_i50" )
			)
			( gate "R9F23"
				( objectStatus "@baseboard_fab2_lib.baseboard_fab2(sch_1):page160_i51" )
			)
			( gate "R9F22"
				( objectStatus "@baseboard_fab2_lib.baseboard_fab2(sch_1):page160_i52" )
			)
			( gate "J1F2"
				( objectStatus "@baseboard_fab2_lib.baseboard_fab2(sch_1):page161_i1" )
			)
			( gate "C1E21"
				( objectStatus "@baseboard_fab2_lib.baseboard_fab2(sch_1):page161_i3" )
			)
			( gate "C1E20"
				( objectStatus "@baseboard_fab2_lib.baseboard_fab2(sch_1):page161_i4" )
			)
			( gate "C9M5"
				( objectStatus "@baseboard_fab2_lib.baseboard_fab2(sch_1):page161_i26" )
			)
			( gate "C9M4"
				( objectStatus "@baseboard_fab2_lib.baseboard_fab2(sch_1):page161_i27" )
			)
			( gate "J1B2"
				( objectStatus "@baseboard_fab2_lib.baseboard_fab2(sch_1):page161_i32" )
			)
			( gate "CR1F1"
				( objectStatus "@baseboard_fab2_lib.baseboard_fab2(sch_1):page161_i42" )
			)
			( gate "R1F2"
				( objectStatus "@baseboard_fab2_lib.baseboard_fab2(sch_1):page161_i43" )
			)
			( gate "R1F1"
				( objectStatus "@baseboard_fab2_lib.baseboard_fab2(sch_1):page161_i45" )
			)
			( gate "C1F9"
				( objectStatus "@baseboard_fab2_lib.baseboard_fab2(sch_1):page161_i46" )
			)
			( gate "CR1E1"
				( objectStatus "@baseboard_fab2_lib.baseboard_fab2(sch_1):page161_i50" )
			)
			( gate "R1E12"
				( objectStatus "@baseboard_fab2_lib.baseboard_fab2(sch_1):page161_i51" )
			)
			( gate "CR1B2"
				( objectStatus "@baseboard_fab2_lib.baseboard_fab2(sch_1):page161_i62" )
			)
			( gate "CR1B1"
				( objectStatus "@baseboard_fab2_lib.baseboard_fab2(sch_1):page161_i64" )
			)
			( gate "R7F33"
				( objectStatus "@baseboard_fab2_lib.baseboard_fab2(sch_1):page161_i65" )
			)
			( gate "R1B22"
				( objectStatus "@baseboard_fab2_lib.baseboard_fab2(sch_1):page161_i67" )
			)
			( gate "C1B15"
				( objectStatus "@baseboard_fab2_lib.baseboard_fab2(sch_1):page161_i68" )
			)
			( gate "R1B21"
				( objectStatus "@baseboard_fab2_lib.baseboard_fab2(sch_1):page161_i70" )
			)
			( gate "U8G2"
				( objectStatus "@baseboard_fab2_lib.baseboard_fab2(sch_1):page161_i88" )
			)
			( gate "C2U27"
				( objectStatus "@baseboard_fab2_lib.baseboard_fab2(sch_1):page161_i90" )
			)
			( gate "U8G3"
				( objectStatus "@baseboard_fab2_lib.baseboard_fab2(sch_1):page161_i92" )
			)
			( gate "C2U28"
				( objectStatus "@baseboard_fab2_lib.baseboard_fab2(sch_1):page161_i93" )
			)
			( gate "R2U42"
				( objectStatus "@baseboard_fab2_lib.baseboard_fab2(sch_1):page161_i99" )
			)
			( gate "R2U44"
				( objectStatus "@baseboard_fab2_lib.baseboard_fab2(sch_1):page161_i102" )
			)
			( gate "C1E22"
				( objectStatus "@baseboard_fab2_lib.baseboard_fab2(sch_1):page161_i113" )
			)
			( gate "R1E11"
				( objectStatus "@baseboard_fab2_lib.baseboard_fab2(sch_1):page161_i120" )
			)
			( gate "U1E2"
				( objectStatus "@baseboard_fab2_lib.baseboard_fab2(sch_1):page161_i121" )
			)
			( gate "CR1B3"
				( objectStatus "@baseboard_fab2_lib.baseboard_fab2(sch_1):page161_i123" )
			)
			( gate "R1B23"
				( objectStatus "@baseboard_fab2_lib.baseboard_fab2(sch_1):page161_i124" )
			)
			( gate "R1B24"
				( objectStatus "@baseboard_fab2_lib.baseboard_fab2(sch_1):page161_i126" )
			)
			( gate "C1B17"
				( objectStatus "@baseboard_fab2_lib.baseboard_fab2(sch_1):page161_i128" )
			)
			( gate "CR1F2"
				( objectStatus "@baseboard_fab2_lib.baseboard_fab2(sch_1):page161_i133" )
			)
			( gate "R9T7"
				( objectStatus "@baseboard_fab2_lib.baseboard_fab2(sch_1):page161_i134" )
			)
			( gate "R9T5"
				( objectStatus "@baseboard_fab2_lib.baseboard_fab2(sch_1):page161_i135" )
			)
			( gate "C9T1"
				( objectStatus "@baseboard_fab2_lib.baseboard_fab2(sch_1):page161_i137" )
			)
			( gate "R8F16"
				( objectStatus "@baseboard_fab2_lib.baseboard_fab2(sch_1):page162_i8" )
			)
			( gate "R8F14"
				( objectStatus "@baseboard_fab2_lib.baseboard_fab2(sch_1):page162_i9" )
			)
			( gate "R8F12"
				( objectStatus "@baseboard_fab2_lib.baseboard_fab2(sch_1):page162_i13" )
			)
			( gate "R8F34"
				( objectStatus "@baseboard_fab2_lib.baseboard_fab2(sch_1):page162_i22" )
			)
			( gate "R8F13"
				( objectStatus "@baseboard_fab2_lib.baseboard_fab2(sch_1):page162_i23" )
			)
			( gate "R8F35"
				( objectStatus "@baseboard_fab2_lib.baseboard_fab2(sch_1):page162_i24" )
			)
			( gate "C8F5"
				( objectStatus "@baseboard_fab2_lib.baseboard_fab2(sch_1):page162_i28" )
			)
			( gate "C8F4"
				( objectStatus "@baseboard_fab2_lib.baseboard_fab2(sch_1):page162_i30" )
			)
			( gate "U8F2"
				( objectStatus "@baseboard_fab2_lib.baseboard_fab2(sch_1):page162_i32" )
			)
			( gate "U1B2"
				( objectStatus "@baseboard_fab2_lib.baseboard_fab2(sch_1):page163_i1" )
			)
			( gate "R6N8"
				( objectStatus "@baseboard_fab2_lib.baseboard_fab2(sch_1):page163_i2" )
			)
			( gate "R6N9"
				( objectStatus "@baseboard_fab2_lib.baseboard_fab2(sch_1):page163_i3" )
			)
			( gate "R9M18"
				( objectStatus "@baseboard_fab2_lib.baseboard_fab2(sch_1):page163_i6" )
			)
			( gate "R9M19"
				( objectStatus "@baseboard_fab2_lib.baseboard_fab2(sch_1):page163_i7" )
			)
			( gate "C9M8"
				( objectStatus "@baseboard_fab2_lib.baseboard_fab2(sch_1):page163_i10" )
			)
			( gate "C9M7"
				( objectStatus "@baseboard_fab2_lib.baseboard_fab2(sch_1):page163_i12" )
			)
			( gate "R9M17"
				( objectStatus "@baseboard_fab2_lib.baseboard_fab2(sch_1):page163_i15" )
			)
			( gate "R9M16"
				( objectStatus "@baseboard_fab2_lib.baseboard_fab2(sch_1):page163_i16" )
			)
			( gate "R9M14"
				( objectStatus "@baseboard_fab2_lib.baseboard_fab2(sch_1):page163_i20" )
			)
			( gate "R9M13"
				( objectStatus "@baseboard_fab2_lib.baseboard_fab2(sch_1):page163_i21" )
			)
			( gate "R9M12"
				( objectStatus "@baseboard_fab2_lib.baseboard_fab2(sch_1):page163_i24" )
			)
			( gate "R9M15"
				( objectStatus "@baseboard_fab2_lib.baseboard_fab2(sch_1):page163_i25" )
			)
			( gate "R1T10"
				( objectStatus "@baseboard_fab2_lib.baseboard_fab2(sch_1):page164_i5" )
			)
			( gate "R1T12"
				( objectStatus "@baseboard_fab2_lib.baseboard_fab2(sch_1):page164_i6" )
			)
			( gate "R1T11"
				( objectStatus "@baseboard_fab2_lib.baseboard_fab2(sch_1):page164_i7" )
			)
			( gate "R1T5"
				( objectStatus "@baseboard_fab2_lib.baseboard_fab2(sch_1):page164_i11" )
			)
			( gate "R1T6"
				( objectStatus "@baseboard_fab2_lib.baseboard_fab2(sch_1):page164_i13" )
			)
			( gate "R1T4"
				( objectStatus "@baseboard_fab2_lib.baseboard_fab2(sch_1):page164_i14" )
			)
			( gate "R1U18"
				( objectStatus "@baseboard_fab2_lib.baseboard_fab2(sch_1):page164_i19" )
			)
			( gate "R1U16"
				( objectStatus "@baseboard_fab2_lib.baseboard_fab2(sch_1):page164_i20" )
			)
			( gate "R1U17"
				( objectStatus "@baseboard_fab2_lib.baseboard_fab2(sch_1):page164_i21" )
			)
			( gate "R1U15"
				( objectStatus "@baseboard_fab2_lib.baseboard_fab2(sch_1):page164_i22" )
			)
			( gate "R1U21"
				( objectStatus "@baseboard_fab2_lib.baseboard_fab2(sch_1):page164_i24" )
			)
			( gate "R1U24"
				( objectStatus "@baseboard_fab2_lib.baseboard_fab2(sch_1):page164_i25" )
			)
			( gate "R1U22"
				( objectStatus "@baseboard_fab2_lib.baseboard_fab2(sch_1):page164_i27" )
			)
			( gate "R1U23"
				( objectStatus "@baseboard_fab2_lib.baseboard_fab2(sch_1):page164_i28" )
			)
			( gate "R2N17"
				( objectStatus "@baseboard_fab2_lib.baseboard_fab2(sch_1):page164_i29" )
			)
			( gate "R2N18"
				( objectStatus "@baseboard_fab2_lib.baseboard_fab2(sch_1):page164_i32" )
			)
			( gate "EU9G1"
				( objectStatus "@baseboard_fab2_lib.baseboard_fab2(sch_1):page165_i52" )
			)
			( gate "R1U45"
				( objectStatus "@baseboard_fab2_lib.baseboard_fab2(sch_1):page165_i55" )
			)
			( gate "R1U48"
				( objectStatus "@baseboard_fab2_lib.baseboard_fab2(sch_1):page165_i56" )
			)
			( gate "R9G23"
				( objectStatus "@baseboard_fab2_lib.baseboard_fab2(sch_1):page165_i57" )
			)
			( gate "R9G25"
				( objectStatus "@baseboard_fab2_lib.baseboard_fab2(sch_1):page165_i58" )
			)
			( gate "C9G19"
				( objectStatus "@baseboard_fab2_lib.baseboard_fab2(sch_1):page165_i61" )
			)
			( gate "C1U20"
				( objectStatus "@baseboard_fab2_lib.baseboard_fab2(sch_1):page165_i67" )
			)
			( gate "R9G21"
				( objectStatus "@baseboard_fab2_lib.baseboard_fab2(sch_1):page165_i69" )
			)
			( gate "FB1U2"
				( objectStatus "@baseboard_fab2_lib.baseboard_fab2(sch_1):page165_i79" )
			)
			( gate "R1U40"
				( objectStatus "@baseboard_fab2_lib.baseboard_fab2(sch_1):page165_i81" )
			)
			( gate "R7C18"
				( objectStatus "@baseboard_fab2_lib.baseboard_fab2(sch_1):page166_i11" )
			)
			( gate "R7C22"
				( objectStatus "@baseboard_fab2_lib.baseboard_fab2(sch_1):page166_i14" )
			)
			( gate "R7C19"
				( objectStatus "@baseboard_fab2_lib.baseboard_fab2(sch_1):page166_i15" )
			)
			( gate "R7C17"
				( objectStatus "@baseboard_fab2_lib.baseboard_fab2(sch_1):page166_i28" )
			)
			( gate "R7D15"
				( objectStatus "@baseboard_fab2_lib.baseboard_fab2(sch_1):page166_i32" )
			)
			( gate "U9B4"
				( objectStatus "@baseboard_fab2_lib.baseboard_fab2(sch_1):page167_i1" )
			)
			( gate "Q9B1"
				( objectStatus "@baseboard_fab2_lib.baseboard_fab2(sch_1):page167_i3" )
			)
			( gate "R9B5"
				( objectStatus "@baseboard_fab2_lib.baseboard_fab2(sch_1):page167_i5" )
			)
			( gate "R9B4"
				( objectStatus "@baseboard_fab2_lib.baseboard_fab2(sch_1):page167_i6" )
			)
			( gate "C1M4"
				( objectStatus "@baseboard_fab2_lib.baseboard_fab2(sch_1):page167_i7" )
			)
			( gate "R1M9"
				( objectStatus "@baseboard_fab2_lib.baseboard_fab2(sch_1):page167_i8" )
			)
			( gate "R9B8"
				( objectStatus "@baseboard_fab2_lib.baseboard_fab2(sch_1):page167_i10" )
			)
			( gate "C1E19"
				( objectStatus "@baseboard_fab2_lib.baseboard_fab2(sch_1):page167_i24" )
			)
			( gate "R9R5"
				( objectStatus "@baseboard_fab2_lib.baseboard_fab2(sch_1):page167_i25" )
			)
			( gate "R9R6"
				( objectStatus "@baseboard_fab2_lib.baseboard_fab2(sch_1):page167_i26" )
			)
			( gate "Q1E1"
				( objectStatus "@baseboard_fab2_lib.baseboard_fab2(sch_1):page167_i27" )
			)
			( gate "U1E1"
				( objectStatus "@baseboard_fab2_lib.baseboard_fab2(sch_1):page167_i30" )
			)
			( gate "R1E9"
				( objectStatus "@baseboard_fab2_lib.baseboard_fab2(sch_1):page167_i34" )
			)
			( gate "R9B6"
				( objectStatus "@baseboard_fab2_lib.baseboard_fab2(sch_1):page167_i35" )
			)
			( gate "R1E10"
				( objectStatus "@baseboard_fab2_lib.baseboard_fab2(sch_1):page167_i38" )
			)
			( gate "C9B7"
				( objectStatus "@baseboard_fab2_lib.baseboard_fab2(sch_1):page167_i39" )
			)
			( gate "C9R14"
				( objectStatus "@baseboard_fab2_lib.baseboard_fab2(sch_1):page167_i41" )
			)
			( gate "C9R13"
				( objectStatus "@baseboard_fab2_lib.baseboard_fab2(sch_1):page167_i42" )
			)
			( gate "U8D4"
				( objectStatus "@baseboard_fab2_lib.baseboard_fab2(sch_1):page167_i49" )
			)
			( gate "R8D27"
				( objectStatus "@baseboard_fab2_lib.baseboard_fab2(sch_1):page167_i50" )
			)
			( gate "R9G15"
				( objectStatus "@baseboard_fab2_lib.baseboard_fab2(sch_1):page167_i58" )
			)
			( gate "R8D28"
				( objectStatus "@baseboard_fab2_lib.baseboard_fab2(sch_1):page167_i70" )
			)
			( gate "R1M8"
				( objectStatus "@baseboard_fab2_lib.baseboard_fab2(sch_1):page167_i74" )
			)
			( gate "R9R7"
				( objectStatus "@baseboard_fab2_lib.baseboard_fab2(sch_1):page167_i75" )
			)
			( gate "R9R8"
				( objectStatus "@baseboard_fab2_lib.baseboard_fab2(sch_1):page167_i76" )
			)
			( gate "R9G14"
				( objectStatus "@baseboard_fab2_lib.baseboard_fab2(sch_1):page167_i77" )
			)
			( gate "R1U31"
				( objectStatus "@baseboard_fab2_lib.baseboard_fab2(sch_1):page167_i78" )
			)
			( gate "R1U25"
				( objectStatus "@baseboard_fab2_lib.baseboard_fab2(sch_1):page167_i79" )
			)
			( gate "R2U38"
				( objectStatus "@baseboard_fab2_lib.baseboard_fab2(sch_1):page167_i80" )
			)
			( gate "R2U39"
				( objectStatus "@baseboard_fab2_lib.baseboard_fab2(sch_1):page167_i83" )
			)
			( gate "R8D24"
				( objectStatus "@baseboard_fab2_lib.baseboard_fab2(sch_1):page167_i84" )
			)
			( gate "R8D23"
				( objectStatus "@baseboard_fab2_lib.baseboard_fab2(sch_1):page167_i85" )
			)
			( gate "CR1L1"
				( objectStatus "@baseboard_fab2_lib.baseboard_fab2(sch_1):page168_i2" )
			)
			( gate "CR1L2"
				( objectStatus "@baseboard_fab2_lib.baseboard_fab2(sch_1):page168_i3" )
			)
			( gate "CR1L3"
				( objectStatus "@baseboard_fab2_lib.baseboard_fab2(sch_1):page168_i4" )
			)
			( gate "CR1L4"
				( objectStatus "@baseboard_fab2_lib.baseboard_fab2(sch_1):page168_i5" )
			)
			( gate "R1L6"
				( objectStatus "@baseboard_fab2_lib.baseboard_fab2(sch_1):page168_i6" )
			)
			( gate "R6W17"
				( objectStatus "@baseboard_fab2_lib.baseboard_fab2(sch_1):page144_i89" )
			)
			( gate "Q1L3"
				( objectStatus "@baseboard_fab2_lib.baseboard_fab2(sch_1):page168_i8" )
			)
			( gate "R6W18"
				( objectStatus "@baseboard_fab2_lib.baseboard_fab2(sch_1):page144_i90" )
			)
			( gate "R1L36"
				( objectStatus "@baseboard_fab2_lib.baseboard_fab2(sch_1):page168_i11" )
			)
			( gate "Q1L4"
				( objectStatus "@baseboard_fab2_lib.baseboard_fab2(sch_1):page168_i18" )
			)
			( gate "Q1L4"
				( objectStatus "@baseboard_fab2_lib.baseboard_fab2(sch_1):page168_i19" )
			)
			( gate "R1L38"
				( objectStatus "@baseboard_fab2_lib.baseboard_fab2(sch_1):page168_i22" )
			)
			( gate "C1U21"
				( objectStatus "@baseboard_fab2_lib.baseboard_fab2(sch_1):page169_i56" )
			)
			( gate "FB1U3"
				( objectStatus "@baseboard_fab2_lib.baseboard_fab2(sch_1):page169_i57" )
			)
			( gate "C9G21"
				( objectStatus "@baseboard_fab2_lib.baseboard_fab2(sch_1):page169_i68" )
			)
			( gate "C9G17"
				( objectStatus "@baseboard_fab2_lib.baseboard_fab2(sch_1):page169_i80" )
			)
			( gate "R1U32"
				( objectStatus "@baseboard_fab2_lib.baseboard_fab2(sch_1):page169_i82" )
			)
			( gate "R1U33"
				( objectStatus "@baseboard_fab2_lib.baseboard_fab2(sch_1):page169_i83" )
			)
			( gate "C9G20"
				( objectStatus "@baseboard_fab2_lib.baseboard_fab2(sch_1):page169_i86" )
			)
			( gate "R1U39"
				( objectStatus "@baseboard_fab2_lib.baseboard_fab2(sch_1):page169_i88" )
			)
			( gate "R9G26"
				( objectStatus "@baseboard_fab2_lib.baseboard_fab2(sch_1):page169_i106" )
			)
			( gate "C9G22"
				( objectStatus "@baseboard_fab2_lib.baseboard_fab2(sch_1):page169_i108" )
			)
			( gate "R1U38"
				( objectStatus "@baseboard_fab2_lib.baseboard_fab2(sch_1):page169_i114" )
			)
			( gate "R1U47"
				( objectStatus "@baseboard_fab2_lib.baseboard_fab2(sch_1):page169_i115" )
			)
			( gate "R1U44"
				( objectStatus "@baseboard_fab2_lib.baseboard_fab2(sch_1):page169_i116" )
			)
			( gate "R1U50"
				( objectStatus "@baseboard_fab2_lib.baseboard_fab2(sch_1):page169_i126" )
			)
			( gate "C9G15"
				( objectStatus "@baseboard_fab2_lib.baseboard_fab2(sch_1):page169_i139" )
			)
			( gate "R1U29"
				( objectStatus "@baseboard_fab2_lib.baseboard_fab2(sch_1):page169_i141" )
			)
			( gate "R1U28"
				( objectStatus "@baseboard_fab2_lib.baseboard_fab2(sch_1):page169_i142" )
			)
			( gate "C9G14"
				( objectStatus "@baseboard_fab2_lib.baseboard_fab2(sch_1):page169_i146" )
			)
			( gate "R1U26"
				( objectStatus "@baseboard_fab2_lib.baseboard_fab2(sch_1):page169_i148" )
			)
			( gate "R1U27"
				( objectStatus "@baseboard_fab2_lib.baseboard_fab2(sch_1):page169_i149" )
			)
			( gate "C9G18"
				( objectStatus "@baseboard_fab2_lib.baseboard_fab2(sch_1):page169_i153" )
			)
			( gate "FB1U4"
				( objectStatus "@baseboard_fab2_lib.baseboard_fab2(sch_1):page169_i155" )
			)
			( gate "Q9G1"
				( objectStatus "@baseboard_fab2_lib.baseboard_fab2(sch_1):page169_i157" )
			)
			( gate "Q9G1"
				( objectStatus "@baseboard_fab2_lib.baseboard_fab2(sch_1):page169_i162" )
			)
			( gate "R1U49"
				( objectStatus "@baseboard_fab2_lib.baseboard_fab2(sch_1):page169_i163" )
			)
			( gate "R9G35"
				( objectStatus "@baseboard_fab2_lib.baseboard_fab2(sch_1):page169_i164" )
			)
			( gate "R2P3"
				( objectStatus "@baseboard_fab2_lib.baseboard_fab2(sch_1):page170_i2" )
			)
			( gate "U8D3"
				( objectStatus "@baseboard_fab2_lib.baseboard_fab2(sch_1):page170_i4" )
			)
			( gate "C2P1"
				( objectStatus "@baseboard_fab2_lib.baseboard_fab2(sch_1):page170_i8" )
			)
			( gate "U8E1"
				( objectStatus "@baseboard_fab2_lib.baseboard_fab2(sch_1):page170_i10" )
			)
			( gate "U8E1"
				( objectStatus "@baseboard_fab2_lib.baseboard_fab2(sch_1):page170_i11" )
			)
			( gate "U8E1"
				( objectStatus "@baseboard_fab2_lib.baseboard_fab2(sch_1):page170_i12" )
			)
			( gate "U1R2"
				( objectStatus "@baseboard_fab2_lib.baseboard_fab2(sch_1):page170_i20" )
			)
			( gate "C1R27"
				( objectStatus "@baseboard_fab2_lib.baseboard_fab2(sch_1):page170_i30" )
			)
			( gate "C8D2"
				( objectStatus "@baseboard_fab2_lib.baseboard_fab2(sch_1):page170_i33" )
			)
			( gate "U8D5"
				( objectStatus "@baseboard_fab2_lib.baseboard_fab2(sch_1):page170_i38" )
			)
			( gate "C8E2"
				( objectStatus "@baseboard_fab2_lib.baseboard_fab2(sch_1):page170_i40" )
			)
			( gate "C8D3"
				( objectStatus "@baseboard_fab2_lib.baseboard_fab2(sch_1):page170_i42" )
			)
			( gate "U1R1"
				( objectStatus "@baseboard_fab2_lib.baseboard_fab2(sch_1):page170_i46" )
			)
			( gate "C1R28"
				( objectStatus "@baseboard_fab2_lib.baseboard_fab2(sch_1):page170_i49" )
			)
			( gate "R1R8"
				( objectStatus "@baseboard_fab2_lib.baseboard_fab2(sch_1):page170_i51" )
			)
			( gate "R2P8"
				( objectStatus "@baseboard_fab2_lib.baseboard_fab2(sch_1):page170_i52" )
			)
			( gate "R2T3"
				( objectStatus "@baseboard_fab2_lib.baseboard_fab2(sch_1):page170_i54" )
			)
			( gate "R2P5"
				( objectStatus "@baseboard_fab2_lib.baseboard_fab2(sch_1):page170_i56" )
			)
			( gate "Q2P1"
				( objectStatus "@baseboard_fab2_lib.baseboard_fab2(sch_1):page170_i58" )
			)
			( gate "R2P13"
				( objectStatus "@baseboard_fab2_lib.baseboard_fab2(sch_1):page170_i61" )
			)
			( gate "R2P11"
				( objectStatus "@baseboard_fab2_lib.baseboard_fab2(sch_1):page170_i63" )
			)
			( gate "R9F3"
				( objectStatus "@baseboard_fab2_lib.baseboard_fab2(sch_1):page170_i65" )
			)
			( gate "Q8F2"
				( objectStatus "@baseboard_fab2_lib.baseboard_fab2(sch_1):page170_i67" )
			)
			( gate "R8D26"
				( objectStatus "@baseboard_fab2_lib.baseboard_fab2(sch_1):page170_i71" )
			)
			( gate "R1R5"
				( objectStatus "@baseboard_fab2_lib.baseboard_fab2(sch_1):page170_i73" )
			)
			( gate "R2P4"
				( objectStatus "@baseboard_fab2_lib.baseboard_fab2(sch_1):page170_i74" )
			)
			( gate "C2L49"
				( objectStatus "@baseboard_fab2_lib.baseboard_fab2(sch_1):page172_i5" )
			)
			( gate "C2L52"
				( objectStatus "@baseboard_fab2_lib.baseboard_fab2(sch_1):page172_i6" )
			)
			( gate "C2L50"
				( objectStatus "@baseboard_fab2_lib.baseboard_fab2(sch_1):page172_i7" )
			)
			( gate "C2L51"
				( objectStatus "@baseboard_fab2_lib.baseboard_fab2(sch_1):page172_i8" )
			)
			( gate "J8A3"
				( objectStatus "@baseboard_fab2_lib.baseboard_fab2(sch_1):page172_i17" )
			)
			( gate "J8A4"
				( objectStatus "@baseboard_fab2_lib.baseboard_fab2(sch_1):page172_i25" )
			)
			( gate "C9B2"
				( objectStatus "@baseboard_fab2_lib.baseboard_fab2(sch_1):page172_i36" )
			)
			( gate "F9B1"
				( objectStatus "@baseboard_fab2_lib.baseboard_fab2(sch_1):page172_i38" )
			)
			( gate "C9B1"
				( objectStatus "@baseboard_fab2_lib.baseboard_fab2(sch_1):page172_i39" )
			)
			( gate "F8B1"
				( objectStatus "@baseboard_fab2_lib.baseboard_fab2(sch_1):page172_i41" )
			)
			( gate "J2M1"
				( objectStatus "@baseboard_fab2_lib.baseboard_fab2(sch_1):page172_i52" )
			)
			( gate "J2L1"
				( objectStatus "@baseboard_fab2_lib.baseboard_fab2(sch_1):page172_i53" )
			)
			( gate "J8A1"
				( objectStatus "@baseboard_fab2_lib.baseboard_fab2(sch_1):page173_i163" )
			)
			( gate "C2L13"
				( objectStatus "@baseboard_fab2_lib.baseboard_fab2(sch_1):page173_i165" )
			)
			( gate "C2L6"
				( objectStatus "@baseboard_fab2_lib.baseboard_fab2(sch_1):page173_i166" )
			)
			( gate "C2L19"
				( objectStatus "@baseboard_fab2_lib.baseboard_fab2(sch_1):page173_i172" )
			)
			( gate "C2L10"
				( objectStatus "@baseboard_fab2_lib.baseboard_fab2(sch_1):page173_i173" )
			)
			( gate "C2L17"
				( objectStatus "@baseboard_fab2_lib.baseboard_fab2(sch_1):page173_i174" )
			)
			( gate "C2L15"
				( objectStatus "@baseboard_fab2_lib.baseboard_fab2(sch_1):page173_i191" )
			)
			( gate "C2L4"
				( objectStatus "@baseboard_fab2_lib.baseboard_fab2(sch_1):page173_i192" )
			)
			( gate "C2L3"
				( objectStatus "@baseboard_fab2_lib.baseboard_fab2(sch_1):page173_i194" )
			)
			( gate "C2L20"
				( objectStatus "@baseboard_fab2_lib.baseboard_fab2(sch_1):page173_i195" )
			)
			( gate "C2L12"
				( objectStatus "@baseboard_fab2_lib.baseboard_fab2(sch_1):page173_i196" )
			)
			( gate "C2L18"
				( objectStatus "@baseboard_fab2_lib.baseboard_fab2(sch_1):page173_i197" )
			)
			( gate "C2L16"
				( objectStatus "@baseboard_fab2_lib.baseboard_fab2(sch_1):page173_i205" )
			)
			( gate "C2L7"
				( objectStatus "@baseboard_fab2_lib.baseboard_fab2(sch_1):page173_i206" )
			)
			( gate "C2L9"
				( objectStatus "@baseboard_fab2_lib.baseboard_fab2(sch_1):page173_i207" )
			)
			( gate "C2L14"
				( objectStatus "@baseboard_fab2_lib.baseboard_fab2(sch_1):page173_i208" )
			)
			( gate "C2L5"
				( objectStatus "@baseboard_fab2_lib.baseboard_fab2(sch_1):page173_i209" )
			)
			( gate "C2L40"
				( objectStatus "@baseboard_fab2_lib.baseboard_fab2(sch_1):page173_i220" )
			)
			( gate "C2L39"
				( objectStatus "@baseboard_fab2_lib.baseboard_fab2(sch_1):page173_i221" )
			)
			( gate "C2L43"
				( objectStatus "@baseboard_fab2_lib.baseboard_fab2(sch_1):page173_i222" )
			)
			( gate "C2L44"
				( objectStatus "@baseboard_fab2_lib.baseboard_fab2(sch_1):page173_i228" )
			)
			( gate "C2L42"
				( objectStatus "@baseboard_fab2_lib.baseboard_fab2(sch_1):page173_i233" )
			)
			( gate "C2L22"
				( objectStatus "@baseboard_fab2_lib.baseboard_fab2(sch_1):page173_i234" )
			)
			( gate "C2L37"
				( objectStatus "@baseboard_fab2_lib.baseboard_fab2(sch_1):page173_i238" )
			)
			( gate "C2L47"
				( objectStatus "@baseboard_fab2_lib.baseboard_fab2(sch_1):page173_i239" )
			)
			( gate "C2L27"
				( objectStatus "@baseboard_fab2_lib.baseboard_fab2(sch_1):page173_i240" )
			)
			( gate "C2L23"
				( objectStatus "@baseboard_fab2_lib.baseboard_fab2(sch_1):page173_i241" )
			)
			( gate "C2L41"
				( objectStatus "@baseboard_fab2_lib.baseboard_fab2(sch_1):page173_i242" )
			)
			( gate "C2L26"
				( objectStatus "@baseboard_fab2_lib.baseboard_fab2(sch_1):page173_i255" )
			)
			( gate "C2L38"
				( objectStatus "@baseboard_fab2_lib.baseboard_fab2(sch_1):page173_i256" )
			)
			( gate "C2L48"
				( objectStatus "@baseboard_fab2_lib.baseboard_fab2(sch_1):page173_i257" )
			)
			( gate "C2L24"
				( objectStatus "@baseboard_fab2_lib.baseboard_fab2(sch_1):page173_i258" )
			)
			( gate "C2L21"
				( objectStatus "@baseboard_fab2_lib.baseboard_fab2(sch_1):page173_i259" )
			)
			( gate "R2L23"
				( objectStatus "@baseboard_fab2_lib.baseboard_fab2(sch_1):page173_i261" )
			)
			( gate "R2L21"
				( objectStatus "@baseboard_fab2_lib.baseboard_fab2(sch_1):page173_i263" )
			)
			( gate "R2L22"
				( objectStatus "@baseboard_fab2_lib.baseboard_fab2(sch_1):page173_i264" )
			)
			( gate "R2L18"
				( objectStatus "@baseboard_fab2_lib.baseboard_fab2(sch_1):page173_i266" )
			)
			( gate "R1L3"
				( objectStatus "@baseboard_fab2_lib.baseboard_fab2(sch_1):page174_i5" )
			)
			( gate "C1L3"
				( objectStatus "@baseboard_fab2_lib.baseboard_fab2(sch_1):page174_i8" )
			)
			( gate "C1L2"
				( objectStatus "@baseboard_fab2_lib.baseboard_fab2(sch_1):page174_i9" )
			)
			( gate "C1L7"
				( objectStatus "@baseboard_fab2_lib.baseboard_fab2(sch_1):page174_i12" )
			)
			( gate "C1L6"
				( objectStatus "@baseboard_fab2_lib.baseboard_fab2(sch_1):page174_i13" )
			)
			( gate "C1L13"
				( objectStatus "@baseboard_fab2_lib.baseboard_fab2(sch_1):page174_i14" )
			)
			( gate "C1L15"
				( objectStatus "@baseboard_fab2_lib.baseboard_fab2(sch_1):page174_i18" )
			)
			( gate "C1L12"
				( objectStatus "@baseboard_fab2_lib.baseboard_fab2(sch_1):page174_i19" )
			)
			( gate "C1L14"
				( objectStatus "@baseboard_fab2_lib.baseboard_fab2(sch_1):page174_i20" )
			)
			( gate "R1L1"
				( objectStatus "@baseboard_fab2_lib.baseboard_fab2(sch_1):page174_i25" )
			)
			( gate "J8A2"
				( objectStatus "@baseboard_fab2_lib.baseboard_fab2(sch_1):page174_i26" )
			)
			( gate "C2L30"
				( objectStatus "@baseboard_fab2_lib.baseboard_fab2(sch_1):page174_i28" )
			)
			( gate "C2L31"
				( objectStatus "@baseboard_fab2_lib.baseboard_fab2(sch_1):page174_i29" )
			)
			( gate "C2L28"
				( objectStatus "@baseboard_fab2_lib.baseboard_fab2(sch_1):page174_i30" )
			)
			( gate "C2L35"
				( objectStatus "@baseboard_fab2_lib.baseboard_fab2(sch_1):page174_i31" )
			)
			( gate "C2L29"
				( objectStatus "@baseboard_fab2_lib.baseboard_fab2(sch_1):page174_i32" )
			)
			( gate "C2L36"
				( objectStatus "@baseboard_fab2_lib.baseboard_fab2(sch_1):page174_i39" )
			)
			( gate "C2L33"
				( objectStatus "@baseboard_fab2_lib.baseboard_fab2(sch_1):page174_i40" )
			)
			( gate "C2L34"
				( objectStatus "@baseboard_fab2_lib.baseboard_fab2(sch_1):page174_i41" )
			)
			( gate "R1L31"
				( objectStatus "@baseboard_fab2_lib.baseboard_fab2(sch_1):page175_i4" )
			)
			( gate "R1L27"
				( objectStatus "@baseboard_fab2_lib.baseboard_fab2(sch_1):page175_i5" )
			)
			( gate "U9A4"
				( objectStatus "@baseboard_fab2_lib.baseboard_fab2(sch_1):page175_i9" )
			)
			( gate "U9A4"
				( objectStatus "@baseboard_fab2_lib.baseboard_fab2(sch_1):page175_i10" )
			)
			( gate "C1L18"
				( objectStatus "@baseboard_fab2_lib.baseboard_fab2(sch_1):page175_i11" )
			)
			( gate "R1L26"
				( objectStatus "@baseboard_fab2_lib.baseboard_fab2(sch_1):page175_i13" )
			)
			( gate "U9A3"
				( objectStatus "@baseboard_fab2_lib.baseboard_fab2(sch_1):page175_i15" )
			)
			( gate "U9A3"
				( objectStatus "@baseboard_fab2_lib.baseboard_fab2(sch_1):page175_i18" )
			)
			( gate "C1L10"
				( objectStatus "@baseboard_fab2_lib.baseboard_fab2(sch_1):page175_i19" )
			)
			( gate "R1L22"
				( objectStatus "@baseboard_fab2_lib.baseboard_fab2(sch_1):page175_i22" )
			)
			( gate "R1L19"
				( objectStatus "@baseboard_fab2_lib.baseboard_fab2(sch_1):page175_i24" )
			)
			( gate "R9A9"
				( objectStatus "@baseboard_fab2_lib.baseboard_fab2(sch_1):page175_i35" )
			)
			( gate "C1L17"
				( objectStatus "@baseboard_fab2_lib.baseboard_fab2(sch_1):page175_i37" )
			)
			( gate "C1L9"
				( objectStatus "@baseboard_fab2_lib.baseboard_fab2(sch_1):page175_i38" )
			)
			( gate "C9A3"
				( objectStatus "@baseboard_fab2_lib.baseboard_fab2(sch_1):page175_i40" )
			)
			( gate "R1L33"
				( objectStatus "@baseboard_fab2_lib.baseboard_fab2(sch_1):page175_i45" )
			)
			( gate "Q9A3"
				( objectStatus "@baseboard_fab2_lib.baseboard_fab2(sch_1):page175_i49" )
			)
			( gate "DS9A1"
				( objectStatus "@baseboard_fab2_lib.baseboard_fab2(sch_1):page175_i50" )
			)
			( gate "U1L2"
				( objectStatus "@baseboard_fab2_lib.baseboard_fab2(sch_1):page175_i57" )
			)
			( gate "R1L8"
				( objectStatus "@baseboard_fab2_lib.baseboard_fab2(sch_1):page175_i58" )
			)
			( gate "R1L12"
				( objectStatus "@baseboard_fab2_lib.baseboard_fab2(sch_1):page175_i63" )
			)
			( gate "C1L4"
				( objectStatus "@baseboard_fab2_lib.baseboard_fab2(sch_1):page175_i64" )
			)
			( gate "DS9A3"
				( objectStatus "@baseboard_fab2_lib.baseboard_fab2(sch_1):page175_i67" )
			)
			( gate "S9A1"
				( objectStatus "@baseboard_fab2_lib.baseboard_fab2(sch_1):page175_i78" )
			)
			( gate "S9A2"
				( objectStatus "@baseboard_fab2_lib.baseboard_fab2(sch_1):page175_i84" )
			)
			( gate "R1M5"
				( objectStatus "@baseboard_fab2_lib.baseboard_fab2(sch_1):page176_i16" )
			)
			( gate "L1M2"
				( objectStatus "@baseboard_fab2_lib.baseboard_fab2(sch_1):page176_i30" )
			)
			( gate "R1M6"
				( objectStatus "@baseboard_fab2_lib.baseboard_fab2(sch_1):page176_i31" )
			)
			( gate "J9B1"
				( objectStatus "@baseboard_fab2_lib.baseboard_fab2(sch_1):page176_i69" )
			)
			( gate "CR1M2"
				( objectStatus "@baseboard_fab2_lib.baseboard_fab2(sch_1):page176_i98" )
			)
			( gate "U1M3"
				( objectStatus "@baseboard_fab2_lib.baseboard_fab2(sch_1):page176_i100" )
			)
			( gate "R1M24"
				( objectStatus "@baseboard_fab2_lib.baseboard_fab2(sch_1):page176_i105" )
			)
			( gate "C1M38"
				( objectStatus "@baseboard_fab2_lib.baseboard_fab2(sch_1):page176_i108" )
			)
			( gate "R1M25"
				( objectStatus "@baseboard_fab2_lib.baseboard_fab2(sch_1):page176_i111" )
			)
			( gate "C9B8"
				( objectStatus "@baseboard_fab2_lib.baseboard_fab2(sch_1):page176_i113" )
			)
			( gate "R1M13"
				( objectStatus "@baseboard_fab2_lib.baseboard_fab2(sch_1):page177_i3" )
			)
			( gate "R1M10"
				( objectStatus "@baseboard_fab2_lib.baseboard_fab2(sch_1):page177_i6" )
			)
			( gate "R1M12"
				( objectStatus "@baseboard_fab2_lib.baseboard_fab2(sch_1):page177_i8" )
			)
			( gate "R1M11"
				( objectStatus "@baseboard_fab2_lib.baseboard_fab2(sch_1):page177_i9" )
			)
			( gate "C1M3"
				( objectStatus "@baseboard_fab2_lib.baseboard_fab2(sch_1):page177_i20" )
			)
			( gate "DS9A6"
				( objectStatus "@baseboard_fab2_lib.baseboard_fab2(sch_1):page177_i31" )
			)
			( gate "R1L37"
				( objectStatus "@baseboard_fab2_lib.baseboard_fab2(sch_1):page177_i33" )
			)
			( gate "DS9A2"
				( objectStatus "@baseboard_fab2_lib.baseboard_fab2(sch_1):page177_i42" )
			)
			( gate "R1L21"
				( objectStatus "@baseboard_fab2_lib.baseboard_fab2(sch_1):page177_i43" )
			)
			( gate "U1M1"
				( objectStatus "@baseboard_fab2_lib.baseboard_fab2(sch_1):page177_i70" )
			)
			( gate "DS9F1"
				( objectStatus "@baseboard_fab2_lib.baseboard_fab2(sch_1):page177_i71" )
			)
			( gate "R9F28"
				( objectStatus "@baseboard_fab2_lib.baseboard_fab2(sch_1):page177_i72" )
			)
			( gate "R9F30"
				( objectStatus "@baseboard_fab2_lib.baseboard_fab2(sch_1):page177_i76" )
			)
			( gate "Q9F1"
				( objectStatus "@baseboard_fab2_lib.baseboard_fab2(sch_1):page177_i79" )
			)
			( gate "Q9F1"
				( objectStatus "@baseboard_fab2_lib.baseboard_fab2(sch_1):page177_i80" )
			)
			( gate "R9F52"
				( objectStatus "@baseboard_fab2_lib.baseboard_fab2(sch_1):page177_i82" )
			)
			( gate "R8D20"
				( objectStatus "@baseboard_fab2_lib.baseboard_fab2(sch_1):page178_i1" )
			)
			( gate "R2L12"
				( objectStatus "@baseboard_fab2_lib.baseboard_fab2(sch_1):page178_i2" )
			)
			( gate "R8D19"
				( objectStatus "@baseboard_fab2_lib.baseboard_fab2(sch_1):page178_i8" )
			)
			( gate "R2N31"
				( objectStatus "@baseboard_fab2_lib.baseboard_fab2(sch_1):page178_i11" )
			)
			( gate "R2L15"
				( objectStatus "@baseboard_fab2_lib.baseboard_fab2(sch_1):page178_i12" )
			)
			( gate "R2L11"
				( objectStatus "@baseboard_fab2_lib.baseboard_fab2(sch_1):page178_i13" )
			)
			( gate "R2L6"
				( objectStatus "@baseboard_fab2_lib.baseboard_fab2(sch_1):page178_i17" )
			)
			( gate "R2L4"
				( objectStatus "@baseboard_fab2_lib.baseboard_fab2(sch_1):page178_i18" )
			)
			( gate "R2L5"
				( objectStatus "@baseboard_fab2_lib.baseboard_fab2(sch_1):page178_i20" )
			)
			( gate "R8B29"
				( objectStatus "@baseboard_fab2_lib.baseboard_fab2(sch_1):page178_i21" )
			)
			( gate "R2N19"
				( objectStatus "@baseboard_fab2_lib.baseboard_fab2(sch_1):page178_i22" )
			)
			( gate "R2N22"
				( objectStatus "@baseboard_fab2_lib.baseboard_fab2(sch_1):page178_i23" )
			)
			( gate "J1F1"
				( objectStatus "@baseboard_fab2_lib.baseboard_fab2(sch_1):page181_i111" )
			)
			( gate "C1F4"
				( objectStatus "@baseboard_fab2_lib.baseboard_fab2(sch_1):page181_i160" )
			)
			( gate "C1F5"
				( objectStatus "@baseboard_fab2_lib.baseboard_fab2(sch_1):page181_i161" )
			)
			( gate "C1F2"
				( objectStatus "@baseboard_fab2_lib.baseboard_fab2(sch_1):page181_i162" )
			)
			( gate "C1F13"
				( objectStatus "@baseboard_fab2_lib.baseboard_fab2(sch_1):page181_i163" )
			)
			( gate "C1F10"
				( objectStatus "@baseboard_fab2_lib.baseboard_fab2(sch_1):page181_i164" )
			)
			( gate "C1F6"
				( objectStatus "@baseboard_fab2_lib.baseboard_fab2(sch_1):page181_i165" )
			)
			( gate "C1F20"
				( objectStatus "@baseboard_fab2_lib.baseboard_fab2(sch_1):page181_i166" )
			)
			( gate "C1F3"
				( objectStatus "@baseboard_fab2_lib.baseboard_fab2(sch_1):page181_i167" )
			)
			( gate "C1F12"
				( objectStatus "@baseboard_fab2_lib.baseboard_fab2(sch_1):page181_i168" )
			)
			( gate "C1F11"
				( objectStatus "@baseboard_fab2_lib.baseboard_fab2(sch_1):page181_i169" )
			)
			( gate "C1F8"
				( objectStatus "@baseboard_fab2_lib.baseboard_fab2(sch_1):page181_i170" )
			)
			( gate "C1F18"
				( objectStatus "@baseboard_fab2_lib.baseboard_fab2(sch_1):page181_i171" )
			)
			( gate "C1F16"
				( objectStatus "@baseboard_fab2_lib.baseboard_fab2(sch_1):page181_i172" )
			)
			( gate "C1F17"
				( objectStatus "@baseboard_fab2_lib.baseboard_fab2(sch_1):page181_i173" )
			)
			( gate "C1F15"
				( objectStatus "@baseboard_fab2_lib.baseboard_fab2(sch_1):page181_i174" )
			)
			( gate "C1F14"
				( objectStatus "@baseboard_fab2_lib.baseboard_fab2(sch_1):page181_i175" )
			)
			( gate "R9T9"
				( objectStatus "@baseboard_fab2_lib.baseboard_fab2(sch_1):page181_i177" )
			)
			( gate "CR1F4"
				( objectStatus "@baseboard_fab2_lib.baseboard_fab2(sch_1):page181_i178" )
			)
			( gate "CR1F3"
				( objectStatus "@baseboard_fab2_lib.baseboard_fab2(sch_1):page181_i180" )
			)
			( gate "Q9T1"
				( objectStatus "@baseboard_fab2_lib.baseboard_fab2(sch_1):page181_i181" )
			)
			( gate "R9T6"
				( objectStatus "@baseboard_fab2_lib.baseboard_fab2(sch_1):page181_i183" )
			)
			( gate "R9T3"
				( objectStatus "@baseboard_fab2_lib.baseboard_fab2(sch_1):page181_i185" )
			)
			( gate "J1F3"
				( objectStatus "@baseboard_fab2_lib.baseboard_fab2(sch_1):page181_i189" )
			)
			( gate "R7D5"
				( objectStatus "@baseboard_fab2_lib.baseboard_fab2(sch_1):page181_i199" )
			)
			( gate "R7D9"
				( objectStatus "@baseboard_fab2_lib.baseboard_fab2(sch_1):page181_i200" )
			)
			( gate "R3P61"
				( objectStatus "@baseboard_fab2_lib.baseboard_fab2(sch_1):page181_i201" )
			)
			( gate "R8E5"
				( objectStatus "@baseboard_fab2_lib.baseboard_fab2(sch_1):page181_i218" )
			)
			( gate "C2R6"
				( objectStatus "@baseboard_fab2_lib.baseboard_fab2(sch_1):page181_i224" )
			)
			( gate "U8E1"
				( objectStatus "@baseboard_fab2_lib.baseboard_fab2(sch_1):page181_i243" )
			)
			( gate "C8E1"
				( objectStatus "@baseboard_fab2_lib.baseboard_fab2(sch_1):page181_i253" )
			)
			( gate "R9R9"
				( objectStatus "@baseboard_fab2_lib.baseboard_fab2(sch_1):page181_i254" )
			)
			( gate "R9R12"
				( objectStatus "@baseboard_fab2_lib.baseboard_fab2(sch_1):page181_i255" )
			)
			( gate "R9R10"
				( objectStatus "@baseboard_fab2_lib.baseboard_fab2(sch_1):page181_i256" )
			)
			( gate "R9T1"
				( objectStatus "@baseboard_fab2_lib.baseboard_fab2(sch_1):page181_i261" )
			)
			( gate "R1F8"
				( objectStatus "@baseboard_fab2_lib.baseboard_fab2(sch_1):page181_i268" )
			)
			( gate "R9F69"
				( objectStatus "@baseboard_fab2_lib.baseboard_fab2(sch_1):page158_i150" )
			)
			( gate "R9F68"
				( objectStatus "@baseboard_fab2_lib.baseboard_fab2(sch_1):page158_i149" )
			)
			( gate "C9N18"
				( objectStatus "@baseboard_fab2_lib.baseboard_fab2(sch_1):page182_i9" )
			)
			( gate "C9N17"
				( objectStatus "@baseboard_fab2_lib.baseboard_fab2(sch_1):page182_i12" )
			)
			( gate "C9N15"
				( objectStatus "@baseboard_fab2_lib.baseboard_fab2(sch_1):page182_i13" )
			)
			( gate "C9N1"
				( objectStatus "@baseboard_fab2_lib.baseboard_fab2(sch_1):page182_i14" )
			)
			( gate "C9N2"
				( objectStatus "@baseboard_fab2_lib.baseboard_fab2(sch_1):page182_i15" )
			)
			( gate "C9N12"
				( objectStatus "@baseboard_fab2_lib.baseboard_fab2(sch_1):page182_i16" )
			)
			( gate "J1C1"
				( objectStatus "@baseboard_fab2_lib.baseboard_fab2(sch_1):page182_i18" )
			)
			( gate "C9N9"
				( objectStatus "@baseboard_fab2_lib.baseboard_fab2(sch_1):page182_i49" )
			)
			( gate "C9N8"
				( objectStatus "@baseboard_fab2_lib.baseboard_fab2(sch_1):page182_i50" )
			)
			( gate "C9N3"
				( objectStatus "@baseboard_fab2_lib.baseboard_fab2(sch_1):page182_i51" )
			)
			( gate "C9N16"
				( objectStatus "@baseboard_fab2_lib.baseboard_fab2(sch_1):page182_i52" )
			)
			( gate "C9N10"
				( objectStatus "@baseboard_fab2_lib.baseboard_fab2(sch_1):page182_i53" )
			)
			( gate "C9N7"
				( objectStatus "@baseboard_fab2_lib.baseboard_fab2(sch_1):page182_i54" )
			)
			( gate "C9N4"
				( objectStatus "@baseboard_fab2_lib.baseboard_fab2(sch_1):page182_i55" )
			)
			( gate "C9N14"
				( objectStatus "@baseboard_fab2_lib.baseboard_fab2(sch_1):page182_i56" )
			)
			( gate "C9N6"
				( objectStatus "@baseboard_fab2_lib.baseboard_fab2(sch_1):page182_i81" )
			)
			( gate "C9N5"
				( objectStatus "@baseboard_fab2_lib.baseboard_fab2(sch_1):page182_i83" )
			)
			( gate "R1C11"
				( objectStatus "@baseboard_fab2_lib.baseboard_fab2(sch_1):page182_i97" )
			)
			( gate "R1C10"
				( objectStatus "@baseboard_fab2_lib.baseboard_fab2(sch_1):page182_i101" )
			)
			( gate "R1C9"
				( objectStatus "@baseboard_fab2_lib.baseboard_fab2(sch_1):page182_i104" )
			)
			( gate "R1F9"
				( objectStatus "@baseboard_fab2_lib.baseboard_fab2(sch_1):page182_i107" )
			)
			( gate "R1C31"
				( objectStatus "@baseboard_fab2_lib.baseboard_fab2(sch_1):page182_i110" )
			)
			( gate "EU9F3"
				( objectStatus "@baseboard_fab2_lib.baseboard_fab2(sch_1):page183_i1" )
			)
			( gate "R9F47"
				( objectStatus "@baseboard_fab2_lib.baseboard_fab2(sch_1):page183_i4" )
			)
			( gate "C9F19"
				( objectStatus "@baseboard_fab2_lib.baseboard_fab2(sch_1):page183_i7" )
			)
			( gate "R9F50"
				( objectStatus "@baseboard_fab2_lib.baseboard_fab2(sch_1):page183_i11" )
			)
			( gate "R9F51"
				( objectStatus "@baseboard_fab2_lib.baseboard_fab2(sch_1):page183_i12" )
			)
			( gate "R9F48"
				( objectStatus "@baseboard_fab2_lib.baseboard_fab2(sch_1):page183_i13" )
			)
			( gate "R9F49"
				( objectStatus "@baseboard_fab2_lib.baseboard_fab2(sch_1):page183_i14" )
			)
			( gate "Y9F1"
				( objectStatus "@baseboard_fab2_lib.baseboard_fab2(sch_1):page183_i19" )
			)
			( gate "C9F20"
				( objectStatus "@baseboard_fab2_lib.baseboard_fab2(sch_1):page183_i20" )
			)
			( gate "C9F21"
				( objectStatus "@baseboard_fab2_lib.baseboard_fab2(sch_1):page183_i21" )
			)
			( gate "R9F58"
				( objectStatus "@baseboard_fab2_lib.baseboard_fab2(sch_1):page183_i24" )
			)
			( gate "R9F59"
				( objectStatus "@baseboard_fab2_lib.baseboard_fab2(sch_1):page183_i25" )
			)
			( gate "R9F55"
				( objectStatus "@baseboard_fab2_lib.baseboard_fab2(sch_1):page183_i30" )
			)
			( gate "R9F57"
				( objectStatus "@baseboard_fab2_lib.baseboard_fab2(sch_1):page183_i48" )
			)
			( gate "R9F56"
				( objectStatus "@baseboard_fab2_lib.baseboard_fab2(sch_1):page183_i49" )
			)
			( gate "R9F54"
				( objectStatus "@baseboard_fab2_lib.baseboard_fab2(sch_1):page183_i52" )
			)
			( gate "R9F53"
				( objectStatus "@baseboard_fab2_lib.baseboard_fab2(sch_1):page183_i53" )
			)
			( gate "J8E1"
				( objectStatus "@baseboard_fab2_lib.baseboard_fab2(sch_1):page184_i87" )
			)
			( gate "R8E9"
				( objectStatus "@baseboard_fab2_lib.baseboard_fab2(sch_1):page184_i88" )
			)
			( gate "R8D35"
				( objectStatus "@baseboard_fab2_lib.baseboard_fab2(sch_1):page184_i92" )
			)
			( gate "R8E13"
				( objectStatus "@baseboard_fab2_lib.baseboard_fab2(sch_1):page184_i93" )
			)
			( gate "R8E10"
				( objectStatus "@baseboard_fab2_lib.baseboard_fab2(sch_1):page184_i95" )
			)
			( gate "R8E1"
				( objectStatus "@baseboard_fab2_lib.baseboard_fab2(sch_1):page184_i99" )
			)
			( gate "RM8D1"
				( objectStatus "@baseboard_fab2_lib.baseboard_fab2(sch_1):page184_i104" )
			)
			( gate "J8F1"
				( objectStatus "@baseboard_fab2_lib.baseboard_fab2(sch_1):page185_i53" )
			)
			( gate "C2T11"
				( objectStatus "@baseboard_fab2_lib.baseboard_fab2(sch_1):page185_i62" )
			)
			( gate "C2T10"
				( objectStatus "@baseboard_fab2_lib.baseboard_fab2(sch_1):page185_i63" )
			)
			( gate "C2T13"
				( objectStatus "@baseboard_fab2_lib.baseboard_fab2(sch_1):page185_i64" )
			)
			( gate "C2T14"
				( objectStatus "@baseboard_fab2_lib.baseboard_fab2(sch_1):page185_i65" )
			)
			( gate "C2T20"
				( objectStatus "@baseboard_fab2_lib.baseboard_fab2(sch_1):page185_i66" )
			)
			( gate "C2T23"
				( objectStatus "@baseboard_fab2_lib.baseboard_fab2(sch_1):page185_i67" )
			)
			( gate "C8F15"
				( objectStatus "@baseboard_fab2_lib.baseboard_fab2(sch_1):page185_i90" )
			)
			( gate "C8F6"
				( objectStatus "@baseboard_fab2_lib.baseboard_fab2(sch_1):page185_i95" )
			)
			( gate "C8F7"
				( objectStatus "@baseboard_fab2_lib.baseboard_fab2(sch_1):page185_i96" )
			)
			( gate "C8F11"
				( objectStatus "@baseboard_fab2_lib.baseboard_fab2(sch_1):page185_i97" )
			)
			( gate "C8F12"
				( objectStatus "@baseboard_fab2_lib.baseboard_fab2(sch_1):page185_i98" )
			)
			( gate "C8F13"
				( objectStatus "@baseboard_fab2_lib.baseboard_fab2(sch_1):page185_i99" )
			)
			( gate "R8F18"
				( objectStatus "@baseboard_fab2_lib.baseboard_fab2(sch_1):page185_i105" )
			)
			( gate "R8F21"
				( objectStatus "@baseboard_fab2_lib.baseboard_fab2(sch_1):page185_i106" )
			)
			( gate "U2P1"
				( objectStatus "@baseboard_fab2_lib.baseboard_fab2(sch_1):page185_i110" )
			)
			( gate "R2P15"
				( objectStatus "@baseboard_fab2_lib.baseboard_fab2(sch_1):page185_i111" )
			)
			( gate "R2P16"
				( objectStatus "@baseboard_fab2_lib.baseboard_fab2(sch_1):page185_i113" )
			)
			( gate "R2P14"
				( objectStatus "@baseboard_fab2_lib.baseboard_fab2(sch_1):page185_i115" )
			)
			( gate "C2P9"
				( objectStatus "@baseboard_fab2_lib.baseboard_fab2(sch_1):page185_i117" )
			)
			( gate "C2T29"
				( objectStatus "@baseboard_fab2_lib.baseboard_fab2(sch_1):page185_i120" )
			)
			( gate "C2T26"
				( objectStatus "@baseboard_fab2_lib.baseboard_fab2(sch_1):page185_i123" )
			)
			( gate "C2T21"
				( objectStatus "@baseboard_fab2_lib.baseboard_fab2(sch_1):page185_i124" )
			)
			( gate "C2T16"
				( objectStatus "@baseboard_fab2_lib.baseboard_fab2(sch_1):page185_i126" )
			)
			( gate "C2T15"
				( objectStatus "@baseboard_fab2_lib.baseboard_fab2(sch_1):page185_i127" )
			)
			( gate "C2T24"
				( objectStatus "@baseboard_fab2_lib.baseboard_fab2(sch_1):page185_i129" )
			)
			( gate "C2T2"
				( objectStatus "@baseboard_fab2_lib.baseboard_fab2(sch_1):page185_i131" )
			)
			( gate "C2T4"
				( objectStatus "@baseboard_fab2_lib.baseboard_fab2(sch_1):page185_i132" )
			)
			( gate "C2T5"
				( objectStatus "@baseboard_fab2_lib.baseboard_fab2(sch_1):page185_i135" )
			)
			( gate "R8F36"
				( objectStatus "@baseboard_fab2_lib.baseboard_fab2(sch_1):page185_i136" )
			)
			( gate "C1M27"
				( objectStatus "@baseboard_fab2_lib.baseboard_fab2(sch_1):page186_i3" )
			)
			( gate "C1M26"
				( objectStatus "@baseboard_fab2_lib.baseboard_fab2(sch_1):page186_i6" )
			)
			( gate "C1M23"
				( objectStatus "@baseboard_fab2_lib.baseboard_fab2(sch_1):page186_i7" )
			)
			( gate "C1M22"
				( objectStatus "@baseboard_fab2_lib.baseboard_fab2(sch_1):page186_i8" )
			)
			( gate "C1M24"
				( objectStatus "@baseboard_fab2_lib.baseboard_fab2(sch_1):page186_i10" )
			)
			( gate "R1M14"
				( objectStatus "@baseboard_fab2_lib.baseboard_fab2(sch_1):page186_i220" )
			)
			( gate "R9B7"
				( objectStatus "@baseboard_fab2_lib.baseboard_fab2(sch_1):page186_i222" )
			)
			( gate "C1M20"
				( objectStatus "@baseboard_fab2_lib.baseboard_fab2(sch_1):page186_i270" )
			)
			( gate "C1M21"
				( objectStatus "@baseboard_fab2_lib.baseboard_fab2(sch_1):page186_i334" )
			)
			( gate "C1M25"
				( objectStatus "@baseboard_fab2_lib.baseboard_fab2(sch_1):page186_i335" )
			)
			( gate "J9B3"
				( objectStatus "@baseboard_fab2_lib.baseboard_fab2(sch_1):page186_i336" )
			)
			( gate "R1M16"
				( objectStatus "@baseboard_fab2_lib.baseboard_fab2(sch_1):page186_i337" )
			)
			( gate "R1M17"
				( objectStatus "@baseboard_fab2_lib.baseboard_fab2(sch_1):page186_i338" )
			)
			( gate "R1M15"
				( objectStatus "@baseboard_fab2_lib.baseboard_fab2(sch_1):page186_i339" )
			)
			( gate "R1M18"
				( objectStatus "@baseboard_fab2_lib.baseboard_fab2(sch_1):page186_i340" )
			)
			( gate "C9B10"
				( objectStatus "@baseboard_fab2_lib.baseboard_fab2(sch_1):page186_i345" )
			)
			( gate "C9B9"
				( objectStatus "@baseboard_fab2_lib.baseboard_fab2(sch_1):page186_i347" )
			)
			( gate "R2R8"
				( objectStatus "@baseboard_fab2_lib.baseboard_fab2(sch_1):page187_i18" )
			)
			( gate "J8E3"
				( objectStatus "@baseboard_fab2_lib.baseboard_fab2(sch_1):page187_i119" )
			)
			( gate "R9E10"
				( objectStatus "@baseboard_fab2_lib.baseboard_fab2(sch_1):page187_i145" )
			)
			( gate "R9E11"
				( objectStatus "@baseboard_fab2_lib.baseboard_fab2(sch_1):page187_i150" )
			)
			( gate "R9E12"
				( objectStatus "@baseboard_fab2_lib.baseboard_fab2(sch_1):page187_i153" )
			)
			( gate "C2R15"
				( objectStatus "@baseboard_fab2_lib.baseboard_fab2(sch_1):page188_i2" )
			)
			( gate "C2R18"
				( objectStatus "@baseboard_fab2_lib.baseboard_fab2(sch_1):page188_i3" )
			)
			( gate "C2P11"
				( objectStatus "@baseboard_fab2_lib.baseboard_fab2(sch_1):page188_i21" )
			)
			( gate "C2P12"
				( objectStatus "@baseboard_fab2_lib.baseboard_fab2(sch_1):page188_i23" )
			)
			( gate "C2R17"
				( objectStatus "@baseboard_fab2_lib.baseboard_fab2(sch_1):page188_i25" )
			)
			( gate "J8E4"
				( objectStatus "@baseboard_fab2_lib.baseboard_fab2(sch_1):page188_i27" )
			)
			( gate "C2R16"
				( objectStatus "@baseboard_fab2_lib.baseboard_fab2(sch_1):page188_i40" )
			)
			( gate "C2P10"
				( objectStatus "@baseboard_fab2_lib.baseboard_fab2(sch_1):page188_i41" )
			)
			( gate "C2P16"
				( objectStatus "@baseboard_fab2_lib.baseboard_fab2(sch_1):page188_i53" )
			)
			( gate "C2P15"
				( objectStatus "@baseboard_fab2_lib.baseboard_fab2(sch_1):page188_i55" )
			)
			( gate "C2P14"
				( objectStatus "@baseboard_fab2_lib.baseboard_fab2(sch_1):page188_i56" )
			)
			( gate "C2P13"
				( objectStatus "@baseboard_fab2_lib.baseboard_fab2(sch_1):page188_i57" )
			)
			( gate "C8C8"
				( objectStatus "@baseboard_fab2_lib.baseboard_fab2(sch_1):page188_i64" )
			)
			( gate "C8C9"
				( objectStatus "@baseboard_fab2_lib.baseboard_fab2(sch_1):page188_i68" )
			)
			( gate "C8C11"
				( objectStatus "@baseboard_fab2_lib.baseboard_fab2(sch_1):page188_i72" )
			)
			( gate "C8C10"
				( objectStatus "@baseboard_fab2_lib.baseboard_fab2(sch_1):page188_i73" )
			)
			( gate "C8C12"
				( objectStatus "@baseboard_fab2_lib.baseboard_fab2(sch_1):page188_i80" )
			)
			( gate "C8C13"
				( objectStatus "@baseboard_fab2_lib.baseboard_fab2(sch_1):page188_i81" )
			)
			( gate "C8C15"
				( objectStatus "@baseboard_fab2_lib.baseboard_fab2(sch_1):page188_i82" )
			)
			( gate "C8C14"
				( objectStatus "@baseboard_fab2_lib.baseboard_fab2(sch_1):page188_i86" )
			)
			( gate "R1R18"
				( objectStatus "@baseboard_fab2_lib.baseboard_fab2(sch_1):page188_i88" )
			)
			( gate "R1R19"
				( objectStatus "@baseboard_fab2_lib.baseboard_fab2(sch_1):page188_i89" )
			)
			( gate "R1R21"
				( objectStatus "@baseboard_fab2_lib.baseboard_fab2(sch_1):page188_i90" )
			)
			( gate "R1R20"
				( objectStatus "@baseboard_fab2_lib.baseboard_fab2(sch_1):page188_i91" )
			)
			( gate "R1R22"
				( objectStatus "@baseboard_fab2_lib.baseboard_fab2(sch_1):page188_i92" )
			)
			( gate "R1R16"
				( objectStatus "@baseboard_fab2_lib.baseboard_fab2(sch_1):page188_i93" )
			)
			( gate "R1R17"
				( objectStatus "@baseboard_fab2_lib.baseboard_fab2(sch_1):page188_i94" )
			)
			( gate "R1R23"
				( objectStatus "@baseboard_fab2_lib.baseboard_fab2(sch_1):page188_i95" )
			)
			( gate "R8G10"
				( objectStatus "@baseboard_fab2_lib.baseboard_fab2(sch_1):page189_i7" )
			)
			( gate "R7G19"
				( objectStatus "@baseboard_fab2_lib.baseboard_fab2(sch_1):page189_i8" )
			)
			( gate "R8G9"
				( objectStatus "@baseboard_fab2_lib.baseboard_fab2(sch_1):page189_i9" )
			)
			( gate "R7G18"
				( objectStatus "@baseboard_fab2_lib.baseboard_fab2(sch_1):page189_i13" )
			)
			( gate "R8G8"
				( objectStatus "@baseboard_fab2_lib.baseboard_fab2(sch_1):page189_i17" )
			)
			( gate "R8G7"
				( objectStatus "@baseboard_fab2_lib.baseboard_fab2(sch_1):page189_i18" )
			)
			( gate "R8G11"
				( objectStatus "@baseboard_fab2_lib.baseboard_fab2(sch_1):page189_i19" )
			)
			( gate "R8G14"
				( objectStatus "@baseboard_fab2_lib.baseboard_fab2(sch_1):page189_i20" )
			)
			( gate "R8G12"
				( objectStatus "@baseboard_fab2_lib.baseboard_fab2(sch_1):page189_i21" )
			)
			( gate "R8G16"
				( objectStatus "@baseboard_fab2_lib.baseboard_fab2(sch_1):page189_i22" )
			)
			( gate "R8G13"
				( objectStatus "@baseboard_fab2_lib.baseboard_fab2(sch_1):page189_i23" )
			)
			( gate "R8G15"
				( objectStatus "@baseboard_fab2_lib.baseboard_fab2(sch_1):page189_i24" )
			)
			( gate "R8G17"
				( objectStatus "@baseboard_fab2_lib.baseboard_fab2(sch_1):page189_i25" )
			)
			( gate "R8G18"
				( objectStatus "@baseboard_fab2_lib.baseboard_fab2(sch_1):page189_i26" )
			)
			( gate "R7G16"
				( objectStatus "@baseboard_fab2_lib.baseboard_fab2(sch_1):page189_i27" )
			)
			( gate "R7G15"
				( objectStatus "@baseboard_fab2_lib.baseboard_fab2(sch_1):page189_i36" )
			)
			( gate "R7G17"
				( objectStatus "@baseboard_fab2_lib.baseboard_fab2(sch_1):page189_i37" )
			)
			( gate "R7G14"
				( objectStatus "@baseboard_fab2_lib.baseboard_fab2(sch_1):page189_i38" )
			)
			( gate "R3R15"
				( objectStatus "@baseboard_fab2_lib.baseboard_fab2(sch_1):page189_i44" )
			)
			( gate "R3R11"
				( objectStatus "@baseboard_fab2_lib.baseboard_fab2(sch_1):page189_i45" )
			)
			( gate "J7G2"
				( objectStatus "@baseboard_fab2_lib.baseboard_fab2(sch_1):page189_i47" )
			)
			( gate "CR3U1"
				( objectStatus "@baseboard_fab2_lib.baseboard_fab2(sch_1):page189_i49" )
			)
			( gate "R8G20"
				( objectStatus "@baseboard_fab2_lib.baseboard_fab2(sch_1):page189_i50" )
			)
			( gate "R7G23"
				( objectStatus "@baseboard_fab2_lib.baseboard_fab2(sch_1):page189_i51" )
			)
			( gate "R7G22"
				( objectStatus "@baseboard_fab2_lib.baseboard_fab2(sch_1):page189_i53" )
			)
			( gate "R8G23"
				( objectStatus "@baseboard_fab2_lib.baseboard_fab2(sch_1):page189_i56" )
			)
			( gate "R7G21"
				( objectStatus "@baseboard_fab2_lib.baseboard_fab2(sch_1):page189_i63" )
			)
			( gate "R8G19"
				( objectStatus "@baseboard_fab2_lib.baseboard_fab2(sch_1):page189_i64" )
			)
			( gate "R8G21"
				( objectStatus "@baseboard_fab2_lib.baseboard_fab2(sch_1):page189_i65" )
			)
			( gate "R8G22"
				( objectStatus "@baseboard_fab2_lib.baseboard_fab2(sch_1):page189_i66" )
			)
			( gate "R3P34"
				( objectStatus "@baseboard_fab2_lib.baseboard_fab2(sch_1):page190_i116" )
			)
			( gate "R3P35"
				( objectStatus "@baseboard_fab2_lib.baseboard_fab2(sch_1):page190_i117" )
			)
			( gate "U8D7"
				( objectStatus "@baseboard_fab2_lib.baseboard_fab2(sch_1):page190_i179" )
			)
			( gate "R2R2"
				( objectStatus "@baseboard_fab2_lib.baseboard_fab2(sch_1):page190_i338" )
			)
			( gate "U8D7"
				( objectStatus "@baseboard_fab2_lib.baseboard_fab2(sch_1):page191_i59" )
			)
			( gate "R2R6"
				( objectStatus "@baseboard_fab2_lib.baseboard_fab2(sch_1):page191_i166" )
			)
			( gate "R2R7"
				( objectStatus "@baseboard_fab2_lib.baseboard_fab2(sch_1):page191_i172" )
			)
			( gate "R2R4"
				( objectStatus "@baseboard_fab2_lib.baseboard_fab2(sch_1):page191_i184" )
			)
			( gate "R7D42"
				( objectStatus "@baseboard_fab2_lib.baseboard_fab2(sch_1):page191_i193" )
			)
			( gate "C2P8"
				( objectStatus "@baseboard_fab2_lib.baseboard_fab2(sch_1):page192_i1" )
			)
			( gate "C2P5"
				( objectStatus "@baseboard_fab2_lib.baseboard_fab2(sch_1):page192_i3" )
			)
			( gate "C3R1"
				( objectStatus "@baseboard_fab2_lib.baseboard_fab2(sch_1):page192_i4" )
			)
			( gate "C3P43"
				( objectStatus "@baseboard_fab2_lib.baseboard_fab2(sch_1):page192_i6" )
			)
			( gate "C3R3"
				( objectStatus "@baseboard_fab2_lib.baseboard_fab2(sch_1):page192_i7" )
			)
			( gate "C2R1"
				( objectStatus "@baseboard_fab2_lib.baseboard_fab2(sch_1):page192_i8" )
			)
			( gate "C2P2"
				( objectStatus "@baseboard_fab2_lib.baseboard_fab2(sch_1):page192_i9" )
			)
			( gate "C3R2"
				( objectStatus "@baseboard_fab2_lib.baseboard_fab2(sch_1):page192_i10" )
			)
			( gate "C3P51"
				( objectStatus "@baseboard_fab2_lib.baseboard_fab2(sch_1):page192_i11" )
			)
			( gate "C3P47"
				( objectStatus "@baseboard_fab2_lib.baseboard_fab2(sch_1):page192_i12" )
			)
			( gate "U8D7"
				( objectStatus "@baseboard_fab2_lib.baseboard_fab2(sch_1):page192_i14" )
			)
			( gate "C2R5"
				( objectStatus "@baseboard_fab2_lib.baseboard_fab2(sch_1):page192_i15" )
			)
			( gate "C2P4"
				( objectStatus "@baseboard_fab2_lib.baseboard_fab2(sch_1):page192_i16" )
			)
			( gate "C3P52"
				( objectStatus "@baseboard_fab2_lib.baseboard_fab2(sch_1):page192_i17" )
			)
			( gate "C2P6"
				( objectStatus "@baseboard_fab2_lib.baseboard_fab2(sch_1):page192_i18" )
			)
			( gate "C2R3"
				( objectStatus "@baseboard_fab2_lib.baseboard_fab2(sch_1):page192_i19" )
			)
			( gate "C2P7"
				( objectStatus "@baseboard_fab2_lib.baseboard_fab2(sch_1):page192_i20" )
			)
			( gate "C2R4"
				( objectStatus "@baseboard_fab2_lib.baseboard_fab2(sch_1):page192_i21" )
			)
			( gate "C2P3"
				( objectStatus "@baseboard_fab2_lib.baseboard_fab2(sch_1):page192_i22" )
			)
			( gate "C3P44"
				( objectStatus "@baseboard_fab2_lib.baseboard_fab2(sch_1):page192_i23" )
			)
			( gate "C3P48"
				( objectStatus "@baseboard_fab2_lib.baseboard_fab2(sch_1):page192_i25" )
			)
			( gate "C2R2"
				( objectStatus "@baseboard_fab2_lib.baseboard_fab2(sch_1):page192_i28" )
			)
			( gate "R7E6"
				( objectStatus "@baseboard_fab2_lib.baseboard_fab2(sch_1):page192_i33" )
			)
			( gate "R2R1"
				( objectStatus "@baseboard_fab2_lib.baseboard_fab2(sch_1):page192_i34" )
			)
			( gate "R7E5"
				( objectStatus "@baseboard_fab2_lib.baseboard_fab2(sch_1):page192_i38" )
			)
			( gate "R2R3"
				( objectStatus "@baseboard_fab2_lib.baseboard_fab2(sch_1):page192_i41" )
			)
			( gate "R3R16"
				( objectStatus "@baseboard_fab2_lib.baseboard_fab2(sch_1):page192_i48" )
			)
			( gate "R6M9"
				( objectStatus "@baseboard_fab2_lib.baseboard_fab2(sch_1):page192_i49" )
			)
			( gate "R7E18"
				( objectStatus "@baseboard_fab2_lib.baseboard_fab2(sch_1):page192_i55" )
			)
			( gate "R7E19"
				( objectStatus "@baseboard_fab2_lib.baseboard_fab2(sch_1):page192_i57" )
			)
			( gate "R7E20"
				( objectStatus "@baseboard_fab2_lib.baseboard_fab2(sch_1):page192_i59" )
			)
			( gate "C4C1"
				( objectStatus "@baseboard_fab2_lib.baseboard_fab2(sch_1):page193_i29" )
			)
			( gate "C3C2"
				( objectStatus "@baseboard_fab2_lib.baseboard_fab2(sch_1):page193_i31" )
			)
			( gate "C3C1"
				( objectStatus "@baseboard_fab2_lib.baseboard_fab2(sch_1):page193_i38" )
			)
			( gate "J4E1"
				( objectStatus "@baseboard_fab2_lib.baseboard_fab2(sch_1):page193_i45" )
			)
			( gate "J4B2"
				( objectStatus "@baseboard_fab2_lib.baseboard_fab2(sch_1):page193_i46" )
			)
			( gate "C4E24"
				( objectStatus "@baseboard_fab2_lib.baseboard_fab2(sch_1):page193_i61" )
			)
			( gate "C6R16"
				( objectStatus "@baseboard_fab2_lib.baseboard_fab2(sch_1):page193_i62" )
			)
			( gate "C4F1"
				( objectStatus "@baseboard_fab2_lib.baseboard_fab2(sch_1):page193_i68" )
			)
			( gate "C4F3"
				( objectStatus "@baseboard_fab2_lib.baseboard_fab2(sch_1):page193_i70" )
			)
			( gate "C3F1"
				( objectStatus "@baseboard_fab2_lib.baseboard_fab2(sch_1):page193_i140" )
			)
			( gate "C4F2"
				( objectStatus "@baseboard_fab2_lib.baseboard_fab2(sch_1):page193_i141" )
			)
			( gate "R4C12"
				( objectStatus "@baseboard_fab2_lib.baseboard_fab2(sch_1):page193_i169" )
			)
			( gate "R4C11"
				( objectStatus "@baseboard_fab2_lib.baseboard_fab2(sch_1):page193_i170" )
			)
			( gate "C4T2"
				( objectStatus "@baseboard_fab2_lib.baseboard_fab2(sch_1):page194_i9" )
			)
			( gate "C4T1"
				( objectStatus "@baseboard_fab2_lib.baseboard_fab2(sch_1):page194_i16" )
			)
			( gate "C4R1"
				( objectStatus "@baseboard_fab2_lib.baseboard_fab2(sch_1):page194_i29" )
			)
			( gate "C3R4"
				( objectStatus "@baseboard_fab2_lib.baseboard_fab2(sch_1):page194_i31" )
			)
			( gate "J6E1"
				( objectStatus "@baseboard_fab2_lib.baseboard_fab2(sch_1):page194_i55" )
			)
			( gate "J6B1"
				( objectStatus "@baseboard_fab2_lib.baseboard_fab2(sch_1):page194_i56" )
			)
			( gate "C3N40"
				( objectStatus "@baseboard_fab2_lib.baseboard_fab2(sch_1):page194_i86" )
			)
			( gate "C3M46"
				( objectStatus "@baseboard_fab2_lib.baseboard_fab2(sch_1):page194_i99" )
			)
			( gate "C3N14"
				( objectStatus "@baseboard_fab2_lib.baseboard_fab2(sch_1):page194_i101" )
			)
			( gate "C3T1"
				( objectStatus "@baseboard_fab2_lib.baseboard_fab2(sch_1):page194_i149" )
			)
			( gate "C3T2"
				( objectStatus "@baseboard_fab2_lib.baseboard_fab2(sch_1):page194_i150" )
			)
			( gate "R7C24"
				( objectStatus "@baseboard_fab2_lib.baseboard_fab2(sch_1):page194_i155" )
			)
			( gate "R3N29"
				( objectStatus "@baseboard_fab2_lib.baseboard_fab2(sch_1):page194_i156" )
			)
			( gate "RM1E1"
				( objectStatus "@baseboard_fab2_lib.baseboard_fab2(sch_1):page195_i26" )
			)
			( gate "J1E1"
				( objectStatus "@baseboard_fab2_lib.baseboard_fab2(sch_1):page195_i29" )
			)
			( gate "C9R5"
				( objectStatus "@baseboard_fab2_lib.baseboard_fab2(sch_1):page195_i31" )
			)
			( gate "C1E12"
				( objectStatus "@baseboard_fab2_lib.baseboard_fab2(sch_1):page195_i32" )
			)
			( gate "C1E15"
				( objectStatus "@baseboard_fab2_lib.baseboard_fab2(sch_1):page195_i35" )
			)
			( gate "C9R12"
				( objectStatus "@baseboard_fab2_lib.baseboard_fab2(sch_1):page195_i36" )
			)
			( gate "C9R6"
				( objectStatus "@baseboard_fab2_lib.baseboard_fab2(sch_1):page195_i37" )
			)
			( gate "C1E17"
				( objectStatus "@baseboard_fab2_lib.baseboard_fab2(sch_1):page195_i38" )
			)
			( gate "C1E16"
				( objectStatus "@baseboard_fab2_lib.baseboard_fab2(sch_1):page195_i39" )
			)
			( gate "TH4G1"
				( objectStatus "@baseboard_fab2_lib.baseboard_fab2(sch_1):page195_i49" )
			)
			( gate "TH9G1"
				( objectStatus "@baseboard_fab2_lib.baseboard_fab2(sch_1):page195_i52" )
			)
			( gate "TH9A1"
				( objectStatus "@baseboard_fab2_lib.baseboard_fab2(sch_1):page195_i54" )
			)
			( gate "TH1A1"
				( objectStatus "@baseboard_fab2_lib.baseboard_fab2(sch_1):page195_i56" )
			)
			( gate "TH4A1"
				( objectStatus "@baseboard_fab2_lib.baseboard_fab2(sch_1):page195_i62" )
			)
			( gate "TH7A1"
				( objectStatus "@baseboard_fab2_lib.baseboard_fab2(sch_1):page195_i65" )
			)
			( gate "TH7G1"
				( objectStatus "@baseboard_fab2_lib.baseboard_fab2(sch_1):page195_i67" )
			)
			( gate "RM1G1"
				( objectStatus "@baseboard_fab2_lib.baseboard_fab2(sch_1):page195_i76" )
			)
			( gate "J1D1"
				( objectStatus "@baseboard_fab2_lib.baseboard_fab2(sch_1):page195_i78" )
			)
			( gate "C4F6"
				( objectStatus "@baseboard_fab2_lib.baseboard_fab2(sch_1):page195_i82" )
			)
			( gate "C4B13"
				( objectStatus "@baseboard_fab2_lib.baseboard_fab2(sch_1):page195_i83" )
			)
			( gate "C1B14"
				( objectStatus "@baseboard_fab2_lib.baseboard_fab2(sch_1):page195_i84" )
			)
			( gate "C1F7"
				( objectStatus "@baseboard_fab2_lib.baseboard_fab2(sch_1):page195_i85" )
			)
			( gate "C4F5"
				( objectStatus "@baseboard_fab2_lib.baseboard_fab2(sch_1):page195_i96" )
			)
			( gate "C4B14"
				( objectStatus "@baseboard_fab2_lib.baseboard_fab2(sch_1):page195_i97" )
			)
			( gate "C3T6"
				( objectStatus "@baseboard_fab2_lib.baseboard_fab2(sch_1):page195_i98" )
			)
			( gate "C9M3"
				( objectStatus "@baseboard_fab2_lib.baseboard_fab2(sch_1):page195_i99" )
			)
			( gate "C3B6"
				( objectStatus "@baseboard_fab2_lib.baseboard_fab2(sch_1):page195_i100" )
			)
			( gate "C1R23"
				( objectStatus "@baseboard_fab2_lib.baseboard_fab2(sch_1):page195_i101" )
			)
			( gate "C4M6"
				( objectStatus "@baseboard_fab2_lib.baseboard_fab2(sch_1):page195_i102" )
			)
			( gate "C1M5"
				( objectStatus "@baseboard_fab2_lib.baseboard_fab2(sch_1):page195_i103" )
			)
			( gate "C3T13"
				( objectStatus "@baseboard_fab2_lib.baseboard_fab2(sch_1):page195_i104" )
			)
			( gate "C4M7"
				( objectStatus "@baseboard_fab2_lib.baseboard_fab2(sch_1):page195_i105" )
			)
			( gate "C3T15"
				( objectStatus "@baseboard_fab2_lib.baseboard_fab2(sch_1):page195_i106" )
			)
			( gate "C7M6"
				( objectStatus "@baseboard_fab2_lib.baseboard_fab2(sch_1):page195_i108" )
			)
			( gate "C6N5"
				( objectStatus "@baseboard_fab2_lib.baseboard_fab2(sch_1):page195_i109" )
			)
			( gate "C9T3"
				( objectStatus "@baseboard_fab2_lib.baseboard_fab2(sch_1):page195_i111" )
			)
			( gate "C4F4"
				( objectStatus "@baseboard_fab2_lib.baseboard_fab2(sch_1):page195_i112" )
			)
			( gate "C3T3"
				( objectStatus "@baseboard_fab2_lib.baseboard_fab2(sch_1):page195_i113" )
			)
			( gate "R2U43"
				( objectStatus "@baseboard_fab2_lib.baseboard_fab2(sch_1):page196_i46" )
			)
			( gate "BT8G1"
				( objectStatus "@baseboard_fab2_lib.baseboard_fab2(sch_1):page196_i47" )
			)
			( gate "XBT8G1"
				( objectStatus "@baseboard_fab2_lib.baseboard_fab2(sch_1):page196_i51" )
			)
			( gate "CR2U1"
				( objectStatus "@baseboard_fab2_lib.baseboard_fab2(sch_1):page196_i53" )
			)
			( gate "R3P44"
				( objectStatus "@baseboard_fab2_lib.baseboard_fab2(sch_1):page196_i59" )
			)
			( gate "C3P45"
				( objectStatus "@baseboard_fab2_lib.baseboard_fab2(sch_1):page196_i60" )
			)
			( gate "R2P20"
				( objectStatus "@baseboard_fab2_lib.baseboard_fab2(sch_1):page196_i65" )
			)
			( gate "R1L16"
				( objectStatus "@baseboard_fab2_lib.baseboard_fab2(sch_1):page196_i68" )
			)
			( gate "U7D3"
				( objectStatus "@baseboard_fab2_lib.baseboard_fab2(sch_1):page196_i70" )
			)
			( gate "R3P50"
				( objectStatus "@baseboard_fab2_lib.baseboard_fab2(sch_1):page196_i71" )
			)
			( gate "C3P46"
				( objectStatus "@baseboard_fab2_lib.baseboard_fab2(sch_1):page196_i72" )
			)
			( gate "R3P48"
				( objectStatus "@baseboard_fab2_lib.baseboard_fab2(sch_1):page196_i74" )
			)
			( gate "R3P51"
				( objectStatus "@baseboard_fab2_lib.baseboard_fab2(sch_1):page196_i75" )
			)
			( gate "U1L3"
				( objectStatus "@baseboard_fab2_lib.baseboard_fab2(sch_1):page196_i80" )
			)
			( gate "C1L16"
				( objectStatus "@baseboard_fab2_lib.baseboard_fab2(sch_1):page196_i81" )
			)
			( gate "U8E2"
				( objectStatus "@baseboard_fab2_lib.baseboard_fab2(sch_1):page196_i89" )
			)
			( gate "R8E7"
				( objectStatus "@baseboard_fab2_lib.baseboard_fab2(sch_1):page196_i90" )
			)
			( gate "C8E3"
				( objectStatus "@baseboard_fab2_lib.baseboard_fab2(sch_1):page196_i94" )
			)
			( gate "C2U26"
				( objectStatus "@baseboard_fab2_lib.baseboard_fab2(sch_1):page196_i102" )
			)
			( gate "CR7E1"
				( objectStatus "@baseboard_fab2_lib.baseboard_fab2(sch_1):page196_i103" )
			)
			( gate "U8D8"
				( objectStatus "@baseboard_fab2_lib.baseboard_fab2(sch_1):page196_i104" )
			)
			( gate "C8D4"
				( objectStatus "@baseboard_fab2_lib.baseboard_fab2(sch_1):page196_i105" )
			)
			( gate "R8D42"
				( objectStatus "@baseboard_fab2_lib.baseboard_fab2(sch_1):page196_i106" )
			)
			( gate "R8D38"
				( objectStatus "@baseboard_fab2_lib.baseboard_fab2(sch_1):page196_i112" )
			)
			( gate "R8D40"
				( objectStatus "@baseboard_fab2_lib.baseboard_fab2(sch_1):page196_i113" )
			)
			( gate "R8D39"
				( objectStatus "@baseboard_fab2_lib.baseboard_fab2(sch_1):page196_i114" )
			)
			( gate "R8D37"
				( objectStatus "@baseboard_fab2_lib.baseboard_fab2(sch_1):page196_i115" )
			)
			( gate "R8D41"
				( objectStatus "@baseboard_fab2_lib.baseboard_fab2(sch_1):page196_i120" )
			)
			( gate "R2P18"
				( objectStatus "@baseboard_fab2_lib.baseboard_fab2(sch_1):page196_i121" )
			)
			( gate "R2P21"
				( objectStatus "@baseboard_fab2_lib.baseboard_fab2(sch_1):page196_i122" )
			)
			( gate "Q2P2"
				( objectStatus "@baseboard_fab2_lib.baseboard_fab2(sch_1):page196_i124" )
			)
			( gate "CR8E1"
				( objectStatus "@baseboard_fab2_lib.baseboard_fab2(sch_1):page196_i128" )
			)
			( gate "C6U18"
				( objectStatus "@baseboard_fab2_lib.baseboard_fab2(sch_1):page197_i52" )
			)
			( gate "C6T2"
				( objectStatus "@baseboard_fab2_lib.baseboard_fab2(sch_1):page197_i54" )
			)
			( gate "C4B11"
				( objectStatus "@baseboard_fab2_lib.baseboard_fab2(sch_1):page197_i59" )
			)
			( gate "C4A4"
				( objectStatus "@baseboard_fab2_lib.baseboard_fab2(sch_1):page197_i62" )
			)
			( gate "C6U10"
				( objectStatus "@baseboard_fab2_lib.baseboard_fab2(sch_1):page197_i65" )
			)
			( gate "C4A17"
				( objectStatus "@baseboard_fab2_lib.baseboard_fab2(sch_1):page197_i67" )
			)
			( gate "C9T8"
				( objectStatus "@baseboard_fab2_lib.baseboard_fab2(sch_1):page197_i70" )
			)
			( gate "C9U11"
				( objectStatus "@baseboard_fab2_lib.baseboard_fab2(sch_1):page197_i73" )
			)
			( gate "C9U8"
				( objectStatus "@baseboard_fab2_lib.baseboard_fab2(sch_1):page197_i76" )
			)
			( gate "C1A4"
				( objectStatus "@baseboard_fab2_lib.baseboard_fab2(sch_1):page197_i79" )
			)
			( gate "C1B7"
				( objectStatus "@baseboard_fab2_lib.baseboard_fab2(sch_1):page197_i82" )
			)
			( gate "C1A16"
				( objectStatus "@baseboard_fab2_lib.baseboard_fab2(sch_1):page197_i85" )
			)
			( gate "U4F1"
				( objectStatus "@baseboard_fab2_lib.baseboard_fab2(sch_1):page197_i97" )
			)
			( gate "R4F2"
				( objectStatus "@baseboard_fab2_lib.baseboard_fab2(sch_1):page197_i99" )
			)
			( gate "R4F1"
				( objectStatus "@baseboard_fab2_lib.baseboard_fab2(sch_1):page197_i110" )
			)
			( gate "R4B11"
				( objectStatus "@baseboard_fab2_lib.baseboard_fab2(sch_1):page197_i113" )
			)
			( gate "U4B1"
				( objectStatus "@baseboard_fab2_lib.baseboard_fab2(sch_1):page197_i120" )
			)
			( gate "R4B12"
				( objectStatus "@baseboard_fab2_lib.baseboard_fab2(sch_1):page197_i121" )
			)
			( gate "R9T4"
				( objectStatus "@baseboard_fab2_lib.baseboard_fab2(sch_1):page197_i126" )
			)
			( gate "R1F3"
				( objectStatus "@baseboard_fab2_lib.baseboard_fab2(sch_1):page197_i131" )
			)
			( gate "U1F1"
				( objectStatus "@baseboard_fab2_lib.baseboard_fab2(sch_1):page197_i133" )
			)
			( gate "R1B14"
				( objectStatus "@baseboard_fab2_lib.baseboard_fab2(sch_1):page197_i137" )
			)
			( gate "R9M4"
				( objectStatus "@baseboard_fab2_lib.baseboard_fab2(sch_1):page197_i142" )
			)
			( gate "U1B1"
				( objectStatus "@baseboard_fab2_lib.baseboard_fab2(sch_1):page197_i144" )
			)
			( gate "EU2T1"
				( objectStatus "@baseboard_fab2_lib.baseboard_fab2(sch_1):page198_i1" )
			)
			( gate "EU8B1"
				( objectStatus "@baseboard_fab2_lib.baseboard_fab2(sch_1):page198_i13" )
			)
			( gate "EU7E1"
				( objectStatus "@baseboard_fab2_lib.baseboard_fab2(sch_1):page198_i19" )
			)
			( gate "C8F17"
				( objectStatus "@baseboard_fab2_lib.baseboard_fab2(sch_1):page198_i24" )
			)
			( gate "C8B8"
				( objectStatus "@baseboard_fab2_lib.baseboard_fab2(sch_1):page198_i26" )
			)
			( gate "C8E19"
				( objectStatus "@baseboard_fab2_lib.baseboard_fab2(sch_1):page198_i28" )
			)
			( gate "C8B5"
				( objectStatus "@baseboard_fab2_lib.baseboard_fab2(sch_1):page198_i37" )
			)
			( gate "C8B12"
				( objectStatus "@baseboard_fab2_lib.baseboard_fab2(sch_1):page198_i38" )
			)
			( gate "C8B6"
				( objectStatus "@baseboard_fab2_lib.baseboard_fab2(sch_1):page198_i40" )
			)
			( gate "C8B7"
				( objectStatus "@baseboard_fab2_lib.baseboard_fab2(sch_1):page198_i41" )
			)
			( gate "C2T36"
				( objectStatus "@baseboard_fab2_lib.baseboard_fab2(sch_1):page198_i43" )
			)
			( gate "C2U1"
				( objectStatus "@baseboard_fab2_lib.baseboard_fab2(sch_1):page198_i44" )
			)
			( gate "C2U19"
				( objectStatus "@baseboard_fab2_lib.baseboard_fab2(sch_1):page198_i46" )
			)
			( gate "C2U2"
				( objectStatus "@baseboard_fab2_lib.baseboard_fab2(sch_1):page198_i47" )
			)
			( gate "C7E9"
				( objectStatus "@baseboard_fab2_lib.baseboard_fab2(sch_1):page198_i49" )
			)
			( gate "C7E8"
				( objectStatus "@baseboard_fab2_lib.baseboard_fab2(sch_1):page198_i50" )
			)
			( gate "C7E5"
				( objectStatus "@baseboard_fab2_lib.baseboard_fab2(sch_1):page198_i52" )
			)
			( gate "C7E6"
				( objectStatus "@baseboard_fab2_lib.baseboard_fab2(sch_1):page198_i53" )
			)
			( gate "C1B18"
				( objectStatus "@baseboard_fab2_lib.baseboard_fab2(sch_1):page198_i61" )
			)
			( gate "C1B19"
				( objectStatus "@baseboard_fab2_lib.baseboard_fab2(sch_1):page198_i64" )
			)
			( gate "C9M6"
				( objectStatus "@baseboard_fab2_lib.baseboard_fab2(sch_1):page198_i67" )
			)
			( gate "EU9M1"
				( objectStatus "@baseboard_fab2_lib.baseboard_fab2(sch_1):page198_i69" )
			)
			( gate "C9M10"
				( objectStatus "@baseboard_fab2_lib.baseboard_fab2(sch_1):page198_i74" )
			)
			( gate "C9M9"
				( objectStatus "@baseboard_fab2_lib.baseboard_fab2(sch_1):page198_i76" )
			)
			( gate "R8E12"
				( objectStatus "@baseboard_fab2_lib.baseboard_fab2(sch_1):page198_i78" )
			)
			( gate "R8B4"
				( objectStatus "@baseboard_fab2_lib.baseboard_fab2(sch_1):page198_i83" )
			)
			( gate "Q8G1"
				( objectStatus "@baseboard_fab2_lib.baseboard_fab2(sch_1):page198_i85" )
			)
			( gate "Q1B1"
				( objectStatus "@baseboard_fab2_lib.baseboard_fab2(sch_1):page198_i86" )
			)
			( gate "Q8B1"
				( objectStatus "@baseboard_fab2_lib.baseboard_fab2(sch_1):page198_i87" )
			)
			( gate "Q7E7"
				( objectStatus "@baseboard_fab2_lib.baseboard_fab2(sch_1):page198_i88" )
			)
			( gate "R9P30"
				( objectStatus "@baseboard_fab2_lib.baseboard_fab2(sch_1):page199_i2" )
			)
			( gate "C1D25"
				( objectStatus "@baseboard_fab2_lib.baseboard_fab2(sch_1):page199_i3" )
			)
			( gate "R9P28"
				( objectStatus "@baseboard_fab2_lib.baseboard_fab2(sch_1):page199_i6" )
			)
			( gate "C1D27"
				( objectStatus "@baseboard_fab2_lib.baseboard_fab2(sch_1):page199_i7" )
			)
			( gate "R1D43"
				( objectStatus "@baseboard_fab2_lib.baseboard_fab2(sch_1):page199_i9" )
			)
			( gate "EU1D2"
				( objectStatus "@baseboard_fab2_lib.baseboard_fab2(sch_1):page199_i10" )
			)
			( gate "R9P29"
				( objectStatus "@baseboard_fab2_lib.baseboard_fab2(sch_1):page199_i12" )
			)
			( gate "R1D42"
				( objectStatus "@baseboard_fab2_lib.baseboard_fab2(sch_1):page199_i13" )
			)
			( gate "R1D37"
				( objectStatus "@baseboard_fab2_lib.baseboard_fab2(sch_1):page199_i15" )
			)
			( gate "R1D39"
				( objectStatus "@baseboard_fab2_lib.baseboard_fab2(sch_1):page199_i16" )
			)
			( gate "R1D32"
				( objectStatus "@baseboard_fab2_lib.baseboard_fab2(sch_1):page199_i17" )
			)
			( gate "R1D41"
				( objectStatus "@baseboard_fab2_lib.baseboard_fab2(sch_1):page199_i19" )
			)
			( gate "C9P14"
				( objectStatus "@baseboard_fab2_lib.baseboard_fab2(sch_1):page199_i24" )
			)
			( gate "R1D28"
				( objectStatus "@baseboard_fab2_lib.baseboard_fab2(sch_1):page199_i26" )
			)
			( gate "R1D24"
				( objectStatus "@baseboard_fab2_lib.baseboard_fab2(sch_1):page199_i27" )
			)
			( gate "R1D25"
				( objectStatus "@baseboard_fab2_lib.baseboard_fab2(sch_1):page199_i28" )
			)
			( gate "R9P17"
				( objectStatus "@baseboard_fab2_lib.baseboard_fab2(sch_1):page199_i33" )
			)
			( gate "R9P16"
				( objectStatus "@baseboard_fab2_lib.baseboard_fab2(sch_1):page199_i36" )
			)
			( gate "R1D29"
				( objectStatus "@baseboard_fab2_lib.baseboard_fab2(sch_1):page199_i37" )
			)
			( gate "R1D27"
				( objectStatus "@baseboard_fab2_lib.baseboard_fab2(sch_1):page199_i38" )
			)
			( gate "R9P18"
				( objectStatus "@baseboard_fab2_lib.baseboard_fab2(sch_1):page199_i41" )
			)
			( gate "R1D31"
				( objectStatus "@baseboard_fab2_lib.baseboard_fab2(sch_1):page199_i43" )
			)
			( gate "C1D11"
				( objectStatus "@baseboard_fab2_lib.baseboard_fab2(sch_1):page199_i53" )
			)
			( gate "R9P23"
				( objectStatus "@baseboard_fab2_lib.baseboard_fab2(sch_1):page199_i54" )
			)
			( gate "R9P24"
				( objectStatus "@baseboard_fab2_lib.baseboard_fab2(sch_1):page199_i55" )
			)
			( gate "Q1D3"
				( objectStatus "@baseboard_fab2_lib.baseboard_fab2(sch_1):page199_i58" )
			)
			( gate "R1D36"
				( objectStatus "@baseboard_fab2_lib.baseboard_fab2(sch_1):page199_i65" )
			)
			( gate "C9P12"
				( objectStatus "@baseboard_fab2_lib.baseboard_fab2(sch_1):page199_i67" )
			)
			( gate "Q1D1"
				( objectStatus "@baseboard_fab2_lib.baseboard_fab2(sch_1):page199_i82" )
			)
			( gate "R1D13"
				( objectStatus "@baseboard_fab2_lib.baseboard_fab2(sch_1):page199_i84" )
			)
			( gate "R1D16"
				( objectStatus "@baseboard_fab2_lib.baseboard_fab2(sch_1):page199_i85" )
			)
			( gate "Q1D1"
				( objectStatus "@baseboard_fab2_lib.baseboard_fab2(sch_1):page199_i86" )
			)
			( gate "R1D18"
				( objectStatus "@baseboard_fab2_lib.baseboard_fab2(sch_1):page199_i87" )
			)
			( gate "R1D11"
				( objectStatus "@baseboard_fab2_lib.baseboard_fab2(sch_1):page199_i88" )
			)
			( gate "R1D15"
				( objectStatus "@baseboard_fab2_lib.baseboard_fab2(sch_1):page199_i92" )
			)
			( gate "VR1D1"
				( objectStatus "@baseboard_fab2_lib.baseboard_fab2(sch_1):page199_i99" )
			)
			( gate "R1D40"
				( objectStatus "@baseboard_fab2_lib.baseboard_fab2(sch_1):page199_i100" )
			)
			( gate "R1D34"
				( objectStatus "@baseboard_fab2_lib.baseboard_fab2(sch_1):page199_i102" )
			)
			( gate "C9P15"
				( objectStatus "@baseboard_fab2_lib.baseboard_fab2(sch_1):page199_i105" )
			)
			( gate "C1D26"
				( objectStatus "@baseboard_fab2_lib.baseboard_fab2(sch_1):page199_i107" )
			)
			( gate "R1D33"
				( objectStatus "@baseboard_fab2_lib.baseboard_fab2(sch_1):page199_i108" )
			)
			( gate "R1D26"
				( objectStatus "@baseboard_fab2_lib.baseboard_fab2(sch_1):page199_i109" )
			)
			( gate "R1D30"
				( objectStatus "@baseboard_fab2_lib.baseboard_fab2(sch_1):page199_i110" )
			)
			( gate "C1D19"
				( objectStatus "@baseboard_fab2_lib.baseboard_fab2(sch_1):page199_i119" )
			)
			( gate "C1D21"
				( objectStatus "@baseboard_fab2_lib.baseboard_fab2(sch_1):page199_i121" )
			)
			( gate "J1B3"
				( objectStatus "@baseboard_fab2_lib.baseboard_fab2(sch_1):page199_i123" )
			)
			( gate "J1B4"
				( objectStatus "@baseboard_fab2_lib.baseboard_fab2(sch_1):page199_i124" )
			)
			( gate "C9P17"
				( objectStatus "@baseboard_fab2_lib.baseboard_fab2(sch_1):page200_i36" )
			)
			( gate "C9P16"
				( objectStatus "@baseboard_fab2_lib.baseboard_fab2(sch_1):page200_i40" )
			)
			( gate "C1D22"
				( objectStatus "@baseboard_fab2_lib.baseboard_fab2(sch_1):page200_i42" )
			)
			( gate "R1D45"
				( objectStatus "@baseboard_fab2_lib.baseboard_fab2(sch_1):page200_i43" )
			)
			( gate "R1D44"
				( objectStatus "@baseboard_fab2_lib.baseboard_fab2(sch_1):page200_i44" )
			)
			( gate "R9P27"
				( objectStatus "@baseboard_fab2_lib.baseboard_fab2(sch_1):page200_i47" )
			)
			( gate "R1D46"
				( objectStatus "@baseboard_fab2_lib.baseboard_fab2(sch_1):page200_i48" )
			)
			( gate "R9R1"
				( objectStatus "@baseboard_fab2_lib.baseboard_fab2(sch_1):page200_i49" )
			)
			( gate "R1D49"
				( objectStatus "@baseboard_fab2_lib.baseboard_fab2(sch_1):page200_i50" )
			)
			( gate "R9P26"
				( objectStatus "@baseboard_fab2_lib.baseboard_fab2(sch_1):page200_i51" )
			)
			( gate "R1D47"
				( objectStatus "@baseboard_fab2_lib.baseboard_fab2(sch_1):page200_i52" )
			)
			( gate "EU1E3"
				( objectStatus "@baseboard_fab2_lib.baseboard_fab2(sch_1):page200_i54" )
			)
			( gate "R1E1"
				( objectStatus "@baseboard_fab2_lib.baseboard_fab2(sch_1):page200_i56" )
			)
			( gate "EU9R1"
				( objectStatus "@baseboard_fab2_lib.baseboard_fab2(sch_1):page200_i57" )
			)
			( gate "R9R4"
				( objectStatus "@baseboard_fab2_lib.baseboard_fab2(sch_1):page200_i58" )
			)
			( gate "EU1E1"
				( objectStatus "@baseboard_fab2_lib.baseboard_fab2(sch_1):page200_i59" )
			)
			( gate "R1D48"
				( objectStatus "@baseboard_fab2_lib.baseboard_fab2(sch_1):page200_i60" )
			)
			( gate "R9P19"
				( objectStatus "@baseboard_fab2_lib.baseboard_fab2(sch_1):page200_i70" )
			)
			( gate "R9P21"
				( objectStatus "@baseboard_fab2_lib.baseboard_fab2(sch_1):page200_i71" )
			)
			( gate "R9P20"
				( objectStatus "@baseboard_fab2_lib.baseboard_fab2(sch_1):page200_i86" )
			)
			( gate "U1D1"
				( objectStatus "@baseboard_fab2_lib.baseboard_fab2(sch_1):page200_i103" )
			)
			( gate "R9P13"
				( objectStatus "@baseboard_fab2_lib.baseboard_fab2(sch_1):page200_i107" )
			)
			( gate "R9P11"
				( objectStatus "@baseboard_fab2_lib.baseboard_fab2(sch_1):page200_i108" )
			)
			( gate "R9P7"
				( objectStatus "@baseboard_fab2_lib.baseboard_fab2(sch_1):page200_i145" )
			)
			( gate "R9P9"
				( objectStatus "@baseboard_fab2_lib.baseboard_fab2(sch_1):page200_i146" )
			)
			( gate "R9P6"
				( objectStatus "@baseboard_fab2_lib.baseboard_fab2(sch_1):page200_i149" )
			)
			( gate "R1D51"
				( objectStatus "@baseboard_fab2_lib.baseboard_fab2(sch_1):page200_i154" )
			)
			( gate "C1E2"
				( objectStatus "@baseboard_fab2_lib.baseboard_fab2(sch_1):page200_i155" )
			)
			( gate "R1D22"
				( objectStatus "@baseboard_fab2_lib.baseboard_fab2(sch_1):page200_i158" )
			)
			( gate "U9P1"
				( objectStatus "@baseboard_fab2_lib.baseboard_fab2(sch_1):page200_i163" )
			)
			( gate "U1D2"
				( objectStatus "@baseboard_fab2_lib.baseboard_fab2(sch_1):page200_i170" )
			)
			( gate "R1D20"
				( objectStatus "@baseboard_fab2_lib.baseboard_fab2(sch_1):page200_i172" )
			)
			( gate "R1D14"
				( objectStatus "@baseboard_fab2_lib.baseboard_fab2(sch_1):page200_i173" )
			)
			( gate "R1D12"
				( objectStatus "@baseboard_fab2_lib.baseboard_fab2(sch_1):page200_i174" )
			)
			( gate "R1D19"
				( objectStatus "@baseboard_fab2_lib.baseboard_fab2(sch_1):page200_i175" )
			)
			( gate "C9P6"
				( objectStatus "@baseboard_fab2_lib.baseboard_fab2(sch_1):page200_i185" )
			)
			( gate "C1D9"
				( objectStatus "@baseboard_fab2_lib.baseboard_fab2(sch_1):page200_i187" )
			)
			( gate "R1D10"
				( objectStatus "@baseboard_fab2_lib.baseboard_fab2(sch_1):page200_i189" )
			)
			( gate "R1D23"
				( objectStatus "@baseboard_fab2_lib.baseboard_fab2(sch_1):page200_i191" )
			)
			( gate "R9P10"
				( objectStatus "@baseboard_fab2_lib.baseboard_fab2(sch_1):page200_i192" )
			)
			( gate "Q9P1"
				( objectStatus "@baseboard_fab2_lib.baseboard_fab2(sch_1):page200_i196" )
			)
			( gate "R9P15"
				( objectStatus "@baseboard_fab2_lib.baseboard_fab2(sch_1):page200_i198" )
			)
			( gate "Q9P1"
				( objectStatus "@baseboard_fab2_lib.baseboard_fab2(sch_1):page200_i199" )
			)
			( gate "U9P2"
				( objectStatus "@baseboard_fab2_lib.baseboard_fab2(sch_1):page200_i200" )
			)
			( gate "C9P11"
				( objectStatus "@baseboard_fab2_lib.baseboard_fab2(sch_1):page200_i201" )
			)
			( gate "Q1D2"
				( objectStatus "@baseboard_fab2_lib.baseboard_fab2(sch_1):page200_i203" )
			)
			( gate "R1D21"
				( objectStatus "@baseboard_fab2_lib.baseboard_fab2(sch_1):page200_i204" )
			)
			( gate "R9P4"
				( objectStatus "@baseboard_fab2_lib.baseboard_fab2(sch_1):page200_i210" )
			)
			( gate "CR9P2"
				( objectStatus "@baseboard_fab2_lib.baseboard_fab2(sch_1):page200_i213" )
			)
			( gate "CR9P1"
				( objectStatus "@baseboard_fab2_lib.baseboard_fab2(sch_1):page200_i214" )
			)
			( gate "R9P5"
				( objectStatus "@baseboard_fab2_lib.baseboard_fab2(sch_1):page200_i215" )
			)
			( gate "R9P12"
				( objectStatus "@baseboard_fab2_lib.baseboard_fab2(sch_1):page200_i218" )
			)
			( gate "CR1F5"
				( objectStatus "@baseboard_fab2_lib.baseboard_fab2(sch_1):page200_i220" )
			)
			( gate "R9P33"
				( objectStatus "@baseboard_fab2_lib.baseboard_fab2(sch_1):page200_i222" )
			)
			( gate "R4E4"
				( objectStatus "@baseboard_fab2_lib.baseboard_fab2(sch_1):page201_i19" )
			)
			( gate "R4E10"
				( objectStatus "@baseboard_fab2_lib.baseboard_fab2(sch_1):page201_i20" )
			)
			( gate "R4D31"
				( objectStatus "@baseboard_fab2_lib.baseboard_fab2(sch_1):page201_i22" )
			)
			( gate "R4D58"
				( objectStatus "@baseboard_fab2_lib.baseboard_fab2(sch_1):page201_i25" )
			)
			( gate "R4D67"
				( objectStatus "@baseboard_fab2_lib.baseboard_fab2(sch_1):page201_i26" )
			)
			( gate "R4E5"
				( objectStatus "@baseboard_fab2_lib.baseboard_fab2(sch_1):page201_i27" )
			)
			( gate "R4D50"
				( objectStatus "@baseboard_fab2_lib.baseboard_fab2(sch_1):page201_i28" )
			)
			( gate "C4D25"
				( objectStatus "@baseboard_fab2_lib.baseboard_fab2(sch_1):page201_i30" )
			)
			( gate "R4D53"
				( objectStatus "@baseboard_fab2_lib.baseboard_fab2(sch_1):page201_i31" )
			)
			( gate "C4D26"
				( objectStatus "@baseboard_fab2_lib.baseboard_fab2(sch_1):page201_i32" )
			)
			( gate "C4D15"
				( objectStatus "@baseboard_fab2_lib.baseboard_fab2(sch_1):page201_i37" )
			)
			( gate "C4D19"
				( objectStatus "@baseboard_fab2_lib.baseboard_fab2(sch_1):page201_i39" )
			)
			( gate "R4D26"
				( objectStatus "@baseboard_fab2_lib.baseboard_fab2(sch_1):page201_i40" )
			)
			( gate "R4E9"
				( objectStatus "@baseboard_fab2_lib.baseboard_fab2(sch_1):page201_i52" )
			)
			( gate "R4D27"
				( objectStatus "@baseboard_fab2_lib.baseboard_fab2(sch_1):page201_i54" )
			)
			( gate "R4D32"
				( objectStatus "@baseboard_fab2_lib.baseboard_fab2(sch_1):page201_i55" )
			)
			( gate "R4E6"
				( objectStatus "@baseboard_fab2_lib.baseboard_fab2(sch_1):page201_i56" )
			)
			( gate "C4D20"
				( objectStatus "@baseboard_fab2_lib.baseboard_fab2(sch_1):page201_i60" )
			)
			( gate "C4D29"
				( objectStatus "@baseboard_fab2_lib.baseboard_fab2(sch_1):page201_i64" )
			)
			( gate "C4D17"
				( objectStatus "@baseboard_fab2_lib.baseboard_fab2(sch_1):page201_i66" )
			)
			( gate "C4D18"
				( objectStatus "@baseboard_fab2_lib.baseboard_fab2(sch_1):page201_i68" )
			)
			( gate "C4D45"
				( objectStatus "@baseboard_fab2_lib.baseboard_fab2(sch_1):page201_i70" )
			)
			( gate "R4D66"
				( objectStatus "@baseboard_fab2_lib.baseboard_fab2(sch_1):page201_i98" )
			)
			( gate "R6P32"
				( objectStatus "@baseboard_fab2_lib.baseboard_fab2(sch_1):page201_i102" )
			)
			( gate "R6P37"
				( objectStatus "@baseboard_fab2_lib.baseboard_fab2(sch_1):page201_i103" )
			)
			( gate "R4E8"
				( objectStatus "@baseboard_fab2_lib.baseboard_fab2(sch_1):page201_i109" )
			)
			( gate "R4D39"
				( objectStatus "@baseboard_fab2_lib.baseboard_fab2(sch_1):page201_i110" )
			)
			( gate "R4E3"
				( objectStatus "@baseboard_fab2_lib.baseboard_fab2(sch_1):page201_i111" )
			)
			( gate "R4E20"
				( objectStatus "@baseboard_fab2_lib.baseboard_fab2(sch_1):page201_i116" )
			)
			( gate "R6P27"
				( objectStatus "@baseboard_fab2_lib.baseboard_fab2(sch_1):page201_i120" )
			)
			( gate "R6P28"
				( objectStatus "@baseboard_fab2_lib.baseboard_fab2(sch_1):page201_i121" )
			)
			( gate "J8D4"
				( objectStatus "@baseboard_fab2_lib.baseboard_fab2(sch_1):page201_i122" )
			)
			( gate "R4D63"
				( objectStatus "@baseboard_fab2_lib.baseboard_fab2(sch_1):page201_i124" )
			)
			( gate "C4D42"
				( objectStatus "@baseboard_fab2_lib.baseboard_fab2(sch_1):page201_i125" )
			)
			( gate "R4D65"
				( objectStatus "@baseboard_fab2_lib.baseboard_fab2(sch_1):page201_i127" )
			)
			( gate "R6P45"
				( objectStatus "@baseboard_fab2_lib.baseboard_fab2(sch_1):page201_i128" )
			)
			( gate "R6P18"
				( objectStatus "@baseboard_fab2_lib.baseboard_fab2(sch_1):page201_i131" )
			)
			( gate "R6P16"
				( objectStatus "@baseboard_fab2_lib.baseboard_fab2(sch_1):page201_i132" )
			)
			( gate "R6P42"
				( objectStatus "@baseboard_fab2_lib.baseboard_fab2(sch_1):page201_i139" )
			)
			( gate "R6P38"
				( objectStatus "@baseboard_fab2_lib.baseboard_fab2(sch_1):page201_i147" )
			)
			( gate "R6P34"
				( objectStatus "@baseboard_fab2_lib.baseboard_fab2(sch_1):page201_i148" )
			)
			( gate "R6P30"
				( objectStatus "@baseboard_fab2_lib.baseboard_fab2(sch_1):page201_i149" )
			)
			( gate "R6P43"
				( objectStatus "@baseboard_fab2_lib.baseboard_fab2(sch_1):page201_i150" )
			)
			( gate "R6P29"
				( objectStatus "@baseboard_fab2_lib.baseboard_fab2(sch_1):page201_i154" )
			)
			( gate "EU4D4"
				( objectStatus "@baseboard_fab2_lib.baseboard_fab2(sch_1):page201_i155" )
			)
			( gate "L4E1"
				( objectStatus "@baseboard_fab2_lib.baseboard_fab2(sch_1):page202_i5" )
			)
			( gate "C6R7"
				( objectStatus "@baseboard_fab2_lib.baseboard_fab2(sch_1):page202_i9" )
			)
			( gate "C4E5"
				( objectStatus "@baseboard_fab2_lib.baseboard_fab2(sch_1):page202_i18" )
			)
			( gate "C4E6"
				( objectStatus "@baseboard_fab2_lib.baseboard_fab2(sch_1):page202_i19" )
			)
			( gate "C4E17"
				( objectStatus "@baseboard_fab2_lib.baseboard_fab2(sch_1):page202_i22" )
			)
			( gate "C4E27"
				( objectStatus "@baseboard_fab2_lib.baseboard_fab2(sch_1):page202_i24" )
			)
			( gate "C4E25"
				( objectStatus "@baseboard_fab2_lib.baseboard_fab2(sch_1):page202_i25" )
			)
			( gate "C4E11"
				( objectStatus "@baseboard_fab2_lib.baseboard_fab2(sch_1):page202_i27" )
			)
			( gate "L4D3"
				( objectStatus "@baseboard_fab2_lib.baseboard_fab2(sch_1):page202_i29" )
			)
			( gate "C4D50"
				( objectStatus "@baseboard_fab2_lib.baseboard_fab2(sch_1):page202_i32" )
			)
			( gate "R6R2"
				( objectStatus "@baseboard_fab2_lib.baseboard_fab2(sch_1):page202_i33" )
			)
			( gate "C4E10"
				( objectStatus "@baseboard_fab2_lib.baseboard_fab2(sch_1):page202_i34" )
			)
			( gate "C4E20"
				( objectStatus "@baseboard_fab2_lib.baseboard_fab2(sch_1):page202_i35" )
			)
			( gate "C4E19"
				( objectStatus "@baseboard_fab2_lib.baseboard_fab2(sch_1):page202_i36" )
			)
			( gate "C6R11"
				( objectStatus "@baseboard_fab2_lib.baseboard_fab2(sch_1):page202_i37" )
			)
			( gate "C6P13"
				( objectStatus "@baseboard_fab2_lib.baseboard_fab2(sch_1):page202_i38" )
			)
			( gate "R6R6"
				( objectStatus "@baseboard_fab2_lib.baseboard_fab2(sch_1):page202_i39" )
			)
			( gate "C6R13"
				( objectStatus "@baseboard_fab2_lib.baseboard_fab2(sch_1):page202_i42" )
			)
			( gate "C4E26"
				( objectStatus "@baseboard_fab2_lib.baseboard_fab2(sch_1):page202_i45" )
			)
			( gate "C4D49"
				( objectStatus "@baseboard_fab2_lib.baseboard_fab2(sch_1):page202_i46" )
			)
			( gate "C4D48"
				( objectStatus "@baseboard_fab2_lib.baseboard_fab2(sch_1):page202_i47" )
			)
			( gate "C6R4"
				( objectStatus "@baseboard_fab2_lib.baseboard_fab2(sch_1):page202_i48" )
			)
			( gate "C6P22"
				( objectStatus "@baseboard_fab2_lib.baseboard_fab2(sch_1):page202_i49" )
			)
			( gate "C6N8"
				( objectStatus "@baseboard_fab2_lib.baseboard_fab2(sch_1):page202_i51" )
			)
			( gate "C4E3"
				( objectStatus "@baseboard_fab2_lib.baseboard_fab2(sch_1):page202_i61" )
			)
			( gate "C6P16"
				( objectStatus "@baseboard_fab2_lib.baseboard_fab2(sch_1):page202_i62" )
			)
			( gate "EU4E1"
				( objectStatus "@baseboard_fab2_lib.baseboard_fab2(sch_1):page202_i63" )
			)
			( gate "EU4D6"
				( objectStatus "@baseboard_fab2_lib.baseboard_fab2(sch_1):page202_i64" )
			)
			( gate "R4E22"
				( objectStatus "@baseboard_fab2_lib.baseboard_fab2(sch_1):page202_i65" )
			)
			( gate "R4E19"
				( objectStatus "@baseboard_fab2_lib.baseboard_fab2(sch_1):page202_i67" )
			)
			( gate "C6P24"
				( objectStatus "@baseboard_fab2_lib.baseboard_fab2(sch_1):page203_i1" )
			)
			( gate "C6R6"
				( objectStatus "@baseboard_fab2_lib.baseboard_fab2(sch_1):page203_i2" )
			)
			( gate "C4D9"
				( objectStatus "@baseboard_fab2_lib.baseboard_fab2(sch_1):page203_i3" )
			)
			( gate "L4D2"
				( objectStatus "@baseboard_fab2_lib.baseboard_fab2(sch_1):page203_i15" )
			)
			( gate "C6R3"
				( objectStatus "@baseboard_fab2_lib.baseboard_fab2(sch_1):page203_i16" )
			)
			( gate "C6R9"
				( objectStatus "@baseboard_fab2_lib.baseboard_fab2(sch_1):page203_i18" )
			)
			( gate "L4D1"
				( objectStatus "@baseboard_fab2_lib.baseboard_fab2(sch_1):page203_i24" )
			)
			( gate "C6P3"
				( objectStatus "@baseboard_fab2_lib.baseboard_fab2(sch_1):page203_i25" )
			)
			( gate "C6P23"
				( objectStatus "@baseboard_fab2_lib.baseboard_fab2(sch_1):page203_i28" )
			)
			( gate "C6P14"
				( objectStatus "@baseboard_fab2_lib.baseboard_fab2(sch_1):page203_i29" )
			)
			( gate "C6P18"
				( objectStatus "@baseboard_fab2_lib.baseboard_fab2(sch_1):page203_i30" )
			)
			( gate "C6P8"
				( objectStatus "@baseboard_fab2_lib.baseboard_fab2(sch_1):page203_i32" )
			)
			( gate "C6N9"
				( objectStatus "@baseboard_fab2_lib.baseboard_fab2(sch_1):page203_i34" )
			)
			( gate "R6P19"
				( objectStatus "@baseboard_fab2_lib.baseboard_fab2(sch_1):page203_i38" )
			)
			( gate "C4D13"
				( objectStatus "@baseboard_fab2_lib.baseboard_fab2(sch_1):page203_i40" )
			)
			( gate "C4D14"
				( objectStatus "@baseboard_fab2_lib.baseboard_fab2(sch_1):page203_i41" )
			)
			( gate "C4D28"
				( objectStatus "@baseboard_fab2_lib.baseboard_fab2(sch_1):page203_i42" )
			)
			( gate "C4D16"
				( objectStatus "@baseboard_fab2_lib.baseboard_fab2(sch_1):page203_i45" )
			)
			( gate "C4D35"
				( objectStatus "@baseboard_fab2_lib.baseboard_fab2(sch_1):page203_i46" )
			)
			( gate "C4D30"
				( objectStatus "@baseboard_fab2_lib.baseboard_fab2(sch_1):page203_i47" )
			)
			( gate "C4D5"
				( objectStatus "@baseboard_fab2_lib.baseboard_fab2(sch_1):page203_i48" )
			)
			( gate "C4D6"
				( objectStatus "@baseboard_fab2_lib.baseboard_fab2(sch_1):page203_i49" )
			)
			( gate "R6P10"
				( objectStatus "@baseboard_fab2_lib.baseboard_fab2(sch_1):page203_i50" )
			)
			( gate "C4D7"
				( objectStatus "@baseboard_fab2_lib.baseboard_fab2(sch_1):page203_i51" )
			)
			( gate "C4D11"
				( objectStatus "@baseboard_fab2_lib.baseboard_fab2(sch_1):page203_i52" )
			)
			( gate "C4D10"
				( objectStatus "@baseboard_fab2_lib.baseboard_fab2(sch_1):page203_i53" )
			)
			( gate "C6P19"
				( objectStatus "@baseboard_fab2_lib.baseboard_fab2(sch_1):page203_i54" )
			)
			( gate "C6P20"
				( objectStatus "@baseboard_fab2_lib.baseboard_fab2(sch_1):page203_i57" )
			)
			( gate "C6P15"
				( objectStatus "@baseboard_fab2_lib.baseboard_fab2(sch_1):page203_i58" )
			)
			( gate "C6P7"
				( objectStatus "@baseboard_fab2_lib.baseboard_fab2(sch_1):page203_i59" )
			)
			( gate "C6P21"
				( objectStatus "@baseboard_fab2_lib.baseboard_fab2(sch_1):page203_i66" )
			)
			( gate "R4E13"
				( objectStatus "@baseboard_fab2_lib.baseboard_fab2(sch_1):page203_i67" )
			)
			( gate "C4D34"
				( objectStatus "@baseboard_fab2_lib.baseboard_fab2(sch_1):page203_i68" )
			)
			( gate "C4D4"
				( objectStatus "@baseboard_fab2_lib.baseboard_fab2(sch_1):page203_i69" )
			)
			( gate "EU4D3"
				( objectStatus "@baseboard_fab2_lib.baseboard_fab2(sch_1):page203_i70" )
			)
			( gate "EU4D1"
				( objectStatus "@baseboard_fab2_lib.baseboard_fab2(sch_1):page203_i71" )
			)
			( gate "R4D72"
				( objectStatus "@baseboard_fab2_lib.baseboard_fab2(sch_1):page203_i89" )
			)
			( gate "R4D71"
				( objectStatus "@baseboard_fab2_lib.baseboard_fab2(sch_1):page203_i91" )
			)
			( gate "L4C3"
				( objectStatus "@baseboard_fab2_lib.baseboard_fab2(sch_1):page204_i5" )
			)
			( gate "C4D12"
				( objectStatus "@baseboard_fab2_lib.baseboard_fab2(sch_1):page204_i9" )
			)
			( gate "C4D47"
				( objectStatus "@baseboard_fab2_lib.baseboard_fab2(sch_1):page204_i18" )
			)
			( gate "C4C14"
				( objectStatus "@baseboard_fab2_lib.baseboard_fab2(sch_1):page204_i19" )
			)
			( gate "C4C17"
				( objectStatus "@baseboard_fab2_lib.baseboard_fab2(sch_1):page204_i22" )
			)
			( gate "R6P47"
				( objectStatus "@baseboard_fab2_lib.baseboard_fab2(sch_1):page204_i33" )
			)
			( gate "C4D46"
				( objectStatus "@baseboard_fab2_lib.baseboard_fab2(sch_1):page204_i34" )
			)
			( gate "C4C19"
				( objectStatus "@baseboard_fab2_lib.baseboard_fab2(sch_1):page204_i35" )
			)
			( gate "C4C18"
				( objectStatus "@baseboard_fab2_lib.baseboard_fab2(sch_1):page204_i36" )
			)
			( gate "C6N10"
				( objectStatus "@baseboard_fab2_lib.baseboard_fab2(sch_1):page204_i37" )
			)
			( gate "C6P17"
				( objectStatus "@baseboard_fab2_lib.baseboard_fab2(sch_1):page204_i38" )
			)
			( gate "C6N11"
				( objectStatus "@baseboard_fab2_lib.baseboard_fab2(sch_1):page204_i42" )
			)
			( gate "R4C6"
				( objectStatus "@baseboard_fab2_lib.baseboard_fab2(sch_1):page204_i45" )
			)
			( gate "L4C1"
				( objectStatus "@baseboard_fab2_lib.baseboard_fab2(sch_1):page204_i46" )
			)
			( gate "C4D2"
				( objectStatus "@baseboard_fab2_lib.baseboard_fab2(sch_1):page204_i48" )
			)
			( gate "C4E16"
				( objectStatus "@baseboard_fab2_lib.baseboard_fab2(sch_1):page204_i50" )
			)
			( gate "C4C2"
				( objectStatus "@baseboard_fab2_lib.baseboard_fab2(sch_1):page204_i51" )
			)
			( gate "U4C1"
				( objectStatus "@baseboard_fab2_lib.baseboard_fab2(sch_1):page204_i53" )
			)
			( gate "R4E14"
				( objectStatus "@baseboard_fab2_lib.baseboard_fab2(sch_1):page204_i60" )
			)
			( gate "R4E16"
				( objectStatus "@baseboard_fab2_lib.baseboard_fab2(sch_1):page204_i61" )
			)
			( gate "R4E17"
				( objectStatus "@baseboard_fab2_lib.baseboard_fab2(sch_1):page204_i62" )
			)
			( gate "R4E15"
				( objectStatus "@baseboard_fab2_lib.baseboard_fab2(sch_1):page204_i63" )
			)
			( gate "R4E18"
				( objectStatus "@baseboard_fab2_lib.baseboard_fab2(sch_1):page204_i64" )
			)
			( gate "C4C12"
				( objectStatus "@baseboard_fab2_lib.baseboard_fab2(sch_1):page204_i67" )
			)
			( gate "C6R2"
				( objectStatus "@baseboard_fab2_lib.baseboard_fab2(sch_1):page204_i70" )
			)
			( gate "EU4C2"
				( objectStatus "@baseboard_fab2_lib.baseboard_fab2(sch_1):page204_i71" )
			)
			( gate "R4D68"
				( objectStatus "@baseboard_fab2_lib.baseboard_fab2(sch_1):page204_i83" )
			)
			( gate "C6N7"
				( objectStatus "@baseboard_fab2_lib.baseboard_fab2(sch_1):page205_i5" )
			)
			( gate "L4C2"
				( objectStatus "@baseboard_fab2_lib.baseboard_fab2(sch_1):page205_i7" )
			)
			( gate "C6N1"
				( objectStatus "@baseboard_fab2_lib.baseboard_fab2(sch_1):page205_i12" )
			)
			( gate "C6N4"
				( objectStatus "@baseboard_fab2_lib.baseboard_fab2(sch_1):page205_i14" )
			)
			( gate "C4C5"
				( objectStatus "@baseboard_fab2_lib.baseboard_fab2(sch_1):page205_i16" )
			)
			( gate "C4C4"
				( objectStatus "@baseboard_fab2_lib.baseboard_fab2(sch_1):page205_i18" )
			)
			( gate "R6N3"
				( objectStatus "@baseboard_fab2_lib.baseboard_fab2(sch_1):page205_i19" )
			)
			( gate "C4C6"
				( objectStatus "@baseboard_fab2_lib.baseboard_fab2(sch_1):page205_i20" )
			)
			( gate "R4C5"
				( objectStatus "@baseboard_fab2_lib.baseboard_fab2(sch_1):page205_i24" )
			)
			( gate "C4C8"
				( objectStatus "@baseboard_fab2_lib.baseboard_fab2(sch_1):page205_i25" )
			)
			( gate "R4C4"
				( objectStatus "@baseboard_fab2_lib.baseboard_fab2(sch_1):page205_i26" )
			)
			( gate "R4C1"
				( objectStatus "@baseboard_fab2_lib.baseboard_fab2(sch_1):page205_i29" )
			)
			( gate "R4C2"
				( objectStatus "@baseboard_fab2_lib.baseboard_fab2(sch_1):page205_i30" )
			)
			( gate "C4C10"
				( objectStatus "@baseboard_fab2_lib.baseboard_fab2(sch_1):page205_i31" )
			)
			( gate "C4C9"
				( objectStatus "@baseboard_fab2_lib.baseboard_fab2(sch_1):page205_i32" )
			)
			( gate "C6N2"
				( objectStatus "@baseboard_fab2_lib.baseboard_fab2(sch_1):page205_i33" )
			)
			( gate "C6N3"
				( objectStatus "@baseboard_fab2_lib.baseboard_fab2(sch_1):page205_i34" )
			)
			( gate "C6N6"
				( objectStatus "@baseboard_fab2_lib.baseboard_fab2(sch_1):page205_i35" )
			)
			( gate "R4C3"
				( objectStatus "@baseboard_fab2_lib.baseboard_fab2(sch_1):page205_i37" )
			)
			( gate "C4C11"
				( objectStatus "@baseboard_fab2_lib.baseboard_fab2(sch_1):page205_i43" )
			)
			( gate "R6N4"
				( objectStatus "@baseboard_fab2_lib.baseboard_fab2(sch_1):page205_i45" )
			)
			( gate "EU4C1"
				( objectStatus "@baseboard_fab2_lib.baseboard_fab2(sch_1):page205_i46" )
			)
			( gate "R4C13"
				( objectStatus "@baseboard_fab2_lib.baseboard_fab2(sch_1):page205_i62" )
			)
			( gate "R9P1"
				( objectStatus "@baseboard_fab2_lib.baseboard_fab2(sch_1):page206_i4" )
			)
			( gate "R1D6"
				( objectStatus "@baseboard_fab2_lib.baseboard_fab2(sch_1):page206_i6" )
			)
			( gate "R1D7"
				( objectStatus "@baseboard_fab2_lib.baseboard_fab2(sch_1):page206_i7" )
			)
			( gate "R1C23"
				( objectStatus "@baseboard_fab2_lib.baseboard_fab2(sch_1):page206_i27" )
			)
			( gate "R1C25"
				( objectStatus "@baseboard_fab2_lib.baseboard_fab2(sch_1):page206_i28" )
			)
			( gate "C1C13"
				( objectStatus "@baseboard_fab2_lib.baseboard_fab2(sch_1):page206_i29" )
			)
			( gate "C1C14"
				( objectStatus "@baseboard_fab2_lib.baseboard_fab2(sch_1):page206_i31" )
			)
			( gate "R1D53"
				( objectStatus "@baseboard_fab2_lib.baseboard_fab2(sch_1):page206_i33" )
			)
			( gate "R1C18"
				( objectStatus "@baseboard_fab2_lib.baseboard_fab2(sch_1):page206_i34" )
			)
			( gate "R1C28"
				( objectStatus "@baseboard_fab2_lib.baseboard_fab2(sch_1):page206_i35" )
			)
			( gate "R1D8"
				( objectStatus "@baseboard_fab2_lib.baseboard_fab2(sch_1):page206_i36" )
			)
			( gate "R1D3"
				( objectStatus "@baseboard_fab2_lib.baseboard_fab2(sch_1):page206_i37" )
			)
			( gate "R1D2"
				( objectStatus "@baseboard_fab2_lib.baseboard_fab2(sch_1):page206_i38" )
			)
			( gate "C1C7"
				( objectStatus "@baseboard_fab2_lib.baseboard_fab2(sch_1):page206_i41" )
			)
			( gate "C1C9"
				( objectStatus "@baseboard_fab2_lib.baseboard_fab2(sch_1):page206_i42" )
			)
			( gate "R1C14"
				( objectStatus "@baseboard_fab2_lib.baseboard_fab2(sch_1):page206_i46" )
			)
			( gate "R1C13"
				( objectStatus "@baseboard_fab2_lib.baseboard_fab2(sch_1):page206_i49" )
			)
			( gate "R9P2"
				( objectStatus "@baseboard_fab2_lib.baseboard_fab2(sch_1):page206_i53" )
			)
			( gate "R1D9"
				( objectStatus "@baseboard_fab2_lib.baseboard_fab2(sch_1):page206_i54" )
			)
			( gate "R1C16"
				( objectStatus "@baseboard_fab2_lib.baseboard_fab2(sch_1):page206_i56" )
			)
			( gate "C1C16"
				( objectStatus "@baseboard_fab2_lib.baseboard_fab2(sch_1):page206_i68" )
			)
			( gate "C1C10"
				( objectStatus "@baseboard_fab2_lib.baseboard_fab2(sch_1):page206_i69" )
			)
			( gate "C1C11"
				( objectStatus "@baseboard_fab2_lib.baseboard_fab2(sch_1):page206_i71" )
			)
			( gate "C1C8"
				( objectStatus "@baseboard_fab2_lib.baseboard_fab2(sch_1):page206_i73" )
			)
			( gate "R1C21"
				( objectStatus "@baseboard_fab2_lib.baseboard_fab2(sch_1):page206_i77" )
			)
			( gate "C1D1"
				( objectStatus "@baseboard_fab2_lib.baseboard_fab2(sch_1):page206_i78" )
			)
			( gate "R1D4"
				( objectStatus "@baseboard_fab2_lib.baseboard_fab2(sch_1):page206_i79" )
			)
			( gate "R9N7"
				( objectStatus "@baseboard_fab2_lib.baseboard_fab2(sch_1):page206_i111" )
			)
			( gate "R9N8"
				( objectStatus "@baseboard_fab2_lib.baseboard_fab2(sch_1):page206_i112" )
			)
			( gate "R1C30"
				( objectStatus "@baseboard_fab2_lib.baseboard_fab2(sch_1):page206_i113" )
			)
			( gate "C1C23"
				( objectStatus "@baseboard_fab2_lib.baseboard_fab2(sch_1):page206_i114" )
			)
			( gate "R1D1"
				( objectStatus "@baseboard_fab2_lib.baseboard_fab2(sch_1):page206_i116" )
			)
			( gate "R9P3"
				( objectStatus "@baseboard_fab2_lib.baseboard_fab2(sch_1):page206_i117" )
			)
			( gate "R9N16"
				( objectStatus "@baseboard_fab2_lib.baseboard_fab2(sch_1):page206_i119" )
			)
			( gate "R9N14"
				( objectStatus "@baseboard_fab2_lib.baseboard_fab2(sch_1):page206_i120" )
			)
			( gate "R9N15"
				( objectStatus "@baseboard_fab2_lib.baseboard_fab2(sch_1):page206_i122" )
			)
			( gate "R9N17"
				( objectStatus "@baseboard_fab2_lib.baseboard_fab2(sch_1):page206_i123" )
			)
			( gate "R9N12"
				( objectStatus "@baseboard_fab2_lib.baseboard_fab2(sch_1):page206_i124" )
			)
			( gate "R9N10"
				( objectStatus "@baseboard_fab2_lib.baseboard_fab2(sch_1):page206_i125" )
			)
			( gate "R9N9"
				( objectStatus "@baseboard_fab2_lib.baseboard_fab2(sch_1):page206_i126" )
			)
			( gate "R9N5"
				( objectStatus "@baseboard_fab2_lib.baseboard_fab2(sch_1):page206_i128" )
			)
			( gate "EU1C2"
				( objectStatus "@baseboard_fab2_lib.baseboard_fab2(sch_1):page206_i130" )
			)
			( gate "C9R8"
				( objectStatus "@baseboard_fab2_lib.baseboard_fab2(sch_1):page207_i8" )
			)
			( gate "L1E1"
				( objectStatus "@baseboard_fab2_lib.baseboard_fab2(sch_1):page207_i10" )
			)
			( gate "L1D3"
				( objectStatus "@baseboard_fab2_lib.baseboard_fab2(sch_1):page207_i16" )
			)
			( gate "C1E3"
				( objectStatus "@baseboard_fab2_lib.baseboard_fab2(sch_1):page207_i18" )
			)
			( gate "EU1E2"
				( objectStatus "@baseboard_fab2_lib.baseboard_fab2(sch_1):page207_i20" )
			)
			( gate "EU1D4"
				( objectStatus "@baseboard_fab2_lib.baseboard_fab2(sch_1):page207_i24" )
			)
			( gate "R9R2"
				( objectStatus "@baseboard_fab2_lib.baseboard_fab2(sch_1):page207_i26" )
			)
			( gate "C1E7"
				( objectStatus "@baseboard_fab2_lib.baseboard_fab2(sch_1):page207_i28" )
			)
			( gate "C1E6"
				( objectStatus "@baseboard_fab2_lib.baseboard_fab2(sch_1):page207_i29" )
			)
			( gate "C1E11"
				( objectStatus "@baseboard_fab2_lib.baseboard_fab2(sch_1):page207_i30" )
			)
			( gate "C1E8"
				( objectStatus "@baseboard_fab2_lib.baseboard_fab2(sch_1):page207_i32" )
			)
			( gate "C1E14"
				( objectStatus "@baseboard_fab2_lib.baseboard_fab2(sch_1):page207_i33" )
			)
			( gate "C1E13"
				( objectStatus "@baseboard_fab2_lib.baseboard_fab2(sch_1):page207_i34" )
			)
			( gate "C1E25"
				( objectStatus "@baseboard_fab2_lib.baseboard_fab2(sch_1):page207_i36" )
			)
			( gate "C1E23"
				( objectStatus "@baseboard_fab2_lib.baseboard_fab2(sch_1):page207_i37" )
			)
			( gate "C1D36"
				( objectStatus "@baseboard_fab2_lib.baseboard_fab2(sch_1):page207_i38" )
			)
			( gate "R9R11"
				( objectStatus "@baseboard_fab2_lib.baseboard_fab2(sch_1):page207_i39" )
			)
			( gate "C1E24"
				( objectStatus "@baseboard_fab2_lib.baseboard_fab2(sch_1):page207_i40" )
			)
			( gate "C1D34"
				( objectStatus "@baseboard_fab2_lib.baseboard_fab2(sch_1):page207_i41" )
			)
			( gate "C1D35"
				( objectStatus "@baseboard_fab2_lib.baseboard_fab2(sch_1):page207_i42" )
			)
			( gate "C9R7"
				( objectStatus "@baseboard_fab2_lib.baseboard_fab2(sch_1):page207_i43" )
			)
			( gate "C9R10"
				( objectStatus "@baseboard_fab2_lib.baseboard_fab2(sch_1):page207_i44" )
			)
			( gate "C9R11"
				( objectStatus "@baseboard_fab2_lib.baseboard_fab2(sch_1):page207_i48" )
			)
			( gate "C9P22"
				( objectStatus "@baseboard_fab2_lib.baseboard_fab2(sch_1):page207_i50" )
			)
			( gate "C9P25"
				( objectStatus "@baseboard_fab2_lib.baseboard_fab2(sch_1):page207_i51" )
			)
			( gate "C9P26"
				( objectStatus "@baseboard_fab2_lib.baseboard_fab2(sch_1):page207_i54" )
			)
			( gate "C1E9"
				( objectStatus "@baseboard_fab2_lib.baseboard_fab2(sch_1):page207_i58" )
			)
			( gate "C9P3"
				( objectStatus "@baseboard_fab2_lib.baseboard_fab2(sch_1):page207_i59" )
			)
			( gate "R1E13"
				( objectStatus "@baseboard_fab2_lib.baseboard_fab2(sch_1):page207_i67" )
			)
			( gate "R1E14"
				( objectStatus "@baseboard_fab2_lib.baseboard_fab2(sch_1):page207_i68" )
			)
			( gate "R1E3"
				( objectStatus "@baseboard_fab2_lib.baseboard_fab2(sch_1):page208_i7" )
			)
			( gate "C1D14"
				( objectStatus "@baseboard_fab2_lib.baseboard_fab2(sch_1):page208_i9" )
			)
			( gate "L1D2"
				( objectStatus "@baseboard_fab2_lib.baseboard_fab2(sch_1):page208_i11" )
			)
			( gate "C9P8"
				( objectStatus "@baseboard_fab2_lib.baseboard_fab2(sch_1):page208_i12" )
			)
			( gate "C9P5"
				( objectStatus "@baseboard_fab2_lib.baseboard_fab2(sch_1):page208_i14" )
			)
			( gate "L1D1"
				( objectStatus "@baseboard_fab2_lib.baseboard_fab2(sch_1):page208_i20" )
			)
			( gate "C1D3"
				( objectStatus "@baseboard_fab2_lib.baseboard_fab2(sch_1):page208_i22" )
			)
			( gate "C9N24"
				( objectStatus "@baseboard_fab2_lib.baseboard_fab2(sch_1):page208_i24" )
			)
			( gate "C9R9"
				( objectStatus "@baseboard_fab2_lib.baseboard_fab2(sch_1):page208_i25" )
			)
			( gate "C9R3"
				( objectStatus "@baseboard_fab2_lib.baseboard_fab2(sch_1):page208_i26" )
			)
			( gate "EU1D3"
				( objectStatus "@baseboard_fab2_lib.baseboard_fab2(sch_1):page208_i27" )
			)
			( gate "C9P23"
				( objectStatus "@baseboard_fab2_lib.baseboard_fab2(sch_1):page208_i28" )
			)
			( gate "C9P18"
				( objectStatus "@baseboard_fab2_lib.baseboard_fab2(sch_1):page208_i30" )
			)
			( gate "R9P22"
				( objectStatus "@baseboard_fab2_lib.baseboard_fab2(sch_1):page208_i36" )
			)
			( gate "C1D16"
				( objectStatus "@baseboard_fab2_lib.baseboard_fab2(sch_1):page208_i38" )
			)
			( gate "C1D15"
				( objectStatus "@baseboard_fab2_lib.baseboard_fab2(sch_1):page208_i39" )
			)
			( gate "C1D20"
				( objectStatus "@baseboard_fab2_lib.baseboard_fab2(sch_1):page208_i40" )
			)
			( gate "C1D17"
				( objectStatus "@baseboard_fab2_lib.baseboard_fab2(sch_1):page208_i43" )
			)
			( gate "C1D28"
				( objectStatus "@baseboard_fab2_lib.baseboard_fab2(sch_1):page208_i44" )
			)
			( gate "C1D23"
				( objectStatus "@baseboard_fab2_lib.baseboard_fab2(sch_1):page208_i45" )
			)
			( gate "C1D6"
				( objectStatus "@baseboard_fab2_lib.baseboard_fab2(sch_1):page208_i46" )
			)
			( gate "C1D5"
				( objectStatus "@baseboard_fab2_lib.baseboard_fab2(sch_1):page208_i47" )
			)
			( gate "C1D10"
				( objectStatus "@baseboard_fab2_lib.baseboard_fab2(sch_1):page208_i48" )
			)
			( gate "R9P8"
				( objectStatus "@baseboard_fab2_lib.baseboard_fab2(sch_1):page208_i49" )
			)
			( gate "C1D7"
				( objectStatus "@baseboard_fab2_lib.baseboard_fab2(sch_1):page208_i50" )
			)
			( gate "C1D13"
				( objectStatus "@baseboard_fab2_lib.baseboard_fab2(sch_1):page208_i51" )
			)
			( gate "C1D12"
				( objectStatus "@baseboard_fab2_lib.baseboard_fab2(sch_1):page208_i52" )
			)
			( gate "C9P4"
				( objectStatus "@baseboard_fab2_lib.baseboard_fab2(sch_1):page208_i53" )
			)
			( gate "C9P7"
				( objectStatus "@baseboard_fab2_lib.baseboard_fab2(sch_1):page208_i54" )
			)
			( gate "C9P9"
				( objectStatus "@baseboard_fab2_lib.baseboard_fab2(sch_1):page208_i55" )
			)
			( gate "C9P24"
				( objectStatus "@baseboard_fab2_lib.baseboard_fab2(sch_1):page208_i58" )
			)
			( gate "C9P1"
				( objectStatus "@baseboard_fab2_lib.baseboard_fab2(sch_1):page208_i59" )
			)
			( gate "C9P2"
				( objectStatus "@baseboard_fab2_lib.baseboard_fab2(sch_1):page208_i60" )
			)
			( gate "C9P10"
				( objectStatus "@baseboard_fab2_lib.baseboard_fab2(sch_1):page208_i66" )
			)
			( gate "C9R2"
				( objectStatus "@baseboard_fab2_lib.baseboard_fab2(sch_1):page208_i67" )
			)
			( gate "EU1D1"
				( objectStatus "@baseboard_fab2_lib.baseboard_fab2(sch_1):page208_i71" )
			)
			( gate "R1D54"
				( objectStatus "@baseboard_fab2_lib.baseboard_fab2(sch_1):page208_i75" )
			)
			( gate "R1D55"
				( objectStatus "@baseboard_fab2_lib.baseboard_fab2(sch_1):page208_i76" )
			)
			( gate "R1E5"
				( objectStatus "@baseboard_fab2_lib.baseboard_fab2(sch_1):page209_i3" )
			)
			( gate "C9N27"
				( objectStatus "@baseboard_fab2_lib.baseboard_fab2(sch_1):page209_i5" )
			)
			( gate "C9N26"
				( objectStatus "@baseboard_fab2_lib.baseboard_fab2(sch_1):page209_i7" )
			)
			( gate "C9N25"
				( objectStatus "@baseboard_fab2_lib.baseboard_fab2(sch_1):page209_i8" )
			)
			( gate "R1E8"
				( objectStatus "@baseboard_fab2_lib.baseboard_fab2(sch_1):page209_i9" )
			)
			( gate "R1E7"
				( objectStatus "@baseboard_fab2_lib.baseboard_fab2(sch_1):page209_i10" )
			)
			( gate "R1E6"
				( objectStatus "@baseboard_fab2_lib.baseboard_fab2(sch_1):page209_i11" )
			)
			( gate "R1E4"
				( objectStatus "@baseboard_fab2_lib.baseboard_fab2(sch_1):page209_i15" )
			)
			( gate "C1C26"
				( objectStatus "@baseboard_fab2_lib.baseboard_fab2(sch_1):page209_i16" )
			)
			( gate "C1C25"
				( objectStatus "@baseboard_fab2_lib.baseboard_fab2(sch_1):page209_i17" )
			)
			( gate "C1D32"
				( objectStatus "@baseboard_fab2_lib.baseboard_fab2(sch_1):page209_i18" )
			)
			( gate "C1C24"
				( objectStatus "@baseboard_fab2_lib.baseboard_fab2(sch_1):page209_i20" )
			)
			( gate "C1C18"
				( objectStatus "@baseboard_fab2_lib.baseboard_fab2(sch_1):page209_i21" )
			)
			( gate "C1D33"
				( objectStatus "@baseboard_fab2_lib.baseboard_fab2(sch_1):page209_i22" )
			)
			( gate "R9P32"
				( objectStatus "@baseboard_fab2_lib.baseboard_fab2(sch_1):page209_i24" )
			)
			( gate "C1B16"
				( objectStatus "@baseboard_fab2_lib.baseboard_fab2(sch_1):page209_i30" )
			)
			( gate "L1B2"
				( objectStatus "@baseboard_fab2_lib.baseboard_fab2(sch_1):page209_i32" )
			)
			( gate "C1C1"
				( objectStatus "@baseboard_fab2_lib.baseboard_fab2(sch_1):page209_i35" )
			)
			( gate "C1E18"
				( objectStatus "@baseboard_fab2_lib.baseboard_fab2(sch_1):page209_i37" )
			)
			( gate "C1C2"
				( objectStatus "@baseboard_fab2_lib.baseboard_fab2(sch_1):page209_i38" )
			)
			( gate "R1B20"
				( objectStatus "@baseboard_fab2_lib.baseboard_fab2(sch_1):page209_i39" )
			)
			( gate "L1C2"
				( objectStatus "@baseboard_fab2_lib.baseboard_fab2(sch_1):page209_i40" )
			)
			( gate "C1D24"
				( objectStatus "@baseboard_fab2_lib.baseboard_fab2(sch_1):page209_i42" )
			)
			( gate "U1B3"
				( objectStatus "@baseboard_fab2_lib.baseboard_fab2(sch_1):page209_i52" )
			)
			( gate "C9P20"
				( objectStatus "@baseboard_fab2_lib.baseboard_fab2(sch_1):page209_i55" )
			)
			( gate "EU1C3"
				( objectStatus "@baseboard_fab2_lib.baseboard_fab2(sch_1):page209_i56" )
			)
			( gate "R1D52"
				( objectStatus "@baseboard_fab2_lib.baseboard_fab2(sch_1):page209_i59" )
			)
			( gate "C1C19"
				( objectStatus "@baseboard_fab2_lib.baseboard_fab2(sch_1):page210_i8" )
			)
			( gate "L1C1"
				( objectStatus "@baseboard_fab2_lib.baseboard_fab2(sch_1):page210_i10" )
			)
			( gate "C9N11"
				( objectStatus "@baseboard_fab2_lib.baseboard_fab2(sch_1):page210_i12" )
			)
			( gate "C9N20"
				( objectStatus "@baseboard_fab2_lib.baseboard_fab2(sch_1):page210_i14" )
			)
			( gate "R9N3"
				( objectStatus "@baseboard_fab2_lib.baseboard_fab2(sch_1):page210_i20" )
			)
			( gate "C1C4"
				( objectStatus "@baseboard_fab2_lib.baseboard_fab2(sch_1):page210_i22" )
			)
			( gate "C1C3"
				( objectStatus "@baseboard_fab2_lib.baseboard_fab2(sch_1):page210_i23" )
			)
			( gate "C1C12"
				( objectStatus "@baseboard_fab2_lib.baseboard_fab2(sch_1):page210_i24" )
			)
			( gate "C1C5"
				( objectStatus "@baseboard_fab2_lib.baseboard_fab2(sch_1):page210_i26" )
			)
			( gate "C1C17"
				( objectStatus "@baseboard_fab2_lib.baseboard_fab2(sch_1):page210_i27" )
			)
			( gate "C1C15"
				( objectStatus "@baseboard_fab2_lib.baseboard_fab2(sch_1):page210_i28" )
			)
			( gate "R1C12"
				( objectStatus "@baseboard_fab2_lib.baseboard_fab2(sch_1):page210_i29" )
			)
			( gate "R1C7"
				( objectStatus "@baseboard_fab2_lib.baseboard_fab2(sch_1):page210_i31" )
			)
			( gate "R1C5"
				( objectStatus "@baseboard_fab2_lib.baseboard_fab2(sch_1):page210_i32" )
			)
			( gate "R1C4"
				( objectStatus "@baseboard_fab2_lib.baseboard_fab2(sch_1):page210_i33" )
			)
			( gate "R1C6"
				( objectStatus "@baseboard_fab2_lib.baseboard_fab2(sch_1):page210_i34" )
			)
			( gate "C9N13"
				( objectStatus "@baseboard_fab2_lib.baseboard_fab2(sch_1):page210_i35" )
			)
			( gate "C9N19"
				( objectStatus "@baseboard_fab2_lib.baseboard_fab2(sch_1):page210_i36" )
			)
			( gate "C9N21"
				( objectStatus "@baseboard_fab2_lib.baseboard_fab2(sch_1):page210_i38" )
			)
			( gate "C9N22"
				( objectStatus "@baseboard_fab2_lib.baseboard_fab2(sch_1):page210_i44" )
			)
			( gate "R9N4"
				( objectStatus "@baseboard_fab2_lib.baseboard_fab2(sch_1):page210_i45" )
			)
			( gate "EU1C1"
				( objectStatus "@baseboard_fab2_lib.baseboard_fab2(sch_1):page210_i51" )
			)
			( gate "R1C37"
				( objectStatus "@baseboard_fab2_lib.baseboard_fab2(sch_1):page210_i52" )
			)
			( gate "C3P4"
				( objectStatus "@baseboard_fab2_lib.baseboard_fab2(sch_1):page211_i11" )
			)
			( gate "C3P5"
				( objectStatus "@baseboard_fab2_lib.baseboard_fab2(sch_1):page211_i13" )
			)
			( gate "R3P11"
				( objectStatus "@baseboard_fab2_lib.baseboard_fab2(sch_1):page211_i16" )
			)
			( gate "R3P13"
				( objectStatus "@baseboard_fab2_lib.baseboard_fab2(sch_1):page211_i17" )
			)
			( gate "C3P3"
				( objectStatus "@baseboard_fab2_lib.baseboard_fab2(sch_1):page211_i20" )
			)
			( gate "C3P7"
				( objectStatus "@baseboard_fab2_lib.baseboard_fab2(sch_1):page211_i22" )
			)
			( gate "R3P22"
				( objectStatus "@baseboard_fab2_lib.baseboard_fab2(sch_1):page211_i24" )
			)
			( gate "R3P17"
				( objectStatus "@baseboard_fab2_lib.baseboard_fab2(sch_1):page211_i28" )
			)
			( gate "R3P15"
				( objectStatus "@baseboard_fab2_lib.baseboard_fab2(sch_1):page211_i29" )
			)
			( gate "R3P12"
				( objectStatus "@baseboard_fab2_lib.baseboard_fab2(sch_1):page211_i31" )
			)
			( gate "R3P16"
				( objectStatus "@baseboard_fab2_lib.baseboard_fab2(sch_1):page211_i32" )
			)
			( gate "C3P2"
				( objectStatus "@baseboard_fab2_lib.baseboard_fab2(sch_1):page211_i33" )
			)
			( gate "R3P24"
				( objectStatus "@baseboard_fab2_lib.baseboard_fab2(sch_1):page211_i46" )
			)
			( gate "R3P23"
				( objectStatus "@baseboard_fab2_lib.baseboard_fab2(sch_1):page211_i47" )
			)
			( gate "R3N31"
				( objectStatus "@baseboard_fab2_lib.baseboard_fab2(sch_1):page211_i52" )
			)
			( gate "R3P25"
				( objectStatus "@baseboard_fab2_lib.baseboard_fab2(sch_1):page211_i56" )
			)
			( gate "R3P20"
				( objectStatus "@baseboard_fab2_lib.baseboard_fab2(sch_1):page211_i58" )
			)
			( gate "R3N23"
				( objectStatus "@baseboard_fab2_lib.baseboard_fab2(sch_1):page211_i60" )
			)
			( gate "R3P1"
				( objectStatus "@baseboard_fab2_lib.baseboard_fab2(sch_1):page211_i61" )
			)
			( gate "R3P18"
				( objectStatus "@baseboard_fab2_lib.baseboard_fab2(sch_1):page211_i64" )
			)
			( gate "R3N22"
				( objectStatus "@baseboard_fab2_lib.baseboard_fab2(sch_1):page211_i65" )
			)
			( gate "C3P6"
				( objectStatus "@baseboard_fab2_lib.baseboard_fab2(sch_1):page211_i71" )
			)
			( gate "R3N19"
				( objectStatus "@baseboard_fab2_lib.baseboard_fab2(sch_1):page211_i81" )
			)
			( gate "C3N39"
				( objectStatus "@baseboard_fab2_lib.baseboard_fab2(sch_1):page211_i83" )
			)
			( gate "R3P26"
				( objectStatus "@baseboard_fab2_lib.baseboard_fab2(sch_1):page211_i87" )
			)
			( gate "R3P21"
				( objectStatus "@baseboard_fab2_lib.baseboard_fab2(sch_1):page211_i88" )
			)
			( gate "R3P57"
				( objectStatus "@baseboard_fab2_lib.baseboard_fab2(sch_1):page211_i91" )
			)
			( gate "EU3P1"
				( objectStatus "@baseboard_fab2_lib.baseboard_fab2(sch_1):page211_i93" )
			)
			( gate "C3N38"
				( objectStatus "@baseboard_fab2_lib.baseboard_fab2(sch_1):page212_i16" )
			)
			( gate "C3N26"
				( objectStatus "@baseboard_fab2_lib.baseboard_fab2(sch_1):page212_i17" )
			)
			( gate "C3N35"
				( objectStatus "@baseboard_fab2_lib.baseboard_fab2(sch_1):page212_i18" )
			)
			( gate "C7C6"
				( objectStatus "@baseboard_fab2_lib.baseboard_fab2(sch_1):page212_i23" )
			)
			( gate "L7C2"
				( objectStatus "@baseboard_fab2_lib.baseboard_fab2(sch_1):page212_i25" )
			)
			( gate "R3N7"
				( objectStatus "@baseboard_fab2_lib.baseboard_fab2(sch_1):page212_i32" )
			)
			( gate "C7C18"
				( objectStatus "@baseboard_fab2_lib.baseboard_fab2(sch_1):page212_i33" )
			)
			( gate "C7C20"
				( objectStatus "@baseboard_fab2_lib.baseboard_fab2(sch_1):page212_i34" )
			)
			( gate "C7C17"
				( objectStatus "@baseboard_fab2_lib.baseboard_fab2(sch_1):page212_i36" )
			)
			( gate "C7C14"
				( objectStatus "@baseboard_fab2_lib.baseboard_fab2(sch_1):page212_i37" )
			)
			( gate "C7C11"
				( objectStatus "@baseboard_fab2_lib.baseboard_fab2(sch_1):page212_i38" )
			)
			( gate "C7C12"
				( objectStatus "@baseboard_fab2_lib.baseboard_fab2(sch_1):page212_i39" )
			)
			( gate "C3N36"
				( objectStatus "@baseboard_fab2_lib.baseboard_fab2(sch_1):page212_i40" )
			)
			( gate "C3N33"
				( objectStatus "@baseboard_fab2_lib.baseboard_fab2(sch_1):page212_i41" )
			)
			( gate "C3N34"
				( objectStatus "@baseboard_fab2_lib.baseboard_fab2(sch_1):page212_i43" )
			)
			( gate "C7C8"
				( objectStatus "@baseboard_fab2_lib.baseboard_fab2(sch_1):page212_i51" )
			)
			( gate "C7C7"
				( objectStatus "@baseboard_fab2_lib.baseboard_fab2(sch_1):page212_i54" )
			)
			( gate "L7C1"
				( objectStatus "@baseboard_fab2_lib.baseboard_fab2(sch_1):page212_i56" )
			)
			( gate "C3P1"
				( objectStatus "@baseboard_fab2_lib.baseboard_fab2(sch_1):page212_i60" )
			)
			( gate "R3N20"
				( objectStatus "@baseboard_fab2_lib.baseboard_fab2(sch_1):page212_i68" )
			)
			( gate "R3N21"
				( objectStatus "@baseboard_fab2_lib.baseboard_fab2(sch_1):page212_i74" )
			)
			( gate "C7C10"
				( objectStatus "@baseboard_fab2_lib.baseboard_fab2(sch_1):page212_i77" )
			)
			( gate "R7C3"
				( objectStatus "@baseboard_fab2_lib.baseboard_fab2(sch_1):page212_i78" )
			)
			( gate "EU7C1"
				( objectStatus "@baseboard_fab2_lib.baseboard_fab2(sch_1):page212_i101" )
			)
			( gate "R7C25"
				( objectStatus "@baseboard_fab2_lib.baseboard_fab2(sch_1):page212_i103" )
			)
			( gate "SH3P1"
				( objectStatus "@baseboard_fab2_lib.baseboard_fab2(sch_1):page212_i104" )
			)
			( gate "SH3P2"
				( objectStatus "@baseboard_fab2_lib.baseboard_fab2(sch_1):page212_i105" )
			)
			( gate "C4D31"
				( objectStatus "@baseboard_fab2_lib.baseboard_fab2(sch_1):page213_i9" )
			)
			( gate "C4D32"
				( objectStatus "@baseboard_fab2_lib.baseboard_fab2(sch_1):page213_i11" )
			)
			( gate "R4D46"
				( objectStatus "@baseboard_fab2_lib.baseboard_fab2(sch_1):page213_i13" )
			)
			( gate "R6P49"
				( objectStatus "@baseboard_fab2_lib.baseboard_fab2(sch_1):page213_i14" )
			)
			( gate "R4D42"
				( objectStatus "@baseboard_fab2_lib.baseboard_fab2(sch_1):page213_i15" )
			)
			( gate "R4D56"
				( objectStatus "@baseboard_fab2_lib.baseboard_fab2(sch_1):page213_i16" )
			)
			( gate "C4D36"
				( objectStatus "@baseboard_fab2_lib.baseboard_fab2(sch_1):page213_i17" )
			)
			( gate "R4D47"
				( objectStatus "@baseboard_fab2_lib.baseboard_fab2(sch_1):page213_i25" )
			)
			( gate "R6P35"
				( objectStatus "@baseboard_fab2_lib.baseboard_fab2(sch_1):page213_i27" )
			)
			( gate "R6P33"
				( objectStatus "@baseboard_fab2_lib.baseboard_fab2(sch_1):page213_i30" )
			)
			( gate "R4D60"
				( objectStatus "@baseboard_fab2_lib.baseboard_fab2(sch_1):page213_i31" )
			)
			( gate "R4D57"
				( objectStatus "@baseboard_fab2_lib.baseboard_fab2(sch_1):page213_i32" )
			)
			( gate "C4D40"
				( objectStatus "@baseboard_fab2_lib.baseboard_fab2(sch_1):page213_i33" )
			)
			( gate "C4D38"
				( objectStatus "@baseboard_fab2_lib.baseboard_fab2(sch_1):page213_i35" )
			)
			( gate "R4D54"
				( objectStatus "@baseboard_fab2_lib.baseboard_fab2(sch_1):page213_i37" )
			)
			( gate "R4D44"
				( objectStatus "@baseboard_fab2_lib.baseboard_fab2(sch_1):page213_i38" )
			)
			( gate "R4D43"
				( objectStatus "@baseboard_fab2_lib.baseboard_fab2(sch_1):page213_i39" )
			)
			( gate "R4D64"
				( objectStatus "@baseboard_fab2_lib.baseboard_fab2(sch_1):page213_i42" )
			)
			( gate "R4D51"
				( objectStatus "@baseboard_fab2_lib.baseboard_fab2(sch_1):page213_i46" )
			)
			( gate "R4D49"
				( objectStatus "@baseboard_fab2_lib.baseboard_fab2(sch_1):page213_i63" )
			)
			( gate "R4E2"
				( objectStatus "@baseboard_fab2_lib.baseboard_fab2(sch_1):page213_i65" )
			)
			( gate "C4D33"
				( objectStatus "@baseboard_fab2_lib.baseboard_fab2(sch_1):page213_i73" )
			)
			( gate "C4D44"
				( objectStatus "@baseboard_fab2_lib.baseboard_fab2(sch_1):page213_i83" )
			)
			( gate "R4E7"
				( objectStatus "@baseboard_fab2_lib.baseboard_fab2(sch_1):page213_i84" )
			)
			( gate "R6P41"
				( objectStatus "@baseboard_fab2_lib.baseboard_fab2(sch_1):page213_i90" )
			)
			( gate "R6P40"
				( objectStatus "@baseboard_fab2_lib.baseboard_fab2(sch_1):page213_i91" )
			)
			( gate "R4D45"
				( objectStatus "@baseboard_fab2_lib.baseboard_fab2(sch_1):page213_i94" )
			)
			( gate "EU4D5"
				( objectStatus "@baseboard_fab2_lib.baseboard_fab2(sch_1):page213_i96" )
			)
			( gate "C4E9"
				( objectStatus "@baseboard_fab2_lib.baseboard_fab2(sch_1):page214_i8" )
			)
			( gate "C4E7"
				( objectStatus "@baseboard_fab2_lib.baseboard_fab2(sch_1):page214_i20" )
			)
			( gate "C6R12"
				( objectStatus "@baseboard_fab2_lib.baseboard_fab2(sch_1):page214_i21" )
			)
			( gate "C6R5"
				( objectStatus "@baseboard_fab2_lib.baseboard_fab2(sch_1):page214_i24" )
			)
			( gate "C4E8"
				( objectStatus "@baseboard_fab2_lib.baseboard_fab2(sch_1):page214_i29" )
			)
			( gate "C4E14"
				( objectStatus "@baseboard_fab2_lib.baseboard_fab2(sch_1):page214_i31" )
			)
			( gate "C7R1"
				( objectStatus "@baseboard_fab2_lib.baseboard_fab2(sch_1):page214_i65" )
			)
			( gate "L4E2"
				( objectStatus "@baseboard_fab2_lib.baseboard_fab2(sch_1):page214_i67" )
			)
			( gate "R6R5"
				( objectStatus "@baseboard_fab2_lib.baseboard_fab2(sch_1):page214_i71" )
			)
			( gate "C4E23"
				( objectStatus "@baseboard_fab2_lib.baseboard_fab2(sch_1):page214_i73" )
			)
			( gate "C4E28"
				( objectStatus "@baseboard_fab2_lib.baseboard_fab2(sch_1):page214_i74" )
			)
			( gate "C4E22"
				( objectStatus "@baseboard_fab2_lib.baseboard_fab2(sch_1):page214_i76" )
			)
			( gate "C4E13"
				( objectStatus "@baseboard_fab2_lib.baseboard_fab2(sch_1):page214_i77" )
			)
			( gate "C4E18"
				( objectStatus "@baseboard_fab2_lib.baseboard_fab2(sch_1):page214_i78" )
			)
			( gate "C4E15"
				( objectStatus "@baseboard_fab2_lib.baseboard_fab2(sch_1):page214_i79" )
			)
			( gate "C6R14"
				( objectStatus "@baseboard_fab2_lib.baseboard_fab2(sch_1):page214_i80" )
			)
			( gate "C6R10"
				( objectStatus "@baseboard_fab2_lib.baseboard_fab2(sch_1):page214_i81" )
			)
			( gate "C6R8"
				( objectStatus "@baseboard_fab2_lib.baseboard_fab2(sch_1):page214_i83" )
			)
			( gate "C3D27"
				( objectStatus "@baseboard_fab2_lib.baseboard_fab2(sch_1):page214_i96" )
			)
			( gate "R3D28"
				( objectStatus "@baseboard_fab2_lib.baseboard_fab2(sch_1):page214_i101" )
			)
			( gate "R3E1"
				( objectStatus "@baseboard_fab2_lib.baseboard_fab2(sch_1):page214_i105" )
			)
			( gate "C3E1"
				( objectStatus "@baseboard_fab2_lib.baseboard_fab2(sch_1):page214_i108" )
			)
			( gate "R7R1"
				( objectStatus "@baseboard_fab2_lib.baseboard_fab2(sch_1):page214_i109" )
			)
			( gate "EU4E2"
				( objectStatus "@baseboard_fab2_lib.baseboard_fab2(sch_1):page214_i126" )
			)
			( gate "R4E21"
				( objectStatus "@baseboard_fab2_lib.baseboard_fab2(sch_1):page214_i127" )
			)
			( gate "SH3D2"
				( objectStatus "@baseboard_fab2_lib.baseboard_fab2(sch_1):page214_i129" )
			)
			( gate "SH3D1"
				( objectStatus "@baseboard_fab2_lib.baseboard_fab2(sch_1):page214_i130" )
			)
			( gate "R3U2"
				( objectStatus "@baseboard_fab2_lib.baseboard_fab2(sch_1):page215_i295" )
			)
			( gate "R7F24"
				( objectStatus "@baseboard_fab2_lib.baseboard_fab2(sch_1):page215_i296" )
			)
			( gate "R7F23"
				( objectStatus "@baseboard_fab2_lib.baseboard_fab2(sch_1):page215_i297" )
			)
			( gate "R7F25"
				( objectStatus "@baseboard_fab2_lib.baseboard_fab2(sch_1):page215_i298" )
			)
			( gate "R7F36"
				( objectStatus "@baseboard_fab2_lib.baseboard_fab2(sch_1):page215_i300" )
			)
			( gate "R7F22"
				( objectStatus "@baseboard_fab2_lib.baseboard_fab2(sch_1):page215_i301" )
			)
			( gate "R7G4"
				( objectStatus "@baseboard_fab2_lib.baseboard_fab2(sch_1):page215_i302" )
			)
			( gate "R7F27"
				( objectStatus "@baseboard_fab2_lib.baseboard_fab2(sch_1):page215_i303" )
			)
			( gate "R7F26"
				( objectStatus "@baseboard_fab2_lib.baseboard_fab2(sch_1):page215_i304" )
			)
			( gate "C7F14"
				( objectStatus "@baseboard_fab2_lib.baseboard_fab2(sch_1):page215_i305" )
			)
			( gate "R7G2"
				( objectStatus "@baseboard_fab2_lib.baseboard_fab2(sch_1):page215_i307" )
			)
			( gate "C7F18"
				( objectStatus "@baseboard_fab2_lib.baseboard_fab2(sch_1):page215_i309" )
			)
			( gate "C7F17"
				( objectStatus "@baseboard_fab2_lib.baseboard_fab2(sch_1):page215_i311" )
			)
			( gate "R3T13"
				( objectStatus "@baseboard_fab2_lib.baseboard_fab2(sch_1):page215_i313" )
			)
			( gate "R7F20"
				( objectStatus "@baseboard_fab2_lib.baseboard_fab2(sch_1):page215_i315" )
			)
			( gate "R7G10"
				( objectStatus "@baseboard_fab2_lib.baseboard_fab2(sch_1):page215_i317" )
			)
			( gate "C7G3"
				( objectStatus "@baseboard_fab2_lib.baseboard_fab2(sch_1):page215_i320" )
			)
			( gate "R7G8"
				( objectStatus "@baseboard_fab2_lib.baseboard_fab2(sch_1):page215_i321" )
			)
			( gate "C7F16"
				( objectStatus "@baseboard_fab2_lib.baseboard_fab2(sch_1):page215_i325" )
			)
			( gate "C7F15"
				( objectStatus "@baseboard_fab2_lib.baseboard_fab2(sch_1):page215_i327" )
			)
			( gate "R3T11"
				( objectStatus "@baseboard_fab2_lib.baseboard_fab2(sch_1):page215_i330" )
			)
			( gate "R7G24"
				( objectStatus "@baseboard_fab2_lib.baseboard_fab2(sch_1):page215_i331" )
			)
			( gate "R3U3"
				( objectStatus "@baseboard_fab2_lib.baseboard_fab2(sch_1):page215_i332" )
			)
			( gate "R7F34"
				( objectStatus "@baseboard_fab2_lib.baseboard_fab2(sch_1):page215_i336" )
			)
			( gate "R7G3"
				( objectStatus "@baseboard_fab2_lib.baseboard_fab2(sch_1):page215_i337" )
			)
			( gate "C7G1"
				( objectStatus "@baseboard_fab2_lib.baseboard_fab2(sch_1):page215_i339" )
			)
			( gate "R3U10"
				( objectStatus "@baseboard_fab2_lib.baseboard_fab2(sch_1):page215_i341" )
			)
			( gate "C7G4"
				( objectStatus "@baseboard_fab2_lib.baseboard_fab2(sch_1):page215_i342" )
			)
			( gate "R7F21"
				( objectStatus "@baseboard_fab2_lib.baseboard_fab2(sch_1):page215_i343" )
			)
			( gate "R7G9"
				( objectStatus "@baseboard_fab2_lib.baseboard_fab2(sch_1):page215_i344" )
			)
			( gate "EU7G1"
				( objectStatus "@baseboard_fab2_lib.baseboard_fab2(sch_1):page215_i358" )
			)
			( gate "C3U10"
				( objectStatus "@baseboard_fab2_lib.baseboard_fab2(sch_1):page215_i360" )
			)
			( gate "C6G3"
				( objectStatus "@baseboard_fab2_lib.baseboard_fab2(sch_1):page216_i6" )
			)
			( gate "C7G31"
				( objectStatus "@baseboard_fab2_lib.baseboard_fab2(sch_1):page216_i44" )
			)
			( gate "C3U2"
				( objectStatus "@baseboard_fab2_lib.baseboard_fab2(sch_1):page216_i45" )
			)
			( gate "C3U3"
				( objectStatus "@baseboard_fab2_lib.baseboard_fab2(sch_1):page216_i46" )
			)
			( gate "C3U4"
				( objectStatus "@baseboard_fab2_lib.baseboard_fab2(sch_1):page216_i47" )
			)
			( gate "C7G37"
				( objectStatus "@baseboard_fab2_lib.baseboard_fab2(sch_1):page216_i48" )
			)
			( gate "C7G33"
				( objectStatus "@baseboard_fab2_lib.baseboard_fab2(sch_1):page216_i50" )
			)
			( gate "C7G29"
				( objectStatus "@baseboard_fab2_lib.baseboard_fab2(sch_1):page216_i51" )
			)
			( gate "R3U6"
				( objectStatus "@baseboard_fab2_lib.baseboard_fab2(sch_1):page216_i52" )
			)
			( gate "C7G35"
				( objectStatus "@baseboard_fab2_lib.baseboard_fab2(sch_1):page216_i53" )
			)
			( gate "C7G34"
				( objectStatus "@baseboard_fab2_lib.baseboard_fab2(sch_1):page216_i54" )
			)
			( gate "CT57"
				( objectStatus "@baseboard_fab2_lib.baseboard_fab2(sch_1):page210_i55" )
			)
			( gate "L7G2"
				( objectStatus "@baseboard_fab2_lib.baseboard_fab2(sch_1):page216_i65" )
			)
			( gate "C7G27"
				( objectStatus "@baseboard_fab2_lib.baseboard_fab2(sch_1):page216_i68" )
			)
			( gate "C7G41"
				( objectStatus "@baseboard_fab2_lib.baseboard_fab2(sch_1):page216_i72" )
			)
			( gate "C7G42"
				( objectStatus "@baseboard_fab2_lib.baseboard_fab2(sch_1):page216_i73" )
			)
			( gate "RT46"
				( objectStatus "@baseboard_fab2_lib.baseboard_fab2(sch_1):page236_i142" )
			)
			( gate "R3U9"
				( objectStatus "@baseboard_fab2_lib.baseboard_fab2(sch_1):page216_i76" )
			)
			( gate "C7G40"
				( objectStatus "@baseboard_fab2_lib.baseboard_fab2(sch_1):page216_i77" )
			)
			( gate "C7G36"
				( objectStatus "@baseboard_fab2_lib.baseboard_fab2(sch_1):page216_i78" )
			)
			( gate "C7G30"
				( objectStatus "@baseboard_fab2_lib.baseboard_fab2(sch_1):page216_i79" )
			)
			( gate "C3U9"
				( objectStatus "@baseboard_fab2_lib.baseboard_fab2(sch_1):page216_i80" )
			)
			( gate "C3U7"
				( objectStatus "@baseboard_fab2_lib.baseboard_fab2(sch_1):page216_i81" )
			)
			( gate "C3U6"
				( objectStatus "@baseboard_fab2_lib.baseboard_fab2(sch_1):page216_i84" )
			)
			( gate "EU7G2"
				( objectStatus "@baseboard_fab2_lib.baseboard_fab2(sch_1):page216_i102" )
			)
			( gate "EU7G3"
				( objectStatus "@baseboard_fab2_lib.baseboard_fab2(sch_1):page216_i103" )
			)
			( gate "R7G25"
				( objectStatus "@baseboard_fab2_lib.baseboard_fab2(sch_1):page216_i104" )
			)
			( gate "R7G30"
				( objectStatus "@baseboard_fab2_lib.baseboard_fab2(sch_1):page216_i106" )
			)
			( gate "R3U4"
				( objectStatus "@baseboard_fab2_lib.baseboard_fab2(sch_1):page217_i58" )
			)
			( gate "R4U6"
				( objectStatus "@baseboard_fab2_lib.baseboard_fab2(sch_1):page217_i74" )
			)
			( gate "C7G28"
				( objectStatus "@baseboard_fab2_lib.baseboard_fab2(sch_1):page217_i75" )
			)
			( gate "C3U1"
				( objectStatus "@baseboard_fab2_lib.baseboard_fab2(sch_1):page217_i76" )
			)
			( gate "C3U5"
				( objectStatus "@baseboard_fab2_lib.baseboard_fab2(sch_1):page217_i77" )
			)
			( gate "C3U8"
				( objectStatus "@baseboard_fab2_lib.baseboard_fab2(sch_1):page217_i78" )
			)
			( gate "C5U13"
				( objectStatus "@baseboard_fab2_lib.baseboard_fab2(sch_1):page217_i82" )
			)
			( gate "C5U10"
				( objectStatus "@baseboard_fab2_lib.baseboard_fab2(sch_1):page217_i83" )
			)
			( gate "C5U1"
				( objectStatus "@baseboard_fab2_lib.baseboard_fab2(sch_1):page217_i88" )
			)
			( gate "C5U14"
				( objectStatus "@baseboard_fab2_lib.baseboard_fab2(sch_1):page217_i89" )
			)
			( gate "C5U15"
				( objectStatus "@baseboard_fab2_lib.baseboard_fab2(sch_1):page217_i90" )
			)
			( gate "C4T4"
				( objectStatus "@baseboard_fab2_lib.baseboard_fab2(sch_1):page217_i91" )
			)
			( gate "C5G9"
				( objectStatus "@baseboard_fab2_lib.baseboard_fab2(sch_1):page217_i92" )
			)
			( gate "C5G20"
				( objectStatus "@baseboard_fab2_lib.baseboard_fab2(sch_1):page217_i110" )
			)
			( gate "L7F2"
				( objectStatus "@baseboard_fab2_lib.baseboard_fab2(sch_1):page217_i124" )
			)
			( gate "C7G2"
				( objectStatus "@baseboard_fab2_lib.baseboard_fab2(sch_1):page217_i175" )
			)
			( gate "C5P39"
				( objectStatus "@baseboard_fab2_lib.baseboard_fab2(sch_1):page217_i184" )
			)
			( gate "C5D57"
				( objectStatus "@baseboard_fab2_lib.baseboard_fab2(sch_1):page217_i186" )
			)
			( gate "C5D56"
				( objectStatus "@baseboard_fab2_lib.baseboard_fab2(sch_1):page217_i188" )
			)
			( gate "C5D55"
				( objectStatus "@baseboard_fab2_lib.baseboard_fab2(sch_1):page217_i189" )
			)
			( gate "C5D54"
				( objectStatus "@baseboard_fab2_lib.baseboard_fab2(sch_1):page217_i190" )
			)
			( gate "C5P38"
				( objectStatus "@baseboard_fab2_lib.baseboard_fab2(sch_1):page217_i193" )
			)
			( gate "C5F2"
				( objectStatus "@baseboard_fab2_lib.baseboard_fab2(sch_1):page217_i205" )
			)
			( gate "C5F1"
				( objectStatus "@baseboard_fab2_lib.baseboard_fab2(sch_1):page217_i206" )
			)
			( gate "C5G10"
				( objectStatus "@baseboard_fab2_lib.baseboard_fab2(sch_1):page217_i207" )
			)
			( gate "C5T2"
				( objectStatus "@baseboard_fab2_lib.baseboard_fab2(sch_1):page217_i208" )
			)
			( gate "C5U11"
				( objectStatus "@baseboard_fab2_lib.baseboard_fab2(sch_1):page217_i209" )
			)
			( gate "C5T13"
				( objectStatus "@baseboard_fab2_lib.baseboard_fab2(sch_1):page217_i210" )
			)
			( gate "C5T4"
				( objectStatus "@baseboard_fab2_lib.baseboard_fab2(sch_1):page217_i211" )
			)
			( gate "C5T1"
				( objectStatus "@baseboard_fab2_lib.baseboard_fab2(sch_1):page217_i212" )
			)
			( gate "C5G19"
				( objectStatus "@baseboard_fab2_lib.baseboard_fab2(sch_1):page217_i213" )
			)
			( gate "C5T5"
				( objectStatus "@baseboard_fab2_lib.baseboard_fab2(sch_1):page217_i216" )
			)
			( gate "C5G3"
				( objectStatus "@baseboard_fab2_lib.baseboard_fab2(sch_1):page217_i217" )
			)
			( gate "C5T6"
				( objectStatus "@baseboard_fab2_lib.baseboard_fab2(sch_1):page217_i218" )
			)
			( gate "C5T7"
				( objectStatus "@baseboard_fab2_lib.baseboard_fab2(sch_1):page217_i219" )
			)
			( gate "C5G15"
				( objectStatus "@baseboard_fab2_lib.baseboard_fab2(sch_1):page217_i220" )
			)
			( gate "C5G16"
				( objectStatus "@baseboard_fab2_lib.baseboard_fab2(sch_1):page217_i221" )
			)
			( gate "C5T8"
				( objectStatus "@baseboard_fab2_lib.baseboard_fab2(sch_1):page217_i222" )
			)
			( gate "C5G14"
				( objectStatus "@baseboard_fab2_lib.baseboard_fab2(sch_1):page217_i223" )
			)
			( gate "C5T9"
				( objectStatus "@baseboard_fab2_lib.baseboard_fab2(sch_1):page217_i224" )
			)
			( gate "C5T10"
				( objectStatus "@baseboard_fab2_lib.baseboard_fab2(sch_1):page217_i225" )
			)
			( gate "C5G17"
				( objectStatus "@baseboard_fab2_lib.baseboard_fab2(sch_1):page217_i226" )
			)
			( gate "C5G18"
				( objectStatus "@baseboard_fab2_lib.baseboard_fab2(sch_1):page217_i227" )
			)
			( gate "C5T11"
				( objectStatus "@baseboard_fab2_lib.baseboard_fab2(sch_1):page217_i228" )
			)
			( gate "C5T12"
				( objectStatus "@baseboard_fab2_lib.baseboard_fab2(sch_1):page217_i229" )
			)
			( gate "C5G8"
				( objectStatus "@baseboard_fab2_lib.baseboard_fab2(sch_1):page217_i230" )
			)
			( gate "C5G1"
				( objectStatus "@baseboard_fab2_lib.baseboard_fab2(sch_1):page217_i231" )
			)
			( gate "C5U9"
				( objectStatus "@baseboard_fab2_lib.baseboard_fab2(sch_1):page217_i232" )
			)
			( gate "C5U8"
				( objectStatus "@baseboard_fab2_lib.baseboard_fab2(sch_1):page217_i233" )
			)
			( gate "C5G7"
				( objectStatus "@baseboard_fab2_lib.baseboard_fab2(sch_1):page217_i234" )
			)
			( gate "C5G5"
				( objectStatus "@baseboard_fab2_lib.baseboard_fab2(sch_1):page217_i235" )
			)
			( gate "C5U7"
				( objectStatus "@baseboard_fab2_lib.baseboard_fab2(sch_1):page217_i236" )
			)
			( gate "C5G6"
				( objectStatus "@baseboard_fab2_lib.baseboard_fab2(sch_1):page217_i237" )
			)
			( gate "C5U6"
				( objectStatus "@baseboard_fab2_lib.baseboard_fab2(sch_1):page217_i238" )
			)
			( gate "C5U5"
				( objectStatus "@baseboard_fab2_lib.baseboard_fab2(sch_1):page217_i239" )
			)
			( gate "C5G13"
				( objectStatus "@baseboard_fab2_lib.baseboard_fab2(sch_1):page217_i240" )
			)
			( gate "C5G4"
				( objectStatus "@baseboard_fab2_lib.baseboard_fab2(sch_1):page217_i241" )
			)
			( gate "C5U4"
				( objectStatus "@baseboard_fab2_lib.baseboard_fab2(sch_1):page217_i243" )
			)
			( gate "C5U3"
				( objectStatus "@baseboard_fab2_lib.baseboard_fab2(sch_1):page217_i244" )
			)
			( gate "C5G2"
				( objectStatus "@baseboard_fab2_lib.baseboard_fab2(sch_1):page217_i245" )
			)
			( gate "C5G12"
				( objectStatus "@baseboard_fab2_lib.baseboard_fab2(sch_1):page217_i246" )
			)
			( gate "C5U2"
				( objectStatus "@baseboard_fab2_lib.baseboard_fab2(sch_1):page217_i247" )
			)
			( gate "C5G11"
				( objectStatus "@baseboard_fab2_lib.baseboard_fab2(sch_1):page217_i250" )
			)
			( gate "SH4U1"
				( objectStatus "@baseboard_fab2_lib.baseboard_fab2(sch_1):page217_i259" )
			)
			( gate "SH4U2"
				( objectStatus "@baseboard_fab2_lib.baseboard_fab2(sch_1):page217_i260" )
			)
			( gate "R3L11"
				( objectStatus "@baseboard_fab2_lib.baseboard_fab2(sch_1):page218_i7" )
			)
			( gate "R3M3"
				( objectStatus "@baseboard_fab2_lib.baseboard_fab2(sch_1):page218_i11" )
			)
			( gate "R7B1"
				( objectStatus "@baseboard_fab2_lib.baseboard_fab2(sch_1):page218_i12" )
			)
			( gate "R7A9"
				( objectStatus "@baseboard_fab2_lib.baseboard_fab2(sch_1):page218_i14" )
			)
			( gate "R7A11"
				( objectStatus "@baseboard_fab2_lib.baseboard_fab2(sch_1):page218_i15" )
			)
			( gate "R7B5"
				( objectStatus "@baseboard_fab2_lib.baseboard_fab2(sch_1):page218_i16" )
			)
			( gate "R7B4"
				( objectStatus "@baseboard_fab2_lib.baseboard_fab2(sch_1):page218_i17" )
			)
			( gate "R7B3"
				( objectStatus "@baseboard_fab2_lib.baseboard_fab2(sch_1):page218_i21" )
			)
			( gate "C7B1"
				( objectStatus "@baseboard_fab2_lib.baseboard_fab2(sch_1):page218_i22" )
			)
			( gate "C7B2"
				( objectStatus "@baseboard_fab2_lib.baseboard_fab2(sch_1):page218_i23" )
			)
			( gate "R7B2"
				( objectStatus "@baseboard_fab2_lib.baseboard_fab2(sch_1):page218_i24" )
			)
			( gate "R7A12"
				( objectStatus "@baseboard_fab2_lib.baseboard_fab2(sch_1):page218_i25" )
			)
			( gate "C7B3"
				( objectStatus "@baseboard_fab2_lib.baseboard_fab2(sch_1):page218_i26" )
			)
			( gate "C7A37"
				( objectStatus "@baseboard_fab2_lib.baseboard_fab2(sch_1):page218_i29" )
			)
			( gate "C7A38"
				( objectStatus "@baseboard_fab2_lib.baseboard_fab2(sch_1):page218_i31" )
			)
			( gate "R3M1"
				( objectStatus "@baseboard_fab2_lib.baseboard_fab2(sch_1):page218_i34" )
			)
			( gate "R3M5"
				( objectStatus "@baseboard_fab2_lib.baseboard_fab2(sch_1):page218_i35" )
			)
			( gate "R7A8"
				( objectStatus "@baseboard_fab2_lib.baseboard_fab2(sch_1):page218_i37" )
			)
			( gate "C7A29"
				( objectStatus "@baseboard_fab2_lib.baseboard_fab2(sch_1):page218_i39" )
			)
			( gate "R7A10"
				( objectStatus "@baseboard_fab2_lib.baseboard_fab2(sch_1):page218_i40" )
			)
			( gate "R3L13"
				( objectStatus "@baseboard_fab2_lib.baseboard_fab2(sch_1):page218_i47" )
			)
			( gate "R7A17"
				( objectStatus "@baseboard_fab2_lib.baseboard_fab2(sch_1):page218_i48" )
			)
			( gate "R3L10"
				( objectStatus "@baseboard_fab2_lib.baseboard_fab2(sch_1):page218_i50" )
			)
			( gate "R3L12"
				( objectStatus "@baseboard_fab2_lib.baseboard_fab2(sch_1):page218_i53" )
			)
			( gate "R7A16"
				( objectStatus "@baseboard_fab2_lib.baseboard_fab2(sch_1):page218_i54" )
			)
			( gate "C7A35"
				( objectStatus "@baseboard_fab2_lib.baseboard_fab2(sch_1):page218_i55" )
			)
			( gate "R3L9"
				( objectStatus "@baseboard_fab2_lib.baseboard_fab2(sch_1):page218_i57" )
			)
			( gate "R3M6"
				( objectStatus "@baseboard_fab2_lib.baseboard_fab2(sch_1):page218_i59" )
			)
			( gate "R7A7"
				( objectStatus "@baseboard_fab2_lib.baseboard_fab2(sch_1):page218_i60" )
			)
			( gate "C7A28"
				( objectStatus "@baseboard_fab2_lib.baseboard_fab2(sch_1):page218_i61" )
			)
			( gate "EU7A5"
				( objectStatus "@baseboard_fab2_lib.baseboard_fab2(sch_1):page218_i75" )
			)
			( gate "C3L31"
				( objectStatus "@baseboard_fab2_lib.baseboard_fab2(sch_1):page218_i77" )
			)
			( gate "C7A12"
				( objectStatus "@baseboard_fab2_lib.baseboard_fab2(sch_1):page219_i44" )
			)
			( gate "C3L2"
				( objectStatus "@baseboard_fab2_lib.baseboard_fab2(sch_1):page219_i45" )
			)
			( gate "C3L4"
				( objectStatus "@baseboard_fab2_lib.baseboard_fab2(sch_1):page219_i46" )
			)
			( gate "C3L13"
				( objectStatus "@baseboard_fab2_lib.baseboard_fab2(sch_1):page219_i47" )
			)
			( gate "C7A11"
				( objectStatus "@baseboard_fab2_lib.baseboard_fab2(sch_1):page219_i48" )
			)
			( gate "C7A16"
				( objectStatus "@baseboard_fab2_lib.baseboard_fab2(sch_1):page219_i50" )
			)
			( gate "C7A5"
				( objectStatus "@baseboard_fab2_lib.baseboard_fab2(sch_1):page219_i51" )
			)
			( gate "R3L6"
				( objectStatus "@baseboard_fab2_lib.baseboard_fab2(sch_1):page219_i52" )
			)
			( gate "C7A18"
				( objectStatus "@baseboard_fab2_lib.baseboard_fab2(sch_1):page219_i53" )
			)
			( gate "C7A17"
				( objectStatus "@baseboard_fab2_lib.baseboard_fab2(sch_1):page219_i54" )
			)
			( gate "L7A1"
				( objectStatus "@baseboard_fab2_lib.baseboard_fab2(sch_1):page219_i55" )
			)
			( gate "L7A3"
				( objectStatus "@baseboard_fab2_lib.baseboard_fab2(sch_1):page219_i65" )
			)
			( gate "C6A4"
				( objectStatus "@baseboard_fab2_lib.baseboard_fab2(sch_1):page219_i68" )
			)
			( gate "C7A25"
				( objectStatus "@baseboard_fab2_lib.baseboard_fab2(sch_1):page219_i72" )
			)
			( gate "C7A26"
				( objectStatus "@baseboard_fab2_lib.baseboard_fab2(sch_1):page219_i73" )
			)
			( gate "C7A22"
				( objectStatus "@baseboard_fab2_lib.baseboard_fab2(sch_1):page219_i75" )
			)
			( gate "R3L8"
				( objectStatus "@baseboard_fab2_lib.baseboard_fab2(sch_1):page219_i76" )
			)
			( gate "C7A24"
				( objectStatus "@baseboard_fab2_lib.baseboard_fab2(sch_1):page219_i77" )
			)
			( gate "C7A20"
				( objectStatus "@baseboard_fab2_lib.baseboard_fab2(sch_1):page219_i78" )
			)
			( gate "C7A21"
				( objectStatus "@baseboard_fab2_lib.baseboard_fab2(sch_1):page219_i79" )
			)
			( gate "C3L17"
				( objectStatus "@baseboard_fab2_lib.baseboard_fab2(sch_1):page219_i80" )
			)
			( gate "C3L16"
				( objectStatus "@baseboard_fab2_lib.baseboard_fab2(sch_1):page219_i81" )
			)
			( gate "C3L15"
				( objectStatus "@baseboard_fab2_lib.baseboard_fab2(sch_1):page219_i84" )
			)
			( gate "C6A1"
				( objectStatus "@baseboard_fab2_lib.baseboard_fab2(sch_1):page219_i87" )
			)
			( gate "EU7A1"
				( objectStatus "@baseboard_fab2_lib.baseboard_fab2(sch_1):page219_i106" )
			)
			( gate "EU7A4"
				( objectStatus "@baseboard_fab2_lib.baseboard_fab2(sch_1):page219_i107" )
			)
			( gate "R7A20"
				( objectStatus "@baseboard_fab2_lib.baseboard_fab2(sch_1):page219_i108" )
			)
			( gate "R7A21"
				( objectStatus "@baseboard_fab2_lib.baseboard_fab2(sch_1):page219_i110" )
			)
			( gate "R4L4"
				( objectStatus "@baseboard_fab2_lib.baseboard_fab2(sch_1):page220_i58" )
			)
			( gate "R4L2"
				( objectStatus "@baseboard_fab2_lib.baseboard_fab2(sch_1):page220_i74" )
			)
			( gate "C3L6"
				( objectStatus "@baseboard_fab2_lib.baseboard_fab2(sch_1):page220_i75" )
			)
			( gate "C3L14"
				( objectStatus "@baseboard_fab2_lib.baseboard_fab2(sch_1):page220_i76" )
			)
			( gate "C6A5"
				( objectStatus "@baseboard_fab2_lib.baseboard_fab2(sch_1):page220_i77" )
			)
			( gate "C4L5"
				( objectStatus "@baseboard_fab2_lib.baseboard_fab2(sch_1):page220_i78" )
			)
			( gate "C5M8"
				( objectStatus "@baseboard_fab2_lib.baseboard_fab2(sch_1):page220_i82" )
			)
			( gate "C5L14"
				( objectStatus "@baseboard_fab2_lib.baseboard_fab2(sch_1):page220_i83" )
			)
			( gate "C5M12"
				( objectStatus "@baseboard_fab2_lib.baseboard_fab2(sch_1):page220_i88" )
			)
			( gate "C5L3"
				( objectStatus "@baseboard_fab2_lib.baseboard_fab2(sch_1):page220_i89" )
			)
			( gate "C5L2"
				( objectStatus "@baseboard_fab2_lib.baseboard_fab2(sch_1):page220_i90" )
			)
			( gate "C5L1"
				( objectStatus "@baseboard_fab2_lib.baseboard_fab2(sch_1):page220_i91" )
			)
			( gate "C5A20"
				( objectStatus "@baseboard_fab2_lib.baseboard_fab2(sch_1):page220_i92" )
			)
			( gate "C5A10"
				( objectStatus "@baseboard_fab2_lib.baseboard_fab2(sch_1):page220_i110" )
			)
			( gate "L7A5"
				( objectStatus "@baseboard_fab2_lib.baseboard_fab2(sch_1):page220_i124" )
			)
			( gate "C7A19"
				( objectStatus "@baseboard_fab2_lib.baseboard_fab2(sch_1):page220_i175" )
			)
			( gate "C5P2"
				( objectStatus "@baseboard_fab2_lib.baseboard_fab2(sch_1):page220_i177" )
			)
			( gate "C5P1"
				( objectStatus "@baseboard_fab2_lib.baseboard_fab2(sch_1):page220_i179" )
			)
			( gate "C5D9"
				( objectStatus "@baseboard_fab2_lib.baseboard_fab2(sch_1):page220_i180" )
			)
			( gate "C5D6"
				( objectStatus "@baseboard_fab2_lib.baseboard_fab2(sch_1):page220_i182" )
			)
			( gate "C5D7"
				( objectStatus "@baseboard_fab2_lib.baseboard_fab2(sch_1):page220_i183" )
			)
			( gate "C5D8"
				( objectStatus "@baseboard_fab2_lib.baseboard_fab2(sch_1):page220_i184" )
			)
			( gate "C5L15"
				( objectStatus "@baseboard_fab2_lib.baseboard_fab2(sch_1):page220_i192" )
			)
			( gate "C5A5"
				( objectStatus "@baseboard_fab2_lib.baseboard_fab2(sch_1):page220_i193" )
			)
			( gate "C5B1"
				( objectStatus "@baseboard_fab2_lib.baseboard_fab2(sch_1):page220_i194" )
			)
			( gate "C5M9"
				( objectStatus "@baseboard_fab2_lib.baseboard_fab2(sch_1):page220_i195" )
			)
			( gate "C4M5"
				( objectStatus "@baseboard_fab2_lib.baseboard_fab2(sch_1):page220_i196" )
			)
			( gate "C5B2"
				( objectStatus "@baseboard_fab2_lib.baseboard_fab2(sch_1):page220_i197" )
			)
			( gate "C5M10"
				( objectStatus "@baseboard_fab2_lib.baseboard_fab2(sch_1):page220_i198" )
			)
			( gate "C5M3"
				( objectStatus "@baseboard_fab2_lib.baseboard_fab2(sch_1):page220_i199" )
			)
			( gate "C5M11"
				( objectStatus "@baseboard_fab2_lib.baseboard_fab2(sch_1):page220_i200" )
			)
			( gate "C5A19"
				( objectStatus "@baseboard_fab2_lib.baseboard_fab2(sch_1):page220_i203" )
			)
			( gate "C5A18"
				( objectStatus "@baseboard_fab2_lib.baseboard_fab2(sch_1):page220_i204" )
			)
			( gate "C5A17"
				( objectStatus "@baseboard_fab2_lib.baseboard_fab2(sch_1):page220_i205" )
			)
			( gate "C5A4"
				( objectStatus "@baseboard_fab2_lib.baseboard_fab2(sch_1):page220_i206" )
			)
			( gate "C5A16"
				( objectStatus "@baseboard_fab2_lib.baseboard_fab2(sch_1):page220_i207" )
			)
			( gate "C5A9"
				( objectStatus "@baseboard_fab2_lib.baseboard_fab2(sch_1):page220_i208" )
			)
			( gate "C5A8"
				( objectStatus "@baseboard_fab2_lib.baseboard_fab2(sch_1):page220_i209" )
			)
			( gate "C5A3"
				( objectStatus "@baseboard_fab2_lib.baseboard_fab2(sch_1):page220_i210" )
			)
			( gate "C5A7"
				( objectStatus "@baseboard_fab2_lib.baseboard_fab2(sch_1):page220_i211" )
			)
			( gate "C5A6"
				( objectStatus "@baseboard_fab2_lib.baseboard_fab2(sch_1):page220_i212" )
			)
			( gate "C5A14"
				( objectStatus "@baseboard_fab2_lib.baseboard_fab2(sch_1):page220_i213" )
			)
			( gate "C5A2"
				( objectStatus "@baseboard_fab2_lib.baseboard_fab2(sch_1):page220_i214" )
			)
			( gate "C5A13"
				( objectStatus "@baseboard_fab2_lib.baseboard_fab2(sch_1):page220_i215" )
			)
			( gate "C5A12"
				( objectStatus "@baseboard_fab2_lib.baseboard_fab2(sch_1):page220_i216" )
			)
			( gate "C5A15"
				( objectStatus "@baseboard_fab2_lib.baseboard_fab2(sch_1):page220_i217" )
			)
			( gate "C5A1"
				( objectStatus "@baseboard_fab2_lib.baseboard_fab2(sch_1):page220_i219" )
			)
			( gate "C5A11"
				( objectStatus "@baseboard_fab2_lib.baseboard_fab2(sch_1):page220_i221" )
			)
			( gate "C4M2"
				( objectStatus "@baseboard_fab2_lib.baseboard_fab2(sch_1):page220_i222" )
			)
			( gate "C5M1"
				( objectStatus "@baseboard_fab2_lib.baseboard_fab2(sch_1):page220_i223" )
			)
			( gate "C5M2"
				( objectStatus "@baseboard_fab2_lib.baseboard_fab2(sch_1):page220_i224" )
			)
			( gate "C5M4"
				( objectStatus "@baseboard_fab2_lib.baseboard_fab2(sch_1):page220_i225" )
			)
			( gate "C5M5"
				( objectStatus "@baseboard_fab2_lib.baseboard_fab2(sch_1):page220_i226" )
			)
			( gate "C5M6"
				( objectStatus "@baseboard_fab2_lib.baseboard_fab2(sch_1):page220_i227" )
			)
			( gate "C5M7"
				( objectStatus "@baseboard_fab2_lib.baseboard_fab2(sch_1):page220_i228" )
			)
			( gate "C5L13"
				( objectStatus "@baseboard_fab2_lib.baseboard_fab2(sch_1):page220_i229" )
			)
			( gate "C5L12"
				( objectStatus "@baseboard_fab2_lib.baseboard_fab2(sch_1):page220_i230" )
			)
			( gate "C5L11"
				( objectStatus "@baseboard_fab2_lib.baseboard_fab2(sch_1):page220_i231" )
			)
			( gate "C5L10"
				( objectStatus "@baseboard_fab2_lib.baseboard_fab2(sch_1):page220_i232" )
			)
			( gate "C5L9"
				( objectStatus "@baseboard_fab2_lib.baseboard_fab2(sch_1):page220_i233" )
			)
			( gate "C5L8"
				( objectStatus "@baseboard_fab2_lib.baseboard_fab2(sch_1):page220_i234" )
			)
			( gate "C5L7"
				( objectStatus "@baseboard_fab2_lib.baseboard_fab2(sch_1):page220_i236" )
			)
			( gate "C5L6"
				( objectStatus "@baseboard_fab2_lib.baseboard_fab2(sch_1):page220_i237" )
			)
			( gate "SH4L2"
				( objectStatus "@baseboard_fab2_lib.baseboard_fab2(sch_1):page220_i239" )
			)
			( gate "SH4L1"
				( objectStatus "@baseboard_fab2_lib.baseboard_fab2(sch_1):page220_i240" )
			)
			( gate "EU4G3"
				( objectStatus "@baseboard_fab2_lib.baseboard_fab2(sch_1):page221_i1" )
			)
			( gate "C4G14"
				( objectStatus "@baseboard_fab2_lib.baseboard_fab2(sch_1):page221_i15" )
			)
			( gate "C4G24"
				( objectStatus "@baseboard_fab2_lib.baseboard_fab2(sch_1):page221_i20" )
			)
			( gate "C6U16"
				( objectStatus "@baseboard_fab2_lib.baseboard_fab2(sch_1):page221_i22" )
			)
			( gate "C4G15"
				( objectStatus "@baseboard_fab2_lib.baseboard_fab2(sch_1):page221_i24" )
			)
			( gate "C6U15"
				( objectStatus "@baseboard_fab2_lib.baseboard_fab2(sch_1):page221_i26" )
			)
			( gate "R6U4"
				( objectStatus "@baseboard_fab2_lib.baseboard_fab2(sch_1):page221_i28" )
			)
			( gate "R6U5"
				( objectStatus "@baseboard_fab2_lib.baseboard_fab2(sch_1):page221_i32" )
			)
			( gate "C4G16"
				( objectStatus "@baseboard_fab2_lib.baseboard_fab2(sch_1):page221_i34" )
			)
			( gate "R6U15"
				( objectStatus "@baseboard_fab2_lib.baseboard_fab2(sch_1):page221_i37" )
			)
			( gate "R4G23"
				( objectStatus "@baseboard_fab2_lib.baseboard_fab2(sch_1):page221_i38" )
			)
			( gate "C4G23"
				( objectStatus "@baseboard_fab2_lib.baseboard_fab2(sch_1):page221_i39" )
			)
			( gate "R4G18"
				( objectStatus "@baseboard_fab2_lib.baseboard_fab2(sch_1):page221_i45" )
			)
			( gate "C6U12"
				( objectStatus "@baseboard_fab2_lib.baseboard_fab2(sch_1):page221_i49" )
			)
			( gate "C5U12"
				( objectStatus "@baseboard_fab2_lib.baseboard_fab2(sch_1):page221_i50" )
			)
			( gate "C5T3"
				( objectStatus "@baseboard_fab2_lib.baseboard_fab2(sch_1):page221_i51" )
			)
			( gate "C5U16"
				( objectStatus "@baseboard_fab2_lib.baseboard_fab2(sch_1):page221_i52" )
			)
			( gate "R4G19"
				( objectStatus "@baseboard_fab2_lib.baseboard_fab2(sch_1):page221_i54" )
			)
			( gate "R6U16"
				( objectStatus "@baseboard_fab2_lib.baseboard_fab2(sch_1):page221_i55" )
			)
			( gate "SH5U1"
				( objectStatus "@baseboard_fab2_lib.baseboard_fab2(sch_1):page221_i56" )
			)
			( gate "C4A12"
				( objectStatus "@baseboard_fab2_lib.baseboard_fab2(sch_1):page222_i12" )
			)
			( gate "C4A1"
				( objectStatus "@baseboard_fab2_lib.baseboard_fab2(sch_1):page222_i16" )
			)
			( gate "R6L9"
				( objectStatus "@baseboard_fab2_lib.baseboard_fab2(sch_1):page222_i19" )
			)
			( gate "C4A9"
				( objectStatus "@baseboard_fab2_lib.baseboard_fab2(sch_1):page222_i21" )
			)
			( gate "C6L3"
				( objectStatus "@baseboard_fab2_lib.baseboard_fab2(sch_1):page222_i24" )
			)
			( gate "C6L4"
				( objectStatus "@baseboard_fab2_lib.baseboard_fab2(sch_1):page222_i26" )
			)
			( gate "C4A10"
				( objectStatus "@baseboard_fab2_lib.baseboard_fab2(sch_1):page222_i28" )
			)
			( gate "R6L11"
				( objectStatus "@baseboard_fab2_lib.baseboard_fab2(sch_1):page222_i30" )
			)
			( gate "EU4A1"
				( objectStatus "@baseboard_fab2_lib.baseboard_fab2(sch_1):page222_i31" )
			)
			( gate "R6L10"
				( objectStatus "@baseboard_fab2_lib.baseboard_fab2(sch_1):page222_i34" )
			)
			( gate "R6L4"
				( objectStatus "@baseboard_fab2_lib.baseboard_fab2(sch_1):page222_i37" )
			)
			( gate "R4A2"
				( objectStatus "@baseboard_fab2_lib.baseboard_fab2(sch_1):page222_i38" )
			)
			( gate "C4A2"
				( objectStatus "@baseboard_fab2_lib.baseboard_fab2(sch_1):page222_i40" )
			)
			( gate "C4A11"
				( objectStatus "@baseboard_fab2_lib.baseboard_fab2(sch_1):page222_i46" )
			)
			( gate "C5L4"
				( objectStatus "@baseboard_fab2_lib.baseboard_fab2(sch_1):page222_i47" )
			)
			( gate "C5M13"
				( objectStatus "@baseboard_fab2_lib.baseboard_fab2(sch_1):page222_i48" )
			)
			( gate "C5L5"
				( objectStatus "@baseboard_fab2_lib.baseboard_fab2(sch_1):page222_i49" )
			)
			( gate "R4A6"
				( objectStatus "@baseboard_fab2_lib.baseboard_fab2(sch_1):page222_i51" )
			)
			( gate "R4A1"
				( objectStatus "@baseboard_fab2_lib.baseboard_fab2(sch_1):page222_i52" )
			)
			( gate "SH5L1"
				( objectStatus "@baseboard_fab2_lib.baseboard_fab2(sch_1):page222_i53" )
			)
			( gate "R9U3"
				( objectStatus "@baseboard_fab2_lib.baseboard_fab2(sch_1):page223_i8" )
			)
			( gate "R1G6"
				( objectStatus "@baseboard_fab2_lib.baseboard_fab2(sch_1):page223_i13" )
			)
			( gate "R1G12"
				( objectStatus "@baseboard_fab2_lib.baseboard_fab2(sch_1):page223_i14" )
			)
			( gate "R1G9"
				( objectStatus "@baseboard_fab2_lib.baseboard_fab2(sch_1):page223_i16" )
			)
			( gate "R1G16"
				( objectStatus "@baseboard_fab2_lib.baseboard_fab2(sch_1):page223_i17" )
			)
			( gate "R1G19"
				( objectStatus "@baseboard_fab2_lib.baseboard_fab2(sch_1):page223_i21" )
			)
			( gate "R1G21"
				( objectStatus "@baseboard_fab2_lib.baseboard_fab2(sch_1):page223_i22" )
			)
			( gate "R1G10"
				( objectStatus "@baseboard_fab2_lib.baseboard_fab2(sch_1):page223_i23" )
			)
			( gate "C1G27"
				( objectStatus "@baseboard_fab2_lib.baseboard_fab2(sch_1):page223_i25" )
			)
			( gate "C1G25"
				( objectStatus "@baseboard_fab2_lib.baseboard_fab2(sch_1):page223_i27" )
			)
			( gate "R9U10"
				( objectStatus "@baseboard_fab2_lib.baseboard_fab2(sch_1):page223_i30" )
			)
			( gate "R1G5"
				( objectStatus "@baseboard_fab2_lib.baseboard_fab2(sch_1):page223_i32" )
			)
			( gate "C1G24"
				( objectStatus "@baseboard_fab2_lib.baseboard_fab2(sch_1):page223_i36" )
			)
			( gate "C1G16"
				( objectStatus "@baseboard_fab2_lib.baseboard_fab2(sch_1):page223_i39" )
			)
			( gate "C1G23"
				( objectStatus "@baseboard_fab2_lib.baseboard_fab2(sch_1):page223_i41" )
			)
			( gate "C1G22"
				( objectStatus "@baseboard_fab2_lib.baseboard_fab2(sch_1):page223_i44" )
			)
			( gate "R9U4"
				( objectStatus "@baseboard_fab2_lib.baseboard_fab2(sch_1):page223_i50" )
			)
			( gate "R1G7"
				( objectStatus "@baseboard_fab2_lib.baseboard_fab2(sch_1):page223_i53" )
			)
			( gate "R9U11"
				( objectStatus "@baseboard_fab2_lib.baseboard_fab2(sch_1):page223_i57" )
			)
			( gate "R1G24"
				( objectStatus "@baseboard_fab2_lib.baseboard_fab2(sch_1):page223_i58" )
			)
			( gate "C1G26"
				( objectStatus "@baseboard_fab2_lib.baseboard_fab2(sch_1):page223_i59" )
			)
			( gate "R1G23"
				( objectStatus "@baseboard_fab2_lib.baseboard_fab2(sch_1):page223_i77" )
			)
			( gate "R1G22"
				( objectStatus "@baseboard_fab2_lib.baseboard_fab2(sch_1):page223_i78" )
			)
			( gate "R1G11"
				( objectStatus "@baseboard_fab2_lib.baseboard_fab2(sch_1):page223_i79" )
			)
			( gate "C1G21"
				( objectStatus "@baseboard_fab2_lib.baseboard_fab2(sch_1):page223_i80" )
			)
			( gate "R1G8"
				( objectStatus "@baseboard_fab2_lib.baseboard_fab2(sch_1):page223_i82" )
			)
			( gate "R9U7"
				( objectStatus "@baseboard_fab2_lib.baseboard_fab2(sch_1):page223_i84" )
			)
			( gate "R9U8"
				( objectStatus "@baseboard_fab2_lib.baseboard_fab2(sch_1):page223_i85" )
			)
			( gate "R1G28"
				( objectStatus "@baseboard_fab2_lib.baseboard_fab2(sch_1):page223_i87" )
			)
			( gate "R1G27"
				( objectStatus "@baseboard_fab2_lib.baseboard_fab2(sch_1):page223_i88" )
			)
			( gate "EU1G2"
				( objectStatus "@baseboard_fab2_lib.baseboard_fab2(sch_1):page223_i90" )
			)
			( gate "C9U12"
				( objectStatus "@baseboard_fab2_lib.baseboard_fab2(sch_1):page223_i92" )
			)
			( gate "C1G17"
				( objectStatus "@baseboard_fab2_lib.baseboard_fab2(sch_1):page224_i6" )
			)
			( gate "C1G11"
				( objectStatus "@baseboard_fab2_lib.baseboard_fab2(sch_1):page224_i44" )
			)
			( gate "C9U6"
				( objectStatus "@baseboard_fab2_lib.baseboard_fab2(sch_1):page224_i45" )
			)
			( gate "C9U4"
				( objectStatus "@baseboard_fab2_lib.baseboard_fab2(sch_1):page224_i46" )
			)
			( gate "C9T4"
				( objectStatus "@baseboard_fab2_lib.baseboard_fab2(sch_1):page224_i47" )
			)
			( gate "C1F27"
				( objectStatus "@baseboard_fab2_lib.baseboard_fab2(sch_1):page224_i48" )
			)
			( gate "C1G6"
				( objectStatus "@baseboard_fab2_lib.baseboard_fab2(sch_1):page224_i50" )
			)
			( gate "C1G14"
				( objectStatus "@baseboard_fab2_lib.baseboard_fab2(sch_1):page224_i51" )
			)
			( gate "R9U1"
				( objectStatus "@baseboard_fab2_lib.baseboard_fab2(sch_1):page224_i52" )
			)
			( gate "C1G4"
				( objectStatus "@baseboard_fab2_lib.baseboard_fab2(sch_1):page224_i53" )
			)
			( gate "C1G5"
				( objectStatus "@baseboard_fab2_lib.baseboard_fab2(sch_1):page224_i54" )
			)
			( gate "L1G1"
				( objectStatus "@baseboard_fab2_lib.baseboard_fab2(sch_1):page224_i55" )
			)
			( gate "L1F2"
				( objectStatus "@baseboard_fab2_lib.baseboard_fab2(sch_1):page224_i65" )
			)
			( gate "C1G20"
				( objectStatus "@baseboard_fab2_lib.baseboard_fab2(sch_1):page224_i68" )
			)
			( gate "C1G29"
				( objectStatus "@baseboard_fab2_lib.baseboard_fab2(sch_1):page224_i72" )
			)
			( gate "C1F21"
				( objectStatus "@baseboard_fab2_lib.baseboard_fab2(sch_1):page224_i73" )
			)
			( gate "C1F26"
				( objectStatus "@baseboard_fab2_lib.baseboard_fab2(sch_1):page224_i75" )
			)
			( gate "R9U12"
				( objectStatus "@baseboard_fab2_lib.baseboard_fab2(sch_1):page224_i76" )
			)
			( gate "C1G28"
				( objectStatus "@baseboard_fab2_lib.baseboard_fab2(sch_1):page224_i77" )
			)
			( gate "C1F28"
				( objectStatus "@baseboard_fab2_lib.baseboard_fab2(sch_1):page224_i78" )
			)
			( gate "C1G13"
				( objectStatus "@baseboard_fab2_lib.baseboard_fab2(sch_1):page224_i79" )
			)
			( gate "C9U3"
				( objectStatus "@baseboard_fab2_lib.baseboard_fab2(sch_1):page224_i80" )
			)
			( gate "C9T6"
				( objectStatus "@baseboard_fab2_lib.baseboard_fab2(sch_1):page224_i81" )
			)
			( gate "C9T9"
				( objectStatus "@baseboard_fab2_lib.baseboard_fab2(sch_1):page224_i84" )
			)
			( gate "EU1G1"
				( objectStatus "@baseboard_fab2_lib.baseboard_fab2(sch_1):page224_i110" )
			)
			( gate "EU1F1"
				( objectStatus "@baseboard_fab2_lib.baseboard_fab2(sch_1):page224_i111" )
			)
			( gate "R1G26"
				( objectStatus "@baseboard_fab2_lib.baseboard_fab2(sch_1):page224_i112" )
			)
			( gate "R1G25"
				( objectStatus "@baseboard_fab2_lib.baseboard_fab2(sch_1):page224_i114" )
			)
			( gate "R1G20"
				( objectStatus "@baseboard_fab2_lib.baseboard_fab2(sch_1):page225_i58" )
			)
			( gate "R7U2"
				( objectStatus "@baseboard_fab2_lib.baseboard_fab2(sch_1):page225_i74" )
			)
			( gate "C9T5"
				( objectStatus "@baseboard_fab2_lib.baseboard_fab2(sch_1):page225_i75" )
			)
			( gate "C9U2"
				( objectStatus "@baseboard_fab2_lib.baseboard_fab2(sch_1):page225_i76" )
			)
			( gate "C9U9"
				( objectStatus "@baseboard_fab2_lib.baseboard_fab2(sch_1):page225_i77" )
			)
			( gate "C9U5"
				( objectStatus "@baseboard_fab2_lib.baseboard_fab2(sch_1):page225_i78" )
			)
			( gate "C8U1"
				( objectStatus "@baseboard_fab2_lib.baseboard_fab2(sch_1):page225_i82" )
			)
			( gate "C8U8"
				( objectStatus "@baseboard_fab2_lib.baseboard_fab2(sch_1):page225_i83" )
			)
			( gate "C8U12"
				( objectStatus "@baseboard_fab2_lib.baseboard_fab2(sch_1):page225_i88" )
			)
			( gate "C8U11"
				( objectStatus "@baseboard_fab2_lib.baseboard_fab2(sch_1):page225_i89" )
			)
			( gate "C7T1"
				( objectStatus "@baseboard_fab2_lib.baseboard_fab2(sch_1):page225_i90" )
			)
			( gate "C7U7"
				( objectStatus "@baseboard_fab2_lib.baseboard_fab2(sch_1):page225_i91" )
			)
			( gate "C2G7"
				( objectStatus "@baseboard_fab2_lib.baseboard_fab2(sch_1):page225_i92" )
			)
			( gate "C2G16"
				( objectStatus "@baseboard_fab2_lib.baseboard_fab2(sch_1):page225_i110" )
			)
			( gate "L1F1"
				( objectStatus "@baseboard_fab2_lib.baseboard_fab2(sch_1):page225_i124" )
			)
			( gate "C8P31"
				( objectStatus "@baseboard_fab2_lib.baseboard_fab2(sch_1):page225_i178" )
			)
			( gate "C2D43"
				( objectStatus "@baseboard_fab2_lib.baseboard_fab2(sch_1):page225_i179" )
			)
			( gate "C2D41"
				( objectStatus "@baseboard_fab2_lib.baseboard_fab2(sch_1):page225_i180" )
			)
			( gate "C2D44"
				( objectStatus "@baseboard_fab2_lib.baseboard_fab2(sch_1):page225_i181" )
			)
			( gate "C2D42"
				( objectStatus "@baseboard_fab2_lib.baseboard_fab2(sch_1):page225_i183" )
			)
			( gate "C8P30"
				( objectStatus "@baseboard_fab2_lib.baseboard_fab2(sch_1):page225_i184" )
			)
			( gate "C1G15"
				( objectStatus "@baseboard_fab2_lib.baseboard_fab2(sch_1):page225_i192" )
			)
			( gate "C1G12"
				( objectStatus "@baseboard_fab2_lib.baseboard_fab2(sch_1):page225_i193" )
			)
			( gate "C1G2"
				( objectStatus "@baseboard_fab2_lib.baseboard_fab2(sch_1):page225_i194" )
			)
			( gate "C1G7"
				( objectStatus "@baseboard_fab2_lib.baseboard_fab2(sch_1):page225_i195" )
			)
			( gate "C8T4"
				( objectStatus "@baseboard_fab2_lib.baseboard_fab2(sch_1):page225_i196" )
			)
			( gate "C2G8"
				( objectStatus "@baseboard_fab2_lib.baseboard_fab2(sch_1):page225_i197" )
			)
			( gate "C8T2"
				( objectStatus "@baseboard_fab2_lib.baseboard_fab2(sch_1):page225_i198" )
			)
			( gate "C8U13"
				( objectStatus "@baseboard_fab2_lib.baseboard_fab2(sch_1):page225_i199" )
			)
			( gate "C2G15"
				( objectStatus "@baseboard_fab2_lib.baseboard_fab2(sch_1):page225_i200" )
			)
			( gate "C2F1"
				( objectStatus "@baseboard_fab2_lib.baseboard_fab2(sch_1):page225_i201" )
			)
			( gate "C8T1"
				( objectStatus "@baseboard_fab2_lib.baseboard_fab2(sch_1):page225_i202" )
			)
			( gate "C8U9"
				( objectStatus "@baseboard_fab2_lib.baseboard_fab2(sch_1):page225_i203" )
			)
			( gate "C8T11"
				( objectStatus "@baseboard_fab2_lib.baseboard_fab2(sch_1):page225_i204" )
			)
			( gate "C3G6"
				( objectStatus "@baseboard_fab2_lib.baseboard_fab2(sch_1):page225_i207" )
			)
			( gate "C3G5"
				( objectStatus "@baseboard_fab2_lib.baseboard_fab2(sch_1):page225_i208" )
			)
			( gate "C2G14"
				( objectStatus "@baseboard_fab2_lib.baseboard_fab2(sch_1):page225_i209" )
			)
			( gate "C2G13"
				( objectStatus "@baseboard_fab2_lib.baseboard_fab2(sch_1):page225_i210" )
			)
			( gate "C3G2"
				( objectStatus "@baseboard_fab2_lib.baseboard_fab2(sch_1):page225_i211" )
			)
			( gate "C3G1"
				( objectStatus "@baseboard_fab2_lib.baseboard_fab2(sch_1):page225_i212" )
			)
			( gate "C2G6"
				( objectStatus "@baseboard_fab2_lib.baseboard_fab2(sch_1):page225_i213" )
			)
			( gate "C2G5"
				( objectStatus "@baseboard_fab2_lib.baseboard_fab2(sch_1):page225_i214" )
			)
			( gate "C2G4"
				( objectStatus "@baseboard_fab2_lib.baseboard_fab2(sch_1):page225_i215" )
			)
			( gate "C2G3"
				( objectStatus "@baseboard_fab2_lib.baseboard_fab2(sch_1):page225_i216" )
			)
			( gate "C2G2"
				( objectStatus "@baseboard_fab2_lib.baseboard_fab2(sch_1):page225_i217" )
			)
			( gate "C2G9"
				( objectStatus "@baseboard_fab2_lib.baseboard_fab2(sch_1):page225_i218" )
			)
			( gate "C2G1"
				( objectStatus "@baseboard_fab2_lib.baseboard_fab2(sch_1):page225_i219" )
			)
			( gate "C2G12"
				( objectStatus "@baseboard_fab2_lib.baseboard_fab2(sch_1):page225_i220" )
			)
			( gate "C2G11"
				( objectStatus "@baseboard_fab2_lib.baseboard_fab2(sch_1):page225_i221" )
			)
			( gate "C2G10"
				( objectStatus "@baseboard_fab2_lib.baseboard_fab2(sch_1):page225_i223" )
			)
			( gate "C8U4"
				( objectStatus "@baseboard_fab2_lib.baseboard_fab2(sch_1):page225_i225" )
			)
			( gate "C8T10"
				( objectStatus "@baseboard_fab2_lib.baseboard_fab2(sch_1):page225_i226" )
			)
			( gate "C8T9"
				( objectStatus "@baseboard_fab2_lib.baseboard_fab2(sch_1):page225_i227" )
			)
			( gate "C8U5"
				( objectStatus "@baseboard_fab2_lib.baseboard_fab2(sch_1):page225_i228" )
			)
			( gate "C8T8"
				( objectStatus "@baseboard_fab2_lib.baseboard_fab2(sch_1):page225_i229" )
			)
			( gate "C8T7"
				( objectStatus "@baseboard_fab2_lib.baseboard_fab2(sch_1):page225_i230" )
			)
			( gate "C8T6"
				( objectStatus "@baseboard_fab2_lib.baseboard_fab2(sch_1):page225_i231" )
			)
			( gate "C8U6"
				( objectStatus "@baseboard_fab2_lib.baseboard_fab2(sch_1):page225_i232" )
			)
			( gate "C8T5"
				( objectStatus "@baseboard_fab2_lib.baseboard_fab2(sch_1):page225_i233" )
			)
			( gate "C7T5"
				( objectStatus "@baseboard_fab2_lib.baseboard_fab2(sch_1):page225_i234" )
			)
			( gate "C7T4"
				( objectStatus "@baseboard_fab2_lib.baseboard_fab2(sch_1):page225_i235" )
			)
			( gate "C8U3"
				( objectStatus "@baseboard_fab2_lib.baseboard_fab2(sch_1):page225_i236" )
			)
			( gate "C7U1"
				( objectStatus "@baseboard_fab2_lib.baseboard_fab2(sch_1):page225_i237" )
			)
			( gate "C7U2"
				( objectStatus "@baseboard_fab2_lib.baseboard_fab2(sch_1):page225_i238" )
			)
			( gate "C8U2"
				( objectStatus "@baseboard_fab2_lib.baseboard_fab2(sch_1):page225_i239" )
			)
			( gate "C8U7"
				( objectStatus "@baseboard_fab2_lib.baseboard_fab2(sch_1):page225_i241" )
			)
			( gate "SH7U1"
				( objectStatus "@baseboard_fab2_lib.baseboard_fab2(sch_1):page225_i243" )
			)
			( gate "SH7U2"
				( objectStatus "@baseboard_fab2_lib.baseboard_fab2(sch_1):page225_i244" )
			)
			( gate "R9M7"
				( objectStatus "@baseboard_fab2_lib.baseboard_fab2(sch_1):page226_i8" )
			)
			( gate "R1B13"
				( objectStatus "@baseboard_fab2_lib.baseboard_fab2(sch_1):page226_i13" )
			)
			( gate "R1B5"
				( objectStatus "@baseboard_fab2_lib.baseboard_fab2(sch_1):page226_i14" )
			)
			( gate "R1B11"
				( objectStatus "@baseboard_fab2_lib.baseboard_fab2(sch_1):page226_i16" )
			)
			( gate "R1B2"
				( objectStatus "@baseboard_fab2_lib.baseboard_fab2(sch_1):page226_i17" )
			)
			( gate "R1B6"
				( objectStatus "@baseboard_fab2_lib.baseboard_fab2(sch_1):page226_i21" )
			)
			( gate "R1B7"
				( objectStatus "@baseboard_fab2_lib.baseboard_fab2(sch_1):page226_i22" )
			)
			( gate "R1B10"
				( objectStatus "@baseboard_fab2_lib.baseboard_fab2(sch_1):page226_i23" )
			)
			( gate "C1B6"
				( objectStatus "@baseboard_fab2_lib.baseboard_fab2(sch_1):page226_i25" )
			)
			( gate "C1B5"
				( objectStatus "@baseboard_fab2_lib.baseboard_fab2(sch_1):page226_i27" )
			)
			( gate "R9M3"
				( objectStatus "@baseboard_fab2_lib.baseboard_fab2(sch_1):page226_i30" )
			)
			( gate "R1B16"
				( objectStatus "@baseboard_fab2_lib.baseboard_fab2(sch_1):page226_i32" )
			)
			( gate "C1B11"
				( objectStatus "@baseboard_fab2_lib.baseboard_fab2(sch_1):page226_i36" )
			)
			( gate "C1B12"
				( objectStatus "@baseboard_fab2_lib.baseboard_fab2(sch_1):page226_i39" )
			)
			( gate "C1B3"
				( objectStatus "@baseboard_fab2_lib.baseboard_fab2(sch_1):page226_i41" )
			)
			( gate "C1B2"
				( objectStatus "@baseboard_fab2_lib.baseboard_fab2(sch_1):page226_i44" )
			)
			( gate "R9M6"
				( objectStatus "@baseboard_fab2_lib.baseboard_fab2(sch_1):page226_i50" )
			)
			( gate "R1B8"
				( objectStatus "@baseboard_fab2_lib.baseboard_fab2(sch_1):page226_i53" )
			)
			( gate "R9M8"
				( objectStatus "@baseboard_fab2_lib.baseboard_fab2(sch_1):page226_i57" )
			)
			( gate "R1B9"
				( objectStatus "@baseboard_fab2_lib.baseboard_fab2(sch_1):page226_i58" )
			)
			( gate "C1B8"
				( objectStatus "@baseboard_fab2_lib.baseboard_fab2(sch_1):page226_i59" )
			)
			( gate "R1B15"
				( objectStatus "@baseboard_fab2_lib.baseboard_fab2(sch_1):page226_i77" )
			)
			( gate "R1B12"
				( objectStatus "@baseboard_fab2_lib.baseboard_fab2(sch_1):page226_i78" )
			)
			( gate "R1B1"
				( objectStatus "@baseboard_fab2_lib.baseboard_fab2(sch_1):page226_i79" )
			)
			( gate "C1B4"
				( objectStatus "@baseboard_fab2_lib.baseboard_fab2(sch_1):page226_i80" )
			)
			( gate "R1B4"
				( objectStatus "@baseboard_fab2_lib.baseboard_fab2(sch_1):page226_i82" )
			)
			( gate "R9M9"
				( objectStatus "@baseboard_fab2_lib.baseboard_fab2(sch_1):page226_i84" )
			)
			( gate "R9M5"
				( objectStatus "@baseboard_fab2_lib.baseboard_fab2(sch_1):page226_i85" )
			)
			( gate "R9M11"
				( objectStatus "@baseboard_fab2_lib.baseboard_fab2(sch_1):page226_i87" )
			)
			( gate "R9M10"
				( objectStatus "@baseboard_fab2_lib.baseboard_fab2(sch_1):page226_i88" )
			)
			( gate "EU1B1"
				( objectStatus "@baseboard_fab2_lib.baseboard_fab2(sch_1):page226_i90" )
			)
			( gate "C9M11"
				( objectStatus "@baseboard_fab2_lib.baseboard_fab2(sch_1):page226_i92" )
			)
			( gate "C1A12"
				( objectStatus "@baseboard_fab2_lib.baseboard_fab2(sch_1):page227_i6" )
			)
			( gate "C1A18"
				( objectStatus "@baseboard_fab2_lib.baseboard_fab2(sch_1):page227_i44" )
			)
			( gate "C9L11"
				( objectStatus "@baseboard_fab2_lib.baseboard_fab2(sch_1):page227_i45" )
			)
			( gate "C9L10"
				( objectStatus "@baseboard_fab2_lib.baseboard_fab2(sch_1):page227_i46" )
			)
			( gate "C9L6"
				( objectStatus "@baseboard_fab2_lib.baseboard_fab2(sch_1):page227_i47" )
			)
			( gate "C1A19"
				( objectStatus "@baseboard_fab2_lib.baseboard_fab2(sch_1):page227_i48" )
			)
			( gate "C1B20"
				( objectStatus "@baseboard_fab2_lib.baseboard_fab2(sch_1):page227_i50" )
			)
			( gate "C1A10"
				( objectStatus "@baseboard_fab2_lib.baseboard_fab2(sch_1):page227_i51" )
			)
			( gate "R9L9"
				( objectStatus "@baseboard_fab2_lib.baseboard_fab2(sch_1):page227_i52" )
			)
			( gate "C1A2"
				( objectStatus "@baseboard_fab2_lib.baseboard_fab2(sch_1):page227_i53" )
			)
			( gate "C1B21"
				( objectStatus "@baseboard_fab2_lib.baseboard_fab2(sch_1):page227_i54" )
			)
			( gate "L1A2"
				( objectStatus "@baseboard_fab2_lib.baseboard_fab2(sch_1):page227_i55" )
			)
			( gate "L1A1"
				( objectStatus "@baseboard_fab2_lib.baseboard_fab2(sch_1):page227_i65" )
			)
			( gate "C1A1"
				( objectStatus "@baseboard_fab2_lib.baseboard_fab2(sch_1):page227_i68" )
			)
			( gate "C1A13"
				( objectStatus "@baseboard_fab2_lib.baseboard_fab2(sch_1):page227_i72" )
			)
			( gate "C1A11"
				( objectStatus "@baseboard_fab2_lib.baseboard_fab2(sch_1):page227_i73" )
			)
			( gate "C1A8"
				( objectStatus "@baseboard_fab2_lib.baseboard_fab2(sch_1):page227_i75" )
			)
			( gate "R9L4"
				( objectStatus "@baseboard_fab2_lib.baseboard_fab2(sch_1):page227_i76" )
			)
			( gate "C1A6"
				( objectStatus "@baseboard_fab2_lib.baseboard_fab2(sch_1):page227_i77" )
			)
			( gate "C1A20"
				( objectStatus "@baseboard_fab2_lib.baseboard_fab2(sch_1):page227_i78" )
			)
			( gate "C1A9"
				( objectStatus "@baseboard_fab2_lib.baseboard_fab2(sch_1):page227_i79" )
			)
			( gate "C9L5"
				( objectStatus "@baseboard_fab2_lib.baseboard_fab2(sch_1):page227_i80" )
			)
			( gate "C9L13"
				( objectStatus "@baseboard_fab2_lib.baseboard_fab2(sch_1):page227_i81" )
			)
			( gate "C9L14"
				( objectStatus "@baseboard_fab2_lib.baseboard_fab2(sch_1):page227_i84" )
			)
			( gate "EU1A2"
				( objectStatus "@baseboard_fab2_lib.baseboard_fab2(sch_1):page227_i101" )
			)
			( gate "EU1A1"
				( objectStatus "@baseboard_fab2_lib.baseboard_fab2(sch_1):page227_i102" )
			)
			( gate "R1A3"
				( objectStatus "@baseboard_fab2_lib.baseboard_fab2(sch_1):page227_i103" )
			)
			( gate "R1A2"
				( objectStatus "@baseboard_fab2_lib.baseboard_fab2(sch_1):page227_i105" )
			)
			( gate "R1A1"
				( objectStatus "@baseboard_fab2_lib.baseboard_fab2(sch_1):page228_i58" )
			)
			( gate "R7L2"
				( objectStatus "@baseboard_fab2_lib.baseboard_fab2(sch_1):page228_i74" )
			)
			( gate "C9L9"
				( objectStatus "@baseboard_fab2_lib.baseboard_fab2(sch_1):page228_i75" )
			)
			( gate "C9L12"
				( objectStatus "@baseboard_fab2_lib.baseboard_fab2(sch_1):page228_i76" )
			)
			( gate "C9L4"
				( objectStatus "@baseboard_fab2_lib.baseboard_fab2(sch_1):page228_i77" )
			)
			( gate "C9L2"
				( objectStatus "@baseboard_fab2_lib.baseboard_fab2(sch_1):page228_i78" )
			)
			( gate "C2A8"
				( objectStatus "@baseboard_fab2_lib.baseboard_fab2(sch_1):page228_i82" )
			)
			( gate "C8L2"
				( objectStatus "@baseboard_fab2_lib.baseboard_fab2(sch_1):page228_i83" )
			)
			( gate "C8L11"
				( objectStatus "@baseboard_fab2_lib.baseboard_fab2(sch_1):page228_i88" )
			)
			( gate "C2A16"
				( objectStatus "@baseboard_fab2_lib.baseboard_fab2(sch_1):page228_i89" )
			)
			( gate "C8M7"
				( objectStatus "@baseboard_fab2_lib.baseboard_fab2(sch_1):page228_i90" )
			)
			( gate "C8M11"
				( objectStatus "@baseboard_fab2_lib.baseboard_fab2(sch_1):page228_i91" )
			)
			( gate "C7L1"
				( objectStatus "@baseboard_fab2_lib.baseboard_fab2(sch_1):page228_i92" )
			)
			( gate "C8L1"
				( objectStatus "@baseboard_fab2_lib.baseboard_fab2(sch_1):page228_i110" )
			)
			( gate "L1B1"
				( objectStatus "@baseboard_fab2_lib.baseboard_fab2(sch_1):page228_i124" )
			)
			( gate "C1B10"
				( objectStatus "@baseboard_fab2_lib.baseboard_fab2(sch_1):page228_i175" )
			)
			( gate "C8P2"
				( objectStatus "@baseboard_fab2_lib.baseboard_fab2(sch_1):page228_i183" )
			)
			( gate "C8P1"
				( objectStatus "@baseboard_fab2_lib.baseboard_fab2(sch_1):page228_i185" )
			)
			( gate "C2D7"
				( objectStatus "@baseboard_fab2_lib.baseboard_fab2(sch_1):page228_i186" )
			)
			( gate "C2D4"
				( objectStatus "@baseboard_fab2_lib.baseboard_fab2(sch_1):page228_i187" )
			)
			( gate "C2D5"
				( objectStatus "@baseboard_fab2_lib.baseboard_fab2(sch_1):page228_i188" )
			)
			( gate "C2D6"
				( objectStatus "@baseboard_fab2_lib.baseboard_fab2(sch_1):page228_i190" )
			)
			( gate "C8M8"
				( objectStatus "@baseboard_fab2_lib.baseboard_fab2(sch_1):page228_i198" )
			)
			( gate "C2A5"
				( objectStatus "@baseboard_fab2_lib.baseboard_fab2(sch_1):page228_i199" )
			)
			( gate "C2B1"
				( objectStatus "@baseboard_fab2_lib.baseboard_fab2(sch_1):page228_i200" )
			)
			( gate "C8L12"
				( objectStatus "@baseboard_fab2_lib.baseboard_fab2(sch_1):page228_i201" )
			)
			( gate "C7M5"
				( objectStatus "@baseboard_fab2_lib.baseboard_fab2(sch_1):page228_i202" )
			)
			( gate "C8M10"
				( objectStatus "@baseboard_fab2_lib.baseboard_fab2(sch_1):page228_i203" )
			)
			( gate "C2B2"
				( objectStatus "@baseboard_fab2_lib.baseboard_fab2(sch_1):page228_i204" )
			)
			( gate "C8M9"
				( objectStatus "@baseboard_fab2_lib.baseboard_fab2(sch_1):page228_i205" )
			)
			( gate "C8M2"
				( objectStatus "@baseboard_fab2_lib.baseboard_fab2(sch_1):page228_i206" )
			)
			( gate "C2A2"
				( objectStatus "@baseboard_fab2_lib.baseboard_fab2(sch_1):page228_i209" )
			)
			( gate "C2A1"
				( objectStatus "@baseboard_fab2_lib.baseboard_fab2(sch_1):page228_i210" )
			)
			( gate "C2A12"
				( objectStatus "@baseboard_fab2_lib.baseboard_fab2(sch_1):page228_i211" )
			)
			( gate "C2A13"
				( objectStatus "@baseboard_fab2_lib.baseboard_fab2(sch_1):page228_i212" )
			)
			( gate "C2A11"
				( objectStatus "@baseboard_fab2_lib.baseboard_fab2(sch_1):page228_i213" )
			)
			( gate "C2A10"
				( objectStatus "@baseboard_fab2_lib.baseboard_fab2(sch_1):page228_i214" )
			)
			( gate "C2A9"
				( objectStatus "@baseboard_fab2_lib.baseboard_fab2(sch_1):page228_i215" )
			)
			( gate "C3A2"
				( objectStatus "@baseboard_fab2_lib.baseboard_fab2(sch_1):page228_i216" )
			)
			( gate "C3A1"
				( objectStatus "@baseboard_fab2_lib.baseboard_fab2(sch_1):page228_i217" )
			)
			( gate "C2A7"
				( objectStatus "@baseboard_fab2_lib.baseboard_fab2(sch_1):page228_i218" )
			)
			( gate "C2A6"
				( objectStatus "@baseboard_fab2_lib.baseboard_fab2(sch_1):page228_i219" )
			)
			( gate "C2A14"
				( objectStatus "@baseboard_fab2_lib.baseboard_fab2(sch_1):page228_i220" )
			)
			( gate "C2A15"
				( objectStatus "@baseboard_fab2_lib.baseboard_fab2(sch_1):page228_i221" )
			)
			( gate "C3A5"
				( objectStatus "@baseboard_fab2_lib.baseboard_fab2(sch_1):page228_i222" )
			)
			( gate "C3A6"
				( objectStatus "@baseboard_fab2_lib.baseboard_fab2(sch_1):page228_i223" )
			)
			( gate "C7L5"
				( objectStatus "@baseboard_fab2_lib.baseboard_fab2(sch_1):page228_i225" )
			)
			( gate "C8M3"
				( objectStatus "@baseboard_fab2_lib.baseboard_fab2(sch_1):page228_i227" )
			)
			( gate "C8M5"
				( objectStatus "@baseboard_fab2_lib.baseboard_fab2(sch_1):page228_i228" )
			)
			( gate "C8L10"
				( objectStatus "@baseboard_fab2_lib.baseboard_fab2(sch_1):page228_i229" )
			)
			( gate "C2A3"
				( objectStatus "@baseboard_fab2_lib.baseboard_fab2(sch_1):page228_i230" )
			)
			( gate "C7M1"
				( objectStatus "@baseboard_fab2_lib.baseboard_fab2(sch_1):page228_i231" )
			)
			( gate "C7M2"
				( objectStatus "@baseboard_fab2_lib.baseboard_fab2(sch_1):page228_i232" )
			)
			( gate "C8M4"
				( objectStatus "@baseboard_fab2_lib.baseboard_fab2(sch_1):page228_i233" )
			)
			( gate "C2A4"
				( objectStatus "@baseboard_fab2_lib.baseboard_fab2(sch_1):page228_i234" )
			)
			( gate "C8M6"
				( objectStatus "@baseboard_fab2_lib.baseboard_fab2(sch_1):page228_i235" )
			)
			( gate "C8L9"
				( objectStatus "@baseboard_fab2_lib.baseboard_fab2(sch_1):page228_i236" )
			)
			( gate "C8L8"
				( objectStatus "@baseboard_fab2_lib.baseboard_fab2(sch_1):page228_i237" )
			)
			( gate "C7L4"
				( objectStatus "@baseboard_fab2_lib.baseboard_fab2(sch_1):page228_i238" )
			)
			( gate "C8L7"
				( objectStatus "@baseboard_fab2_lib.baseboard_fab2(sch_1):page228_i239" )
			)
			( gate "C8L6"
				( objectStatus "@baseboard_fab2_lib.baseboard_fab2(sch_1):page228_i240" )
			)
			( gate "C8L5"
				( objectStatus "@baseboard_fab2_lib.baseboard_fab2(sch_1):page228_i241" )
			)
			( gate "C8M1"
				( objectStatus "@baseboard_fab2_lib.baseboard_fab2(sch_1):page228_i243" )
			)
			( gate "SH7L2"
				( objectStatus "@baseboard_fab2_lib.baseboard_fab2(sch_1):page228_i245" )
			)
			( gate "SH7L1"
				( objectStatus "@baseboard_fab2_lib.baseboard_fab2(sch_1):page228_i246" )
			)
			( gate "R4G17"
				( objectStatus "@baseboard_fab2_lib.baseboard_fab2(sch_1):page229_i14" )
			)
			( gate "C4G13"
				( objectStatus "@baseboard_fab2_lib.baseboard_fab2(sch_1):page229_i15" )
			)
			( gate "C4G20"
				( objectStatus "@baseboard_fab2_lib.baseboard_fab2(sch_1):page229_i17" )
			)
			( gate "C4G21"
				( objectStatus "@baseboard_fab2_lib.baseboard_fab2(sch_1):page229_i21" )
			)
			( gate "EU4G2"
				( objectStatus "@baseboard_fab2_lib.baseboard_fab2(sch_1):page229_i24" )
			)
			( gate "C6U14"
				( objectStatus "@baseboard_fab2_lib.baseboard_fab2(sch_1):page229_i25" )
			)
			( gate "C4G18"
				( objectStatus "@baseboard_fab2_lib.baseboard_fab2(sch_1):page229_i27" )
			)
			( gate "C6U13"
				( objectStatus "@baseboard_fab2_lib.baseboard_fab2(sch_1):page229_i29" )
			)
			( gate "R6U7"
				( objectStatus "@baseboard_fab2_lib.baseboard_fab2(sch_1):page229_i32" )
			)
			( gate "R6U3"
				( objectStatus "@baseboard_fab2_lib.baseboard_fab2(sch_1):page229_i34" )
			)
			( gate "R4G16"
				( objectStatus "@baseboard_fab2_lib.baseboard_fab2(sch_1):page229_i35" )
			)
			( gate "C4G12"
				( objectStatus "@baseboard_fab2_lib.baseboard_fab2(sch_1):page229_i36" )
			)
			( gate "R6U6"
				( objectStatus "@baseboard_fab2_lib.baseboard_fab2(sch_1):page229_i39" )
			)
			( gate "C6U11"
				( objectStatus "@baseboard_fab2_lib.baseboard_fab2(sch_1):page229_i46" )
			)
			( gate "C2F2"
				( objectStatus "@baseboard_fab2_lib.baseboard_fab2(sch_1):page229_i47" )
			)
			( gate "C8T3"
				( objectStatus "@baseboard_fab2_lib.baseboard_fab2(sch_1):page229_i48" )
			)
			( gate "C8U10"
				( objectStatus "@baseboard_fab2_lib.baseboard_fab2(sch_1):page229_i49" )
			)
			( gate "R4G15"
				( objectStatus "@baseboard_fab2_lib.baseboard_fab2(sch_1):page229_i51" )
			)
			( gate "R6U8"
				( objectStatus "@baseboard_fab2_lib.baseboard_fab2(sch_1):page229_i52" )
			)
			( gate "SH8U1"
				( objectStatus "@baseboard_fab2_lib.baseboard_fab2(sch_1):page229_i53" )
			)
			( gate "C4A3"
				( objectStatus "@baseboard_fab2_lib.baseboard_fab2(sch_1):page230_i16" )
			)
			( gate "R4A5"
				( objectStatus "@baseboard_fab2_lib.baseboard_fab2(sch_1):page230_i17" )
			)
			( gate "C4A13"
				( objectStatus "@baseboard_fab2_lib.baseboard_fab2(sch_1):page230_i18" )
			)
			( gate "C4A14"
				( objectStatus "@baseboard_fab2_lib.baseboard_fab2(sch_1):page230_i21" )
			)
			( gate "C4A15"
				( objectStatus "@baseboard_fab2_lib.baseboard_fab2(sch_1):page230_i25" )
			)
			( gate "C6L5"
				( objectStatus "@baseboard_fab2_lib.baseboard_fab2(sch_1):page230_i26" )
			)
			( gate "C4A8"
				( objectStatus "@baseboard_fab2_lib.baseboard_fab2(sch_1):page230_i28" )
			)
			( gate "R6L8"
				( objectStatus "@baseboard_fab2_lib.baseboard_fab2(sch_1):page230_i30" )
			)
			( gate "EU4A2"
				( objectStatus "@baseboard_fab2_lib.baseboard_fab2(sch_1):page230_i31" )
			)
			( gate "R6L6"
				( objectStatus "@baseboard_fab2_lib.baseboard_fab2(sch_1):page230_i34" )
			)
			( gate "R6L5"
				( objectStatus "@baseboard_fab2_lib.baseboard_fab2(sch_1):page230_i37" )
			)
			( gate "R4A3"
				( objectStatus "@baseboard_fab2_lib.baseboard_fab2(sch_1):page230_i38" )
			)
			( gate "C4A6"
				( objectStatus "@baseboard_fab2_lib.baseboard_fab2(sch_1):page230_i39" )
			)
			( gate "C4A7"
				( objectStatus "@baseboard_fab2_lib.baseboard_fab2(sch_1):page230_i46" )
			)
			( gate "C8M12"
				( objectStatus "@baseboard_fab2_lib.baseboard_fab2(sch_1):page230_i47" )
			)
			( gate "C8L3"
				( objectStatus "@baseboard_fab2_lib.baseboard_fab2(sch_1):page230_i48" )
			)
			( gate "C8L4"
				( objectStatus "@baseboard_fab2_lib.baseboard_fab2(sch_1):page230_i49" )
			)
			( gate "R4A4"
				( objectStatus "@baseboard_fab2_lib.baseboard_fab2(sch_1):page230_i51" )
			)
			( gate "R6L7"
				( objectStatus "@baseboard_fab2_lib.baseboard_fab2(sch_1):page230_i52" )
			)
			( gate "SH8L1"
				( objectStatus "@baseboard_fab2_lib.baseboard_fab2(sch_1):page230_i53" )
			)
			( gate "C6F6"
				( objectStatus "@baseboard_fab2_lib.baseboard_fab2(sch_1):page231_i122" )
			)
			( gate "C4T6"
				( objectStatus "@baseboard_fab2_lib.baseboard_fab2(sch_1):page231_i124" )
			)
			( gate "C4T5"
				( objectStatus "@baseboard_fab2_lib.baseboard_fab2(sch_1):page231_i125" )
			)
			( gate "C6G1"
				( objectStatus "@baseboard_fab2_lib.baseboard_fab2(sch_1):page231_i126" )
			)
			( gate "C6G2"
				( objectStatus "@baseboard_fab2_lib.baseboard_fab2(sch_1):page231_i128" )
			)
			( gate "C4U2"
				( objectStatus "@baseboard_fab2_lib.baseboard_fab2(sch_1):page231_i129" )
			)
			( gate "C4U1"
				( objectStatus "@baseboard_fab2_lib.baseboard_fab2(sch_1):page231_i130" )
			)
			( gate "C6G4"
				( objectStatus "@baseboard_fab2_lib.baseboard_fab2(sch_1):page231_i131" )
			)
			( gate "R7F15"
				( objectStatus "@baseboard_fab2_lib.baseboard_fab2(sch_1):page231_i134" )
			)
			( gate "R7F14"
				( objectStatus "@baseboard_fab2_lib.baseboard_fab2(sch_1):page231_i136" )
			)
			( gate "C7F8"
				( objectStatus "@baseboard_fab2_lib.baseboard_fab2(sch_1):page231_i140" )
			)
			( gate "C7F11"
				( objectStatus "@baseboard_fab2_lib.baseboard_fab2(sch_1):page231_i142" )
			)
			( gate "R7F19"
				( objectStatus "@baseboard_fab2_lib.baseboard_fab2(sch_1):page231_i143" )
			)
			( gate "C6G5"
				( objectStatus "@baseboard_fab2_lib.baseboard_fab2(sch_1):page231_i145" )
			)
			( gate "C4U4"
				( objectStatus "@baseboard_fab2_lib.baseboard_fab2(sch_1):page231_i146" )
			)
			( gate "C4U3"
				( objectStatus "@baseboard_fab2_lib.baseboard_fab2(sch_1):page231_i148" )
			)
			( gate "C6F5"
				( objectStatus "@baseboard_fab2_lib.baseboard_fab2(sch_1):page231_i149" )
			)
			( gate "C7F7"
				( objectStatus "@baseboard_fab2_lib.baseboard_fab2(sch_1):page231_i151" )
			)
			( gate "R7F8"
				( objectStatus "@baseboard_fab2_lib.baseboard_fab2(sch_1):page231_i154" )
			)
			( gate "C7F4"
				( objectStatus "@baseboard_fab2_lib.baseboard_fab2(sch_1):page231_i159" )
			)
			( gate "C3T10"
				( objectStatus "@baseboard_fab2_lib.baseboard_fab2(sch_1):page231_i161" )
			)
			( gate "FB7F1"
				( objectStatus "@baseboard_fab2_lib.baseboard_fab2(sch_1):page231_i162" )
			)
			( gate "R7F11"
				( objectStatus "@baseboard_fab2_lib.baseboard_fab2(sch_1):page231_i166" )
			)
			( gate "R7F13"
				( objectStatus "@baseboard_fab2_lib.baseboard_fab2(sch_1):page231_i167" )
			)
			( gate "R7F12"
				( objectStatus "@baseboard_fab2_lib.baseboard_fab2(sch_1):page231_i168" )
			)
			( gate "R7F35"
				( objectStatus "@baseboard_fab2_lib.baseboard_fab2(sch_1):page231_i170" )
			)
			( gate "R7F7"
				( objectStatus "@baseboard_fab2_lib.baseboard_fab2(sch_1):page231_i174" )
			)
			( gate "C7F3"
				( objectStatus "@baseboard_fab2_lib.baseboard_fab2(sch_1):page231_i175" )
			)
			( gate "R7F10"
				( objectStatus "@baseboard_fab2_lib.baseboard_fab2(sch_1):page231_i177" )
			)
			( gate "L7F1"
				( objectStatus "@baseboard_fab2_lib.baseboard_fab2(sch_1):page231_i178" )
			)
			( gate "C6F4"
				( objectStatus "@baseboard_fab2_lib.baseboard_fab2(sch_1):page231_i180" )
			)
			( gate "C3T7"
				( objectStatus "@baseboard_fab2_lib.baseboard_fab2(sch_1):page231_i184" )
			)
			( gate "C3T9"
				( objectStatus "@baseboard_fab2_lib.baseboard_fab2(sch_1):page231_i186" )
			)
			( gate "EU7F1"
				( objectStatus "@baseboard_fab2_lib.baseboard_fab2(sch_1):page231_i193" )
			)
			( gate "C7F10"
				( objectStatus "@baseboard_fab2_lib.baseboard_fab2(sch_1):page231_i194" )
			)
			( gate "C7F9"
				( objectStatus "@baseboard_fab2_lib.baseboard_fab2(sch_1):page231_i199" )
			)
			( gate "C7F12"
				( objectStatus "@baseboard_fab2_lib.baseboard_fab2(sch_1):page231_i200" )
			)
			( gate "R7F18"
				( objectStatus "@baseboard_fab2_lib.baseboard_fab2(sch_1):page231_i201" )
			)
			( gate "C3T11"
				( objectStatus "@baseboard_fab2_lib.baseboard_fab2(sch_1):page231_i202" )
			)
			( gate "C7F6"
				( objectStatus "@baseboard_fab2_lib.baseboard_fab2(sch_1):page231_i205" )
			)
			( gate "R7F16"
				( objectStatus "@baseboard_fab2_lib.baseboard_fab2(sch_1):page231_i208" )
			)
			( gate "C7F5"
				( objectStatus "@baseboard_fab2_lib.baseboard_fab2(sch_1):page231_i209" )
			)
			( gate "C3T8"
				( objectStatus "@baseboard_fab2_lib.baseboard_fab2(sch_1):page231_i210" )
			)
			( gate "C3T14"
				( objectStatus "@baseboard_fab2_lib.baseboard_fab2(sch_1):page231_i211" )
			)
			( gate "C3T12"
				( objectStatus "@baseboard_fab2_lib.baseboard_fab2(sch_1):page231_i215" )
			)
			( gate "C4T3"
				( objectStatus "@baseboard_fab2_lib.baseboard_fab2(sch_1):page231_i217" )
			)
			( gate "R7F17"
				( objectStatus "@baseboard_fab2_lib.baseboard_fab2(sch_1):page231_i218" )
			)
			( gate "C7F13"
				( objectStatus "@baseboard_fab2_lib.baseboard_fab2(sch_1):page231_i219" )
			)
			( gate "R7F9"
				( objectStatus "@baseboard_fab2_lib.baseboard_fab2(sch_1):page231_i220" )
			)
			( gate "C4L2"
				( objectStatus "@baseboard_fab2_lib.baseboard_fab2(sch_1):page232_i102" )
			)
			( gate "C6A3"
				( objectStatus "@baseboard_fab2_lib.baseboard_fab2(sch_1):page232_i104" )
			)
			( gate "C6A2"
				( objectStatus "@baseboard_fab2_lib.baseboard_fab2(sch_1):page232_i105" )
			)
			( gate "C4L3"
				( objectStatus "@baseboard_fab2_lib.baseboard_fab2(sch_1):page232_i106" )
			)
			( gate "C4L4"
				( objectStatus "@baseboard_fab2_lib.baseboard_fab2(sch_1):page232_i108" )
			)
			( gate "C6A7"
				( objectStatus "@baseboard_fab2_lib.baseboard_fab2(sch_1):page232_i109" )
			)
			( gate "C6A6"
				( objectStatus "@baseboard_fab2_lib.baseboard_fab2(sch_1):page232_i110" )
			)
			( gate "C4M3"
				( objectStatus "@baseboard_fab2_lib.baseboard_fab2(sch_1):page232_i111" )
			)
			( gate "C4M4"
				( objectStatus "@baseboard_fab2_lib.baseboard_fab2(sch_1):page232_i125" )
			)
			( gate "C6B2"
				( objectStatus "@baseboard_fab2_lib.baseboard_fab2(sch_1):page232_i126" )
			)
			( gate "C6B1"
				( objectStatus "@baseboard_fab2_lib.baseboard_fab2(sch_1):page232_i128" )
			)
			( gate "C4L1"
				( objectStatus "@baseboard_fab2_lib.baseboard_fab2(sch_1):page232_i129" )
			)
			( gate "R7B20"
				( objectStatus "@baseboard_fab2_lib.baseboard_fab2(sch_1):page232_i150" )
			)
			( gate "C7B9"
				( objectStatus "@baseboard_fab2_lib.baseboard_fab2(sch_1):page232_i185" )
			)
			( gate "R7B14"
				( objectStatus "@baseboard_fab2_lib.baseboard_fab2(sch_1):page232_i193" )
			)
			( gate "C7B11"
				( objectStatus "@baseboard_fab2_lib.baseboard_fab2(sch_1):page232_i197" )
			)
			( gate "FB7B1"
				( objectStatus "@baseboard_fab2_lib.baseboard_fab2(sch_1):page232_i200" )
			)
			( gate "C7B8"
				( objectStatus "@baseboard_fab2_lib.baseboard_fab2(sch_1):page232_i202" )
			)
			( gate "C3M9"
				( objectStatus "@baseboard_fab2_lib.baseboard_fab2(sch_1):page232_i207" )
			)
			( gate "C7B12"
				( objectStatus "@baseboard_fab2_lib.baseboard_fab2(sch_1):page232_i209" )
			)
			( gate "R7B17"
				( objectStatus "@baseboard_fab2_lib.baseboard_fab2(sch_1):page232_i210" )
			)
			( gate "EU7B1"
				( objectStatus "@baseboard_fab2_lib.baseboard_fab2(sch_1):page232_i214" )
			)
			( gate "R7A15"
				( objectStatus "@baseboard_fab2_lib.baseboard_fab2(sch_1):page232_i218" )
			)
			( gate "C7A34"
				( objectStatus "@baseboard_fab2_lib.baseboard_fab2(sch_1):page232_i220" )
			)
			( gate "R7B10"
				( objectStatus "@baseboard_fab2_lib.baseboard_fab2(sch_1):page232_i227" )
			)
			( gate "C6B7"
				( objectStatus "@baseboard_fab2_lib.baseboard_fab2(sch_1):page232_i229" )
			)
			( gate "C6B3"
				( objectStatus "@baseboard_fab2_lib.baseboard_fab2(sch_1):page232_i236" )
			)
			( gate "C7B7"
				( objectStatus "@baseboard_fab2_lib.baseboard_fab2(sch_1):page232_i238" )
			)
			( gate "L7B1"
				( objectStatus "@baseboard_fab2_lib.baseboard_fab2(sch_1):page232_i239" )
			)
			( gate "R7B19"
				( objectStatus "@baseboard_fab2_lib.baseboard_fab2(sch_1):page232_i240" )
			)
			( gate "C7B30"
				( objectStatus "@baseboard_fab2_lib.baseboard_fab2(sch_1):page232_i241" )
			)
			( gate "C7B6"
				( objectStatus "@baseboard_fab2_lib.baseboard_fab2(sch_1):page232_i252" )
			)
			( gate "C3M10"
				( objectStatus "@baseboard_fab2_lib.baseboard_fab2(sch_1):page232_i253" )
			)
			( gate "R7B12"
				( objectStatus "@baseboard_fab2_lib.baseboard_fab2(sch_1):page232_i257" )
			)
			( gate "C3M8"
				( objectStatus "@baseboard_fab2_lib.baseboard_fab2(sch_1):page232_i259" )
			)
			( gate "C3M15"
				( objectStatus "@baseboard_fab2_lib.baseboard_fab2(sch_1):page232_i260" )
			)
			( gate "C3M16"
				( objectStatus "@baseboard_fab2_lib.baseboard_fab2(sch_1):page232_i261" )
			)
			( gate "C7B5"
				( objectStatus "@baseboard_fab2_lib.baseboard_fab2(sch_1):page232_i262" )
			)
			( gate "C4M1"
				( objectStatus "@baseboard_fab2_lib.baseboard_fab2(sch_1):page232_i267" )
			)
			( gate "R7B18"
				( objectStatus "@baseboard_fab2_lib.baseboard_fab2(sch_1):page232_i298" )
			)
			( gate "R7B11"
				( objectStatus "@baseboard_fab2_lib.baseboard_fab2(sch_1):page232_i299" )
			)
			( gate "R7B16"
				( objectStatus "@baseboard_fab2_lib.baseboard_fab2(sch_1):page232_i300" )
			)
			( gate "C7B10"
				( objectStatus "@baseboard_fab2_lib.baseboard_fab2(sch_1):page232_i301" )
			)
			( gate "C7B13"
				( objectStatus "@baseboard_fab2_lib.baseboard_fab2(sch_1):page232_i302" )
			)
			( gate "R7B15"
				( objectStatus "@baseboard_fab2_lib.baseboard_fab2(sch_1):page232_i303" )
			)
			( gate "R7B13"
				( objectStatus "@baseboard_fab2_lib.baseboard_fab2(sch_1):page232_i304" )
			)
			( gate "C7B14"
				( objectStatus "@baseboard_fab2_lib.baseboard_fab2(sch_1):page232_i306" )
			)
			( gate "R7B9"
				( objectStatus "@baseboard_fab2_lib.baseboard_fab2(sch_1):page232_i307" )
			)
			( gate "C7U4"
				( objectStatus "@baseboard_fab2_lib.baseboard_fab2(sch_1):page233_i109" )
			)
			( gate "C7U5"
				( objectStatus "@baseboard_fab2_lib.baseboard_fab2(sch_1):page233_i111" )
			)
			( gate "C7T2"
				( objectStatus "@baseboard_fab2_lib.baseboard_fab2(sch_1):page233_i112" )
			)
			( gate "C7T3"
				( objectStatus "@baseboard_fab2_lib.baseboard_fab2(sch_1):page233_i113" )
			)
			( gate "C7U6"
				( objectStatus "@baseboard_fab2_lib.baseboard_fab2(sch_1):page233_i115" )
			)
			( gate "C3F3"
				( objectStatus "@baseboard_fab2_lib.baseboard_fab2(sch_1):page233_i116" )
			)
			( gate "C3F4"
				( objectStatus "@baseboard_fab2_lib.baseboard_fab2(sch_1):page233_i117" )
			)
			( gate "C3G3"
				( objectStatus "@baseboard_fab2_lib.baseboard_fab2(sch_1):page233_i118" )
			)
			( gate "C3G7"
				( objectStatus "@baseboard_fab2_lib.baseboard_fab2(sch_1):page233_i132" )
			)
			( gate "C3G4"
				( objectStatus "@baseboard_fab2_lib.baseboard_fab2(sch_1):page233_i133" )
			)
			( gate "C3G8"
				( objectStatus "@baseboard_fab2_lib.baseboard_fab2(sch_1):page233_i135" )
			)
			( gate "C7U3"
				( objectStatus "@baseboard_fab2_lib.baseboard_fab2(sch_1):page233_i136" )
			)
			( gate "R4G25"
				( objectStatus "@baseboard_fab2_lib.baseboard_fab2(sch_1):page233_i157" )
			)
			( gate "R4G5"
				( objectStatus "@baseboard_fab2_lib.baseboard_fab2(sch_1):page233_i182" )
			)
			( gate "C4G7"
				( objectStatus "@baseboard_fab2_lib.baseboard_fab2(sch_1):page233_i183" )
			)
			( gate "R4G11"
				( objectStatus "@baseboard_fab2_lib.baseboard_fab2(sch_1):page233_i184" )
			)
			( gate "R4G14"
				( objectStatus "@baseboard_fab2_lib.baseboard_fab2(sch_1):page233_i185" )
			)
			( gate "C6U6"
				( objectStatus "@baseboard_fab2_lib.baseboard_fab2(sch_1):page233_i187" )
			)
			( gate "C4G5"
				( objectStatus "@baseboard_fab2_lib.baseboard_fab2(sch_1):page233_i189" )
			)
			( gate "C4G8"
				( objectStatus "@baseboard_fab2_lib.baseboard_fab2(sch_1):page233_i194" )
			)
			( gate "C4G4"
				( objectStatus "@baseboard_fab2_lib.baseboard_fab2(sch_1):page233_i196" )
			)
			( gate "FB4G1"
				( objectStatus "@baseboard_fab2_lib.baseboard_fab2(sch_1):page233_i198" )
			)
			( gate "R4G24"
				( objectStatus "@baseboard_fab2_lib.baseboard_fab2(sch_1):page233_i199" )
			)
			( gate "C4G9"
				( objectStatus "@baseboard_fab2_lib.baseboard_fab2(sch_1):page233_i201" )
			)
			( gate "R4F6"
				( objectStatus "@baseboard_fab2_lib.baseboard_fab2(sch_1):page233_i208" )
			)
			( gate "C4F12"
				( objectStatus "@baseboard_fab2_lib.baseboard_fab2(sch_1):page233_i209" )
			)
			( gate "R4G6"
				( objectStatus "@baseboard_fab2_lib.baseboard_fab2(sch_1):page233_i211" )
			)
			( gate "C4F7"
				( objectStatus "@baseboard_fab2_lib.baseboard_fab2(sch_1):page233_i217" )
			)
			( gate "C6U3"
				( objectStatus "@baseboard_fab2_lib.baseboard_fab2(sch_1):page233_i221" )
			)
			( gate "C6U2"
				( objectStatus "@baseboard_fab2_lib.baseboard_fab2(sch_1):page233_i223" )
			)
			( gate "C4G26"
				( objectStatus "@baseboard_fab2_lib.baseboard_fab2(sch_1):page233_i224" )
			)
			( gate "EU4G1"
				( objectStatus "@baseboard_fab2_lib.baseboard_fab2(sch_1):page233_i225" )
			)
			( gate "C6U5"
				( objectStatus "@baseboard_fab2_lib.baseboard_fab2(sch_1):page233_i242" )
			)
			( gate "R4G12"
				( objectStatus "@baseboard_fab2_lib.baseboard_fab2(sch_1):page233_i247" )
			)
			( gate "C6U4"
				( objectStatus "@baseboard_fab2_lib.baseboard_fab2(sch_1):page233_i248" )
			)
			( gate "C4G2"
				( objectStatus "@baseboard_fab2_lib.baseboard_fab2(sch_1):page233_i253" )
			)
			( gate "C6U7"
				( objectStatus "@baseboard_fab2_lib.baseboard_fab2(sch_1):page233_i254" )
			)
			( gate "C6U8"
				( objectStatus "@baseboard_fab2_lib.baseboard_fab2(sch_1):page233_i255" )
			)
			( gate "C4F11"
				( objectStatus "@baseboard_fab2_lib.baseboard_fab2(sch_1):page233_i256" )
			)
			( gate "R4G10"
				( objectStatus "@baseboard_fab2_lib.baseboard_fab2(sch_1):page233_i266" )
			)
			( gate "C4G11"
				( objectStatus "@baseboard_fab2_lib.baseboard_fab2(sch_1):page233_i267" )
			)
			( gate "R4G9"
				( objectStatus "@baseboard_fab2_lib.baseboard_fab2(sch_1):page233_i269" )
			)
			( gate "R4G7"
				( objectStatus "@baseboard_fab2_lib.baseboard_fab2(sch_1):page233_i270" )
			)
			( gate "R4G8"
				( objectStatus "@baseboard_fab2_lib.baseboard_fab2(sch_1):page233_i271" )
			)
			( gate "R4G13"
				( objectStatus "@baseboard_fab2_lib.baseboard_fab2(sch_1):page233_i272" )
			)
			( gate "C4G6"
				( objectStatus "@baseboard_fab2_lib.baseboard_fab2(sch_1):page233_i273" )
			)
			( gate "C4G10"
				( objectStatus "@baseboard_fab2_lib.baseboard_fab2(sch_1):page233_i274" )
			)
			( gate "R4G4"
				( objectStatus "@baseboard_fab2_lib.baseboard_fab2(sch_1):page233_i275" )
			)
			( gate "L4G1"
				( objectStatus "@baseboard_fab2_lib.baseboard_fab2(sch_1):page233_i277" )
			)
			( gate "R4B14"
				( objectStatus "@baseboard_fab2_lib.baseboard_fab2(sch_1):page234_i29" )
			)
			( gate "C3B2"
				( objectStatus "@baseboard_fab2_lib.baseboard_fab2(sch_1):page234_i84" )
			)
			( gate "C3A8"
				( objectStatus "@baseboard_fab2_lib.baseboard_fab2(sch_1):page234_i86" )
			)
			( gate "C7L3"
				( objectStatus "@baseboard_fab2_lib.baseboard_fab2(sch_1):page234_i87" )
			)
			( gate "C7L2"
				( objectStatus "@baseboard_fab2_lib.baseboard_fab2(sch_1):page234_i88" )
			)
			( gate "C7L7"
				( objectStatus "@baseboard_fab2_lib.baseboard_fab2(sch_1):page234_i89" )
			)
			( gate "C7L6"
				( objectStatus "@baseboard_fab2_lib.baseboard_fab2(sch_1):page234_i90" )
			)
			( gate "C7M4"
				( objectStatus "@baseboard_fab2_lib.baseboard_fab2(sch_1):page234_i91" )
			)
			( gate "C7M3"
				( objectStatus "@baseboard_fab2_lib.baseboard_fab2(sch_1):page234_i92" )
			)
			( gate "C3A4"
				( objectStatus "@baseboard_fab2_lib.baseboard_fab2(sch_1):page234_i93" )
			)
			( gate "C3B1"
				( objectStatus "@baseboard_fab2_lib.baseboard_fab2(sch_1):page234_i94" )
			)
			( gate "C3A7"
				( objectStatus "@baseboard_fab2_lib.baseboard_fab2(sch_1):page234_i95" )
			)
			( gate "C3A3"
				( objectStatus "@baseboard_fab2_lib.baseboard_fab2(sch_1):page234_i97" )
			)
			( gate "C4B5"
				( objectStatus "@baseboard_fab2_lib.baseboard_fab2(sch_1):page234_i129" )
			)
			( gate "C4B1"
				( objectStatus "@baseboard_fab2_lib.baseboard_fab2(sch_1):page234_i130" )
			)
			( gate "C4B8"
				( objectStatus "@baseboard_fab2_lib.baseboard_fab2(sch_1):page234_i139" )
			)
			( gate "R4B6"
				( objectStatus "@baseboard_fab2_lib.baseboard_fab2(sch_1):page234_i140" )
			)
			( gate "R4B10"
				( objectStatus "@baseboard_fab2_lib.baseboard_fab2(sch_1):page234_i143" )
			)
			( gate "C6L12"
				( objectStatus "@baseboard_fab2_lib.baseboard_fab2(sch_1):page234_i144" )
			)
			( gate "C4B6"
				( objectStatus "@baseboard_fab2_lib.baseboard_fab2(sch_1):page234_i146" )
			)
			( gate "C6L11"
				( objectStatus "@baseboard_fab2_lib.baseboard_fab2(sch_1):page234_i152" )
			)
			( gate "FB4A1"
				( objectStatus "@baseboard_fab2_lib.baseboard_fab2(sch_1):page234_i154" )
			)
			( gate "R4B13"
				( objectStatus "@baseboard_fab2_lib.baseboard_fab2(sch_1):page234_i155" )
			)
			( gate "R4A7"
				( objectStatus "@baseboard_fab2_lib.baseboard_fab2(sch_1):page234_i162" )
			)
			( gate "C4A16"
				( objectStatus "@baseboard_fab2_lib.baseboard_fab2(sch_1):page234_i163" )
			)
			( gate "L4A1"
				( objectStatus "@baseboard_fab2_lib.baseboard_fab2(sch_1):page234_i164" )
			)
			( gate "C3B3"
				( objectStatus "@baseboard_fab2_lib.baseboard_fab2(sch_1):page234_i167" )
			)
			( gate "C4B3"
				( objectStatus "@baseboard_fab2_lib.baseboard_fab2(sch_1):page234_i177" )
			)
			( gate "C4B2"
				( objectStatus "@baseboard_fab2_lib.baseboard_fab2(sch_1):page234_i180" )
			)
			( gate "C4B15"
				( objectStatus "@baseboard_fab2_lib.baseboard_fab2(sch_1):page234_i182" )
			)
			( gate "R4B2"
				( objectStatus "@baseboard_fab2_lib.baseboard_fab2(sch_1):page234_i183" )
			)
			( gate "EU4A3"
				( objectStatus "@baseboard_fab2_lib.baseboard_fab2(sch_1):page234_i184" )
			)
			( gate "C4A20"
				( objectStatus "@baseboard_fab2_lib.baseboard_fab2(sch_1):page234_i199" )
			)
			( gate "R4B7"
				( objectStatus "@baseboard_fab2_lib.baseboard_fab2(sch_1):page234_i201" )
			)
			( gate "C6L10"
				( objectStatus "@baseboard_fab2_lib.baseboard_fab2(sch_1):page234_i202" )
			)
			( gate "C6M3"
				( objectStatus "@baseboard_fab2_lib.baseboard_fab2(sch_1):page234_i203" )
			)
			( gate "C6M5"
				( objectStatus "@baseboard_fab2_lib.baseboard_fab2(sch_1):page234_i204" )
			)
			( gate "C4A19"
				( objectStatus "@baseboard_fab2_lib.baseboard_fab2(sch_1):page234_i205" )
			)
			( gate "C6L8"
				( objectStatus "@baseboard_fab2_lib.baseboard_fab2(sch_1):page234_i210" )
			)
			( gate "C4B9"
				( objectStatus "@baseboard_fab2_lib.baseboard_fab2(sch_1):page234_i211" )
			)
			( gate "C4B4"
				( objectStatus "@baseboard_fab2_lib.baseboard_fab2(sch_1):page234_i212" )
			)
			( gate "R4B8"
				( objectStatus "@baseboard_fab2_lib.baseboard_fab2(sch_1):page234_i213" )
			)
			( gate "R4B3"
				( objectStatus "@baseboard_fab2_lib.baseboard_fab2(sch_1):page234_i214" )
			)
			( gate "R4B5"
				( objectStatus "@baseboard_fab2_lib.baseboard_fab2(sch_1):page234_i215" )
			)
			( gate "R4B4"
				( objectStatus "@baseboard_fab2_lib.baseboard_fab2(sch_1):page234_i216" )
			)
			( gate "C4B7"
				( objectStatus "@baseboard_fab2_lib.baseboard_fab2(sch_1):page234_i218" )
			)
			( gate "R4B9"
				( objectStatus "@baseboard_fab2_lib.baseboard_fab2(sch_1):page234_i219" )
			)
			( gate "R4B1"
				( objectStatus "@baseboard_fab2_lib.baseboard_fab2(sch_1):page234_i220" )
			)
			( gate "C8A7"
				( objectStatus "@baseboard_fab2_lib.baseboard_fab2(sch_1):page235_i143" )
			)
			( gate "C8A8"
				( objectStatus "@baseboard_fab2_lib.baseboard_fab2(sch_1):page235_i145" )
			)
			( gate "R2L16"
				( objectStatus "@baseboard_fab2_lib.baseboard_fab2(sch_1):page235_i147" )
			)
			( gate "R2L24"
				( objectStatus "@baseboard_fab2_lib.baseboard_fab2(sch_1):page235_i148" )
			)
			( gate "R8A6"
				( objectStatus "@baseboard_fab2_lib.baseboard_fab2(sch_1):page235_i149" )
			)
			( gate "C2L8"
				( objectStatus "@baseboard_fab2_lib.baseboard_fab2(sch_1):page235_i151" )
			)
			( gate "C2L2"
				( objectStatus "@baseboard_fab2_lib.baseboard_fab2(sch_1):page235_i153" )
			)
			( gate "R2L8"
				( objectStatus "@baseboard_fab2_lib.baseboard_fab2(sch_1):page235_i154" )
			)
			( gate "R2L14"
				( objectStatus "@baseboard_fab2_lib.baseboard_fab2(sch_1):page235_i159" )
			)
			( gate "R8A4"
				( objectStatus "@baseboard_fab2_lib.baseboard_fab2(sch_1):page235_i165" )
			)
			( gate "R2L10"
				( objectStatus "@baseboard_fab2_lib.baseboard_fab2(sch_1):page235_i166" )
			)
			( gate "C8A3"
				( objectStatus "@baseboard_fab2_lib.baseboard_fab2(sch_1):page235_i167" )
			)
			( gate "C2L11"
				( objectStatus "@baseboard_fab2_lib.baseboard_fab2(sch_1):page235_i169" )
			)
			( gate "R8A8"
				( objectStatus "@baseboard_fab2_lib.baseboard_fab2(sch_1):page235_i172" )
			)
			( gate "R8A9"
				( objectStatus "@baseboard_fab2_lib.baseboard_fab2(sch_1):page235_i173" )
			)
			( gate "R2L9"
				( objectStatus "@baseboard_fab2_lib.baseboard_fab2(sch_1):page235_i176" )
			)
			( gate "C8A2"
				( objectStatus "@baseboard_fab2_lib.baseboard_fab2(sch_1):page235_i209" )
			)
			( gate "R8A1"
				( objectStatus "@baseboard_fab2_lib.baseboard_fab2(sch_1):page235_i210" )
			)
			( gate "R8A5"
				( objectStatus "@baseboard_fab2_lib.baseboard_fab2(sch_1):page235_i216" )
			)
			( gate "R8A2"
				( objectStatus "@baseboard_fab2_lib.baseboard_fab2(sch_1):page235_i217" )
			)
			( gate "C8A9"
				( objectStatus "@baseboard_fab2_lib.baseboard_fab2(sch_1):page235_i218" )
			)
			( gate "R2L17"
				( objectStatus "@baseboard_fab2_lib.baseboard_fab2(sch_1):page235_i221" )
			)
			( gate "R8A7"
				( objectStatus "@baseboard_fab2_lib.baseboard_fab2(sch_1):page235_i222" )
			)
			( gate "R2L1"
				( objectStatus "@baseboard_fab2_lib.baseboard_fab2(sch_1):page235_i224" )
			)
			( gate "R2L7"
				( objectStatus "@baseboard_fab2_lib.baseboard_fab2(sch_1):page235_i225" )
			)
			( gate "EU8A1"
				( objectStatus "@baseboard_fab2_lib.baseboard_fab2(sch_1):page235_i229" )
			)
			( gate "R2L25"
				( objectStatus "@baseboard_fab2_lib.baseboard_fab2(sch_1):page235_i235" )
			)
			( gate "R2L26"
				( objectStatus "@baseboard_fab2_lib.baseboard_fab2(sch_1):page235_i236" )
			)
			( gate "C7A30"
				( objectStatus "@baseboard_fab2_lib.baseboard_fab2(sch_1):page236_i9" )
			)
			( gate "L7A2"
				( objectStatus "@baseboard_fab2_lib.baseboard_fab2(sch_1):page236_i10" )
			)
			( gate "R3L1"
				( objectStatus "@baseboard_fab2_lib.baseboard_fab2(sch_1):page236_i14" )
			)
			( gate "C7A8"
				( objectStatus "@baseboard_fab2_lib.baseboard_fab2(sch_1):page236_i16" )
			)
			( gate "C3L1"
				( objectStatus "@baseboard_fab2_lib.baseboard_fab2(sch_1):page236_i17" )
			)
			( gate "C7A6"
				( objectStatus "@baseboard_fab2_lib.baseboard_fab2(sch_1):page236_i19" )
			)
			( gate "C7A39"
				( objectStatus "@baseboard_fab2_lib.baseboard_fab2(sch_1):page236_i20" )
			)
			( gate "C7A43"
				( objectStatus "@baseboard_fab2_lib.baseboard_fab2(sch_1):page236_i21" )
			)
			( gate "C7A7"
				( objectStatus "@baseboard_fab2_lib.baseboard_fab2(sch_1):page236_i22" )
			)
			( gate "C3L12"
				( objectStatus "@baseboard_fab2_lib.baseboard_fab2(sch_1):page236_i23" )
			)
			( gate "C3L11"
				( objectStatus "@baseboard_fab2_lib.baseboard_fab2(sch_1):page236_i24" )
			)
			( gate "C3L8"
				( objectStatus "@baseboard_fab2_lib.baseboard_fab2(sch_1):page236_i26" )
			)
			( gate "C3L9"
				( objectStatus "@baseboard_fab2_lib.baseboard_fab2(sch_1):page236_i29" )
			)
			( gate "C3L7"
				( objectStatus "@baseboard_fab2_lib.baseboard_fab2(sch_1):page236_i31" )
			)
			( gate "C3L10"
				( objectStatus "@baseboard_fab2_lib.baseboard_fab2(sch_1):page236_i32" )
			)
			( gate "C7A9"
				( objectStatus "@baseboard_fab2_lib.baseboard_fab2(sch_1):page236_i33" )
			)
			( gate "C7A44"
				( objectStatus "@baseboard_fab2_lib.baseboard_fab2(sch_1):page236_i34" )
			)
			( gate "C7A40"
				( objectStatus "@baseboard_fab2_lib.baseboard_fab2(sch_1):page236_i35" )
			)
			( gate "C7A10"
				( objectStatus "@baseboard_fab2_lib.baseboard_fab2(sch_1):page236_i36" )
			)
			( gate "C3L29"
				( objectStatus "@baseboard_fab2_lib.baseboard_fab2(sch_1):page236_i38" )
			)
			( gate "C7A41"
				( objectStatus "@baseboard_fab2_lib.baseboard_fab2(sch_1):page236_i39" )
			)
			( gate "R3L4"
				( objectStatus "@baseboard_fab2_lib.baseboard_fab2(sch_1):page236_i41" )
			)
			( gate "L7A4"
				( objectStatus "@baseboard_fab2_lib.baseboard_fab2(sch_1):page236_i45" )
			)
			( gate "C7A42"
				( objectStatus "@baseboard_fab2_lib.baseboard_fab2(sch_1):page236_i46" )
			)
			( gate "R8B14"
				( objectStatus "@baseboard_fab2_lib.baseboard_fab2(sch_1):page236_i56" )
			)
			( gate "R8B15"
				( objectStatus "@baseboard_fab2_lib.baseboard_fab2(sch_1):page236_i57" )
			)
			( gate "R8B12"
				( objectStatus "@baseboard_fab2_lib.baseboard_fab2(sch_1):page236_i59" )
			)
			( gate "C7A13"
				( objectStatus "@baseboard_fab2_lib.baseboard_fab2(sch_1):page236_i63" )
			)
			( gate "C7A14"
				( objectStatus "@baseboard_fab2_lib.baseboard_fab2(sch_1):page236_i65" )
			)
			( gate "C3L18"
				( objectStatus "@baseboard_fab2_lib.baseboard_fab2(sch_1):page236_i71" )
			)
			( gate "C3L20"
				( objectStatus "@baseboard_fab2_lib.baseboard_fab2(sch_1):page236_i73" )
			)
			( gate "C3L21"
				( objectStatus "@baseboard_fab2_lib.baseboard_fab2(sch_1):page236_i74" )
			)
			( gate "C7A27"
				( objectStatus "@baseboard_fab2_lib.baseboard_fab2(sch_1):page236_i75" )
			)
			( gate "C3L19"
				( objectStatus "@baseboard_fab2_lib.baseboard_fab2(sch_1):page236_i76" )
			)
			( gate "C2L46"
				( objectStatus "@baseboard_fab2_lib.baseboard_fab2(sch_1):page236_i77" )
			)
			( gate "C8A15"
				( objectStatus "@baseboard_fab2_lib.baseboard_fab2(sch_1):page236_i78" )
			)
			( gate "C2L25"
				( objectStatus "@baseboard_fab2_lib.baseboard_fab2(sch_1):page236_i79" )
			)
			( gate "R7A13"
				( objectStatus "@baseboard_fab2_lib.baseboard_fab2(sch_1):page236_i90" )
			)
			( gate "R7A18"
				( objectStatus "@baseboard_fab2_lib.baseboard_fab2(sch_1):page236_i92" )
			)
			( gate "R7A19"
				( objectStatus "@baseboard_fab2_lib.baseboard_fab2(sch_1):page236_i93" )
			)
			( gate "R7A14"
				( objectStatus "@baseboard_fab2_lib.baseboard_fab2(sch_1):page236_i94" )
			)
			( gate "EU7A3"
				( objectStatus "@baseboard_fab2_lib.baseboard_fab2(sch_1):page236_i116" )
			)
			( gate "EU7A2"
				( objectStatus "@baseboard_fab2_lib.baseboard_fab2(sch_1):page236_i117" )
			)
			( gate "R3L15"
				( objectStatus "@baseboard_fab2_lib.baseboard_fab2(sch_1):page236_i118" )
			)
			( gate "R3L14"
				( objectStatus "@baseboard_fab2_lib.baseboard_fab2(sch_1):page236_i120" )
			)
			( gate "R8A10"
				( objectStatus "@baseboard_fab2_lib.baseboard_fab2(sch_1):page237_i3" )
			)
			( gate "C8A11"
				( objectStatus "@baseboard_fab2_lib.baseboard_fab2(sch_1):page237_i5" )
			)
			( gate "C2L45"
				( objectStatus "@baseboard_fab2_lib.baseboard_fab2(sch_1):page237_i12" )
			)
			( gate "C8A14"
				( objectStatus "@baseboard_fab2_lib.baseboard_fab2(sch_1):page237_i13" )
			)
			( gate "R8A12"
				( objectStatus "@baseboard_fab2_lib.baseboard_fab2(sch_1):page237_i15" )
			)
			( gate "C8A6"
				( objectStatus "@baseboard_fab2_lib.baseboard_fab2(sch_1):page237_i29" )
			)
			( gate "C8A4"
				( objectStatus "@baseboard_fab2_lib.baseboard_fab2(sch_1):page237_i31" )
			)
			( gate "C8A10"
				( objectStatus "@baseboard_fab2_lib.baseboard_fab2(sch_1):page237_i55" )
			)
			( gate "C8A12"
				( objectStatus "@baseboard_fab2_lib.baseboard_fab2(sch_1):page237_i77" )
			)
			( gate "C2L32"
				( objectStatus "@baseboard_fab2_lib.baseboard_fab2(sch_1):page237_i79" )
			)
			( gate "R2L19"
				( objectStatus "@baseboard_fab2_lib.baseboard_fab2(sch_1):page237_i80" )
			)
			( gate "R2L20"
				( objectStatus "@baseboard_fab2_lib.baseboard_fab2(sch_1):page237_i81" )
			)
			( gate "EU8A2"
				( objectStatus "@baseboard_fab2_lib.baseboard_fab2(sch_1):page237_i86" )
			)
			( gate "R8A11"
				( objectStatus "@baseboard_fab2_lib.baseboard_fab2(sch_1):page237_i90" )
			)
			( gate "C9F9"
				( objectStatus "@baseboard_fab2_lib.baseboard_fab2(sch_1):page238_i5" )
			)
			( gate "C9F3"
				( objectStatus "@baseboard_fab2_lib.baseboard_fab2(sch_1):page238_i7" )
			)
			( gate "R9F8"
				( objectStatus "@baseboard_fab2_lib.baseboard_fab2(sch_1):page238_i14" )
			)
			( gate "C9F8"
				( objectStatus "@baseboard_fab2_lib.baseboard_fab2(sch_1):page238_i19" )
			)
			( gate "R9F13"
				( objectStatus "@baseboard_fab2_lib.baseboard_fab2(sch_1):page238_i21" )
			)
			( gate "C9E10"
				( objectStatus "@baseboard_fab2_lib.baseboard_fab2(sch_1):page238_i23" )
			)
			( gate "C9F4"
				( objectStatus "@baseboard_fab2_lib.baseboard_fab2(sch_1):page238_i30" )
			)
			( gate "C9E11"
				( objectStatus "@baseboard_fab2_lib.baseboard_fab2(sch_1):page238_i39" )
			)
			( gate "EU9F1"
				( objectStatus "@baseboard_fab2_lib.baseboard_fab2(sch_1):page238_i40" )
			)
			( gate "R9F11"
				( objectStatus "@baseboard_fab2_lib.baseboard_fab2(sch_1):page238_i41" )
			)
			( gate "C9F10"
				( objectStatus "@baseboard_fab2_lib.baseboard_fab2(sch_1):page239_i4" )
			)
			( gate "R9F12"
				( objectStatus "@baseboard_fab2_lib.baseboard_fab2(sch_1):page239_i6" )
			)
			( gate "C9F13"
				( objectStatus "@baseboard_fab2_lib.baseboard_fab2(sch_1):page239_i7" )
			)
			( gate "C1T15"
				( objectStatus "@baseboard_fab2_lib.baseboard_fab2(sch_1):page239_i12" )
			)
			( gate "R9F6"
				( objectStatus "@baseboard_fab2_lib.baseboard_fab2(sch_1):page238_i45" )
			)
			( gate "R9F32"
				( objectStatus "@baseboard_fab2_lib.baseboard_fab2(sch_1):page239_i15" )
			)
			( gate "C1T7"
				( objectStatus "@baseboard_fab2_lib.baseboard_fab2(sch_1):page239_i22" )
			)
			( gate "C9F6"
				( objectStatus "@baseboard_fab2_lib.baseboard_fab2(sch_1):page239_i30" )
			)
			( gate "EU9F2"
				( objectStatus "@baseboard_fab2_lib.baseboard_fab2(sch_1):page239_i70" )
			)
			( gate "C9F5"
				( objectStatus "@baseboard_fab2_lib.baseboard_fab2(sch_1):page239_i71" )
			)
			( gate "R1T9"
				( objectStatus "@baseboard_fab2_lib.baseboard_fab2(sch_1):page239_i72" )
			)
			( gate "R8F9"
				( objectStatus "@baseboard_fab2_lib.baseboard_fab2(sch_1):page240_i106" )
			)
			( gate "C2R11"
				( objectStatus "@baseboard_fab2_lib.baseboard_fab2(sch_1):page240_i109" )
			)
			( gate "R8F1"
				( objectStatus "@baseboard_fab2_lib.baseboard_fab2(sch_1):page240_i111" )
			)
			( gate "C8E17"
				( objectStatus "@baseboard_fab2_lib.baseboard_fab2(sch_1):page240_i113" )
			)
			( gate "C8F2"
				( objectStatus "@baseboard_fab2_lib.baseboard_fab2(sch_1):page240_i116" )
			)
			( gate "R8F5"
				( objectStatus "@baseboard_fab2_lib.baseboard_fab2(sch_1):page240_i117" )
			)
			( gate "EU8F1"
				( objectStatus "@baseboard_fab2_lib.baseboard_fab2(sch_1):page240_i125" )
			)
			( gate "R8E35"
				( objectStatus "@baseboard_fab2_lib.baseboard_fab2(sch_1):page240_i127" )
			)
			( gate "C8E12"
				( objectStatus "@baseboard_fab2_lib.baseboard_fab2(sch_1):page240_i129" )
			)
			( gate "FB9E1"
				( objectStatus "@baseboard_fab2_lib.baseboard_fab2(sch_1):page240_i132" )
			)
			( gate "C9F1"
				( objectStatus "@baseboard_fab2_lib.baseboard_fab2(sch_1):page240_i134" )
			)
			( gate "C8E11"
				( objectStatus "@baseboard_fab2_lib.baseboard_fab2(sch_1):page240_i135" )
			)
			( gate "C8E10"
				( objectStatus "@baseboard_fab2_lib.baseboard_fab2(sch_1):page240_i137" )
			)
			( gate "C8E14"
				( objectStatus "@baseboard_fab2_lib.baseboard_fab2(sch_1):page240_i139" )
			)
			( gate "R8E38"
				( objectStatus "@baseboard_fab2_lib.baseboard_fab2(sch_1):page240_i140" )
			)
			( gate "R8E34"
				( objectStatus "@baseboard_fab2_lib.baseboard_fab2(sch_1):page240_i142" )
			)
			( gate "R8E31"
				( objectStatus "@baseboard_fab2_lib.baseboard_fab2(sch_1):page240_i143" )
			)
			( gate "R8E25"
				( objectStatus "@baseboard_fab2_lib.baseboard_fab2(sch_1):page240_i144" )
			)
			( gate "R8F11"
				( objectStatus "@baseboard_fab2_lib.baseboard_fab2(sch_1):page240_i146" )
			)
			( gate "R8F3"
				( objectStatus "@baseboard_fab2_lib.baseboard_fab2(sch_1):page240_i148" )
			)
			( gate "R2T4"
				( objectStatus "@baseboard_fab2_lib.baseboard_fab2(sch_1):page240_i152" )
			)
			( gate "C8F14"
				( objectStatus "@baseboard_fab2_lib.baseboard_fab2(sch_1):page240_i154" )
			)
			( gate "C8F8"
				( objectStatus "@baseboard_fab2_lib.baseboard_fab2(sch_1):page240_i155" )
			)
			( gate "C2T7"
				( objectStatus "@baseboard_fab2_lib.baseboard_fab2(sch_1):page240_i158" )
			)
			( gate "C2T6"
				( objectStatus "@baseboard_fab2_lib.baseboard_fab2(sch_1):page240_i160" )
			)
			( gate "C8F3"
				( objectStatus "@baseboard_fab2_lib.baseboard_fab2(sch_1):page240_i163" )
			)
			( gate "EU8E1"
				( objectStatus "@baseboard_fab2_lib.baseboard_fab2(sch_1):page240_i170" )
			)
			( gate "R8F10"
				( objectStatus "@baseboard_fab2_lib.baseboard_fab2(sch_1):page240_i171" )
			)
			( gate "L8F1"
				( objectStatus "@baseboard_fab2_lib.baseboard_fab2(sch_1):page240_i173" )
			)
			( gate "C2T9"
				( objectStatus "@baseboard_fab2_lib.baseboard_fab2(sch_1):page240_i174" )
			)
			( gate "R8F2"
				( objectStatus "@baseboard_fab2_lib.baseboard_fab2(sch_1):page240_i176" )
			)
			( gate "R8E40"
				( objectStatus "@baseboard_fab2_lib.baseboard_fab2(sch_1):page240_i177" )
			)
			( gate "C8E9"
				( objectStatus "@baseboard_fab2_lib.baseboard_fab2(sch_1):page241_i2" )
			)
			( gate "C8E7"
				( objectStatus "@baseboard_fab2_lib.baseboard_fab2(sch_1):page241_i3" )
			)
			( gate "C8E4"
				( objectStatus "@baseboard_fab2_lib.baseboard_fab2(sch_1):page241_i8" )
			)
			( gate "R8E18"
				( objectStatus "@baseboard_fab2_lib.baseboard_fab2(sch_1):page241_i9" )
			)
			( gate "R7E12"
				( objectStatus "@baseboard_fab2_lib.baseboard_fab2(sch_1):page241_i11" )
			)
			( gate "C8E6"
				( objectStatus "@baseboard_fab2_lib.baseboard_fab2(sch_1):page241_i12" )
			)
			( gate "C7E10"
				( objectStatus "@baseboard_fab2_lib.baseboard_fab2(sch_1):page241_i14" )
			)
			( gate "R7E14"
				( objectStatus "@baseboard_fab2_lib.baseboard_fab2(sch_1):page241_i18" )
			)
			( gate "C7E14"
				( objectStatus "@baseboard_fab2_lib.baseboard_fab2(sch_1):page241_i30" )
			)
			( gate "R7E17"
				( objectStatus "@baseboard_fab2_lib.baseboard_fab2(sch_1):page241_i37" )
			)
			( gate "C7E11"
				( objectStatus "@baseboard_fab2_lib.baseboard_fab2(sch_1):page241_i39" )
			)
			( gate "C8E13"
				( objectStatus "@baseboard_fab2_lib.baseboard_fab2(sch_1):page241_i41" )
			)
			( gate "C7E13"
				( objectStatus "@baseboard_fab2_lib.baseboard_fab2(sch_1):page241_i45" )
			)
			( gate "C7E12"
				( objectStatus "@baseboard_fab2_lib.baseboard_fab2(sch_1):page241_i47" )
			)
			( gate "R7F1"
				( objectStatus "@baseboard_fab2_lib.baseboard_fab2(sch_1):page241_i50" )
			)
			( gate "R7E16"
				( objectStatus "@baseboard_fab2_lib.baseboard_fab2(sch_1):page241_i51" )
			)
			( gate "C8E16"
				( objectStatus "@baseboard_fab2_lib.baseboard_fab2(sch_1):page241_i53" )
			)
			( gate "R8E39"
				( objectStatus "@baseboard_fab2_lib.baseboard_fab2(sch_1):page241_i54" )
			)
			( gate "C8F1"
				( objectStatus "@baseboard_fab2_lib.baseboard_fab2(sch_1):page241_i57" )
			)
			( gate "R7E13"
				( objectStatus "@baseboard_fab2_lib.baseboard_fab2(sch_1):page241_i58" )
			)
			( gate "C8E15"
				( objectStatus "@baseboard_fab2_lib.baseboard_fab2(sch_1):page241_i63" )
			)
			( gate "R8E37"
				( objectStatus "@baseboard_fab2_lib.baseboard_fab2(sch_1):page241_i78" )
			)
			( gate "FB7E1"
				( objectStatus "@baseboard_fab2_lib.baseboard_fab2(sch_1):page241_i82" )
			)
			( gate "EU7E2"
				( objectStatus "@baseboard_fab2_lib.baseboard_fab2(sch_1):page241_i83" )
			)
			( gate "R7E15"
				( objectStatus "@baseboard_fab2_lib.baseboard_fab2(sch_1):page241_i89" )
			)
			( gate "L8E1"
				( objectStatus "@baseboard_fab2_lib.baseboard_fab2(sch_1):page241_i90" )
			)
			( gate "R8E33"
				( objectStatus "@baseboard_fab2_lib.baseboard_fab2(sch_1):page241_i91" )
			)
			( gate "C5G106"
				( objectStatus "@baseboard_fab2_lib.baseboard_fab2(sch_1):page243_i88" )
			)
			( gate "C5G107"
				( objectStatus "@baseboard_fab2_lib.baseboard_fab2(sch_1):page243_i87" )
			)
			( gate "C5G108"
				( objectStatus "@baseboard_fab2_lib.baseboard_fab2(sch_1):page243_i86" )
			)
			( gate "C5G109"
				( objectStatus "@baseboard_fab2_lib.baseboard_fab2(sch_1):page243_i85" )
			)
			( gate "C5G110"
				( objectStatus "@baseboard_fab2_lib.baseboard_fab2(sch_1):page243_i84" )
			)
			( gate "C5G21"
				( objectStatus "@baseboard_fab2_lib.baseboard_fab2(sch_1):page242_i11" )
			)
			( gate "C5G111"
				( objectStatus "@baseboard_fab2_lib.baseboard_fab2(sch_1):page243_i83" )
			)
			( gate "C5G112"
				( objectStatus "@baseboard_fab2_lib.baseboard_fab2(sch_1):page243_i82" )
			)
			( gate "C5G113"
				( objectStatus "@baseboard_fab2_lib.baseboard_fab2(sch_1):page243_i81" )
			)
			( gate "C5G22"
				( objectStatus "@baseboard_fab2_lib.baseboard_fab2(sch_1):page242_i15" )
			)
			( gate "C5G114"
				( objectStatus "@baseboard_fab2_lib.baseboard_fab2(sch_1):page243_i80" )
			)
			( gate "C5G97"
				( objectStatus "@baseboard_fab2_lib.baseboard_fab2(sch_1):page243_i79" )
			)
			( gate "C5G98"
				( objectStatus "@baseboard_fab2_lib.baseboard_fab2(sch_1):page243_i78" )
			)
			( gate "C5G99"
				( objectStatus "@baseboard_fab2_lib.baseboard_fab2(sch_1):page243_i77" )
			)
			( gate "C5G100"
				( objectStatus "@baseboard_fab2_lib.baseboard_fab2(sch_1):page243_i76" )
			)
			( gate "C5G101"
				( objectStatus "@baseboard_fab2_lib.baseboard_fab2(sch_1):page243_i75" )
			)
			( gate "C5G102"
				( objectStatus "@baseboard_fab2_lib.baseboard_fab2(sch_1):page243_i74" )
			)
			( gate "C5G105"
				( objectStatus "@baseboard_fab2_lib.baseboard_fab2(sch_1):page243_i73" )
			)
			( gate "C5G104"
				( objectStatus "@baseboard_fab2_lib.baseboard_fab2(sch_1):page243_i72" )
			)
			( gate "C5G103"
				( objectStatus "@baseboard_fab2_lib.baseboard_fab2(sch_1):page243_i71" )
			)
			( gate "C5G88"
				( objectStatus "@baseboard_fab2_lib.baseboard_fab2(sch_1):page243_i70" )
			)
			( gate "C5G89"
				( objectStatus "@baseboard_fab2_lib.baseboard_fab2(sch_1):page243_i69" )
			)
			( gate "C5G90"
				( objectStatus "@baseboard_fab2_lib.baseboard_fab2(sch_1):page243_i68" )
			)
			( gate "C5G91"
				( objectStatus "@baseboard_fab2_lib.baseboard_fab2(sch_1):page243_i67" )
			)
			( gate "C5G92"
				( objectStatus "@baseboard_fab2_lib.baseboard_fab2(sch_1):page243_i66" )
			)
			( gate "C5G77"
				( objectStatus "@baseboard_fab2_lib.baseboard_fab2(sch_1):page242_i37" )
			)
			( gate "C5G93"
				( objectStatus "@baseboard_fab2_lib.baseboard_fab2(sch_1):page243_i65" )
			)
			( gate "C5G94"
				( objectStatus "@baseboard_fab2_lib.baseboard_fab2(sch_1):page243_i64" )
			)
			( gate "C5G95"
				( objectStatus "@baseboard_fab2_lib.baseboard_fab2(sch_1):page243_i63" )
			)
			( gate "C5G78"
				( objectStatus "@baseboard_fab2_lib.baseboard_fab2(sch_1):page242_i41" )
			)
			( gate "C5G96"
				( objectStatus "@baseboard_fab2_lib.baseboard_fab2(sch_1):page243_i62" )
			)
			( gate "C5G80"
				( objectStatus "@baseboard_fab2_lib.baseboard_fab2(sch_1):page243_i61" )
			)
			( gate "C5G81"
				( objectStatus "@baseboard_fab2_lib.baseboard_fab2(sch_1):page243_i60" )
			)
			( gate "C5G82"
				( objectStatus "@baseboard_fab2_lib.baseboard_fab2(sch_1):page243_i59" )
			)
			( gate "C5G83"
				( objectStatus "@baseboard_fab2_lib.baseboard_fab2(sch_1):page243_i58" )
			)
			( gate "C5G84"
				( objectStatus "@baseboard_fab2_lib.baseboard_fab2(sch_1):page243_i57" )
			)
			( gate "C5G85"
				( objectStatus "@baseboard_fab2_lib.baseboard_fab2(sch_1):page243_i56" )
			)
			( gate "C5G86"
				( objectStatus "@baseboard_fab2_lib.baseboard_fab2(sch_1):page243_i55" )
			)
			( gate "C5G87"
				( objectStatus "@baseboard_fab2_lib.baseboard_fab2(sch_1):page243_i54" )
			)
			( gate "C5G79"
				( objectStatus "@baseboard_fab2_lib.baseboard_fab2(sch_1):page243_i53" )
			)
			( gate "C5G117"
				( objectStatus "@baseboard_fab2_lib.baseboard_fab2(sch_1):page243_i12" )
			)
			( gate "C5G118"
				( objectStatus "@baseboard_fab2_lib.baseboard_fab2(sch_1):page243_i13" )
			)
			( gate "C5G115"
				( objectStatus "@baseboard_fab2_lib.baseboard_fab2(sch_1):page243_i39" )
			)
			( gate "C5G116"
				( objectStatus "@baseboard_fab2_lib.baseboard_fab2(sch_1):page243_i43" )
			)
			( gate "C5G41"
				( objectStatus "@baseboard_fab2_lib.baseboard_fab2(sch_1):page242_i53" )
			)
			( gate "C5G42"
				( objectStatus "@baseboard_fab2_lib.baseboard_fab2(sch_1):page242_i54" )
			)
			( gate "C5G44"
				( objectStatus "@baseboard_fab2_lib.baseboard_fab2(sch_1):page242_i55" )
			)
			( gate "C5G43"
				( objectStatus "@baseboard_fab2_lib.baseboard_fab2(sch_1):page242_i56" )
			)
			( gate "C5G48"
				( objectStatus "@baseboard_fab2_lib.baseboard_fab2(sch_1):page242_i57" )
			)
			( gate "C5G47"
				( objectStatus "@baseboard_fab2_lib.baseboard_fab2(sch_1):page242_i58" )
			)
			( gate "C5G46"
				( objectStatus "@baseboard_fab2_lib.baseboard_fab2(sch_1):page242_i59" )
			)
			( gate "C5G45"
				( objectStatus "@baseboard_fab2_lib.baseboard_fab2(sch_1):page242_i60" )
			)
			( gate "C5G49"
				( objectStatus "@baseboard_fab2_lib.baseboard_fab2(sch_1):page242_i61" )
			)
			( gate "C5G54"
				( objectStatus "@baseboard_fab2_lib.baseboard_fab2(sch_1):page242_i62" )
			)
			( gate "C5G58"
				( objectStatus "@baseboard_fab2_lib.baseboard_fab2(sch_1):page242_i63" )
			)
			( gate "C5G57"
				( objectStatus "@baseboard_fab2_lib.baseboard_fab2(sch_1):page242_i64" )
			)
			( gate "C5G56"
				( objectStatus "@baseboard_fab2_lib.baseboard_fab2(sch_1):page242_i65" )
			)
			( gate "C5G55"
				( objectStatus "@baseboard_fab2_lib.baseboard_fab2(sch_1):page242_i66" )
			)
			( gate "C5G53"
				( objectStatus "@baseboard_fab2_lib.baseboard_fab2(sch_1):page242_i67" )
			)
			( gate "C5G52"
				( objectStatus "@baseboard_fab2_lib.baseboard_fab2(sch_1):page242_i68" )
			)
			( gate "C5G51"
				( objectStatus "@baseboard_fab2_lib.baseboard_fab2(sch_1):page242_i69" )
			)
			( gate "C5G50"
				( objectStatus "@baseboard_fab2_lib.baseboard_fab2(sch_1):page242_i70" )
			)
			( gate "C5G67"
				( objectStatus "@baseboard_fab2_lib.baseboard_fab2(sch_1):page242_i71" )
			)
			( gate "C5G66"
				( objectStatus "@baseboard_fab2_lib.baseboard_fab2(sch_1):page242_i72" )
			)
			( gate "C5G65"
				( objectStatus "@baseboard_fab2_lib.baseboard_fab2(sch_1):page242_i73" )
			)
			( gate "C5G64"
				( objectStatus "@baseboard_fab2_lib.baseboard_fab2(sch_1):page242_i74" )
			)
			( gate "C5G63"
				( objectStatus "@baseboard_fab2_lib.baseboard_fab2(sch_1):page242_i75" )
			)
			( gate "C5G62"
				( objectStatus "@baseboard_fab2_lib.baseboard_fab2(sch_1):page242_i76" )
			)
			( gate "C5G61"
				( objectStatus "@baseboard_fab2_lib.baseboard_fab2(sch_1):page242_i77" )
			)
			( gate "C5G60"
				( objectStatus "@baseboard_fab2_lib.baseboard_fab2(sch_1):page242_i78" )
			)
			( gate "C5G59"
				( objectStatus "@baseboard_fab2_lib.baseboard_fab2(sch_1):page242_i79" )
			)
			( gate "C5G76"
				( objectStatus "@baseboard_fab2_lib.baseboard_fab2(sch_1):page242_i80" )
			)
			( gate "C5G75"
				( objectStatus "@baseboard_fab2_lib.baseboard_fab2(sch_1):page242_i81" )
			)
			( gate "C5G74"
				( objectStatus "@baseboard_fab2_lib.baseboard_fab2(sch_1):page242_i82" )
			)
			( gate "C5G73"
				( objectStatus "@baseboard_fab2_lib.baseboard_fab2(sch_1):page242_i83" )
			)
			( gate "C5G72"
				( objectStatus "@baseboard_fab2_lib.baseboard_fab2(sch_1):page242_i84" )
			)
			( gate "C5G71"
				( objectStatus "@baseboard_fab2_lib.baseboard_fab2(sch_1):page242_i85" )
			)
			( gate "C5G70"
				( objectStatus "@baseboard_fab2_lib.baseboard_fab2(sch_1):page242_i86" )
			)
			( gate "C5G69"
				( objectStatus "@baseboard_fab2_lib.baseboard_fab2(sch_1):page242_i87" )
			)
			( gate "C5G68"
				( objectStatus "@baseboard_fab2_lib.baseboard_fab2(sch_1):page242_i88" )
			)
			( gate "RT3"
				( objectStatus "@baseboard_fab2_lib.baseboard_fab2(sch_1):page202_i89" )
			)
			( gate "CT1"
				( objectStatus "@baseboard_fab2_lib.baseboard_fab2(sch_1):page202_i70" )
			)
			( gate "RT2"
				( objectStatus "@baseboard_fab2_lib.baseboard_fab2(sch_1):page202_i75" )
			)
			( gate "CT3"
				( objectStatus "@baseboard_fab2_lib.baseboard_fab2(sch_1):page202_i76" )
			)
			( gate "CT2"
				( objectStatus "@baseboard_fab2_lib.baseboard_fab2(sch_1):page202_i78" )
			)
			( gate "CT6"
				( objectStatus "@baseboard_fab2_lib.baseboard_fab2(sch_1):page202_i81" )
			)
			( gate "CT5"
				( objectStatus "@baseboard_fab2_lib.baseboard_fab2(sch_1):page202_i82" )
			)
			( gate "RT4"
				( objectStatus "@baseboard_fab2_lib.baseboard_fab2(sch_1):page202_i83" )
			)
			( gate "CT7"
				( objectStatus "@baseboard_fab2_lib.baseboard_fab2(sch_1):page227_i109" )
			)
			( gate "CT9"
				( objectStatus "@baseboard_fab2_lib.baseboard_fab2(sch_1):page227_i111" )
			)
			( gate "CT8"
				( objectStatus "@baseboard_fab2_lib.baseboard_fab2(sch_1):page227_i114" )
			)
			( gate "CT11"
				( objectStatus "@baseboard_fab2_lib.baseboard_fab2(sch_1):page227_i116" )
			)
			( gate "RT6"
				( objectStatus "@baseboard_fab2_lib.baseboard_fab2(sch_1):page227_i125" )
			)
			( gate "CT10"
				( objectStatus "@baseboard_fab2_lib.baseboard_fab2(sch_1):page227_i119" )
			)
			( gate "CT12"
				( objectStatus "@baseboard_fab2_lib.baseboard_fab2(sch_1):page227_i122" )
			)
			( gate "RT11"
				( objectStatus "@baseboard_fab2_lib.baseboard_fab2(sch_1):page208_i96" )
			)
			( gate "CT13"
				( objectStatus "@baseboard_fab2_lib.baseboard_fab2(sch_1):page209_i62" )
			)
			( gate "CT14"
				( objectStatus "@baseboard_fab2_lib.baseboard_fab2(sch_1):page209_i64" )
			)
			( gate "RT10"
				( objectStatus "@baseboard_fab2_lib.baseboard_fab2(sch_1):page209_i66" )
			)
			( gate "CT15"
				( objectStatus "@baseboard_fab2_lib.baseboard_fab2(sch_1):page209_i67" )
			)
			( gate "CT16"
				( objectStatus "@baseboard_fab2_lib.baseboard_fab2(sch_1):page208_i80" )
			)
			( gate "CTI7"
				( objectStatus "@baseboard_fab2_lib.baseboard_fab2(sch_1):page208_i82" )
			)
			( gate "CT18"
				( objectStatus "@baseboard_fab2_lib.baseboard_fab2(sch_1):page208_i84" )
			)
			( gate "RT12"
				( objectStatus "@baseboard_fab2_lib.baseboard_fab2(sch_1):page208_i86" )
			)
			( gate "CT21"
				( objectStatus "@baseboard_fab2_lib.baseboard_fab2(sch_1):page208_i87" )
			)
			( gate "CT19"
				( objectStatus "@baseboard_fab2_lib.baseboard_fab2(sch_1):page208_i90" )
			)
			( gate "CT20"
				( objectStatus "@baseboard_fab2_lib.baseboard_fab2(sch_1):page208_i92" )
			)
			( gate "RT13"
				( objectStatus "@baseboard_fab2_lib.baseboard_fab2(sch_1):page208_i94" )
			)
			( gate "CT24"
				( objectStatus "@baseboard_fab2_lib.baseboard_fab2(sch_1):page207_i71" )
			)
			( gate "CT22"
				( objectStatus "@baseboard_fab2_lib.baseboard_fab2(sch_1):page207_i74" )
			)
			( gate "RT16"
				( objectStatus "@baseboard_fab2_lib.baseboard_fab2(sch_1):page207_i76" )
			)
			( gate "CT23"
				( objectStatus "@baseboard_fab2_lib.baseboard_fab2(sch_1):page207_i77" )
			)
			( gate "CT30"
				( objectStatus "@baseboard_fab2_lib.baseboard_fab2(sch_1):page224_i117" )
			)
			( gate "RT20"
				( objectStatus "@baseboard_fab2_lib.baseboard_fab2(sch_1):page224_i119" )
			)
			( gate "CT29"
				( objectStatus "@baseboard_fab2_lib.baseboard_fab2(sch_1):page224_i121" )
			)
			( gate "CT28"
				( objectStatus "@baseboard_fab2_lib.baseboard_fab2(sch_1):page224_i122" )
			)
			( gate "CT31"
				( objectStatus "@baseboard_fab2_lib.baseboard_fab2(sch_1):page224_i124" )
			)
			( gate "CT33"
				( objectStatus "@baseboard_fab2_lib.baseboard_fab2(sch_1):page224_i127" )
			)
			( gate "RT22"
				( objectStatus "@baseboard_fab2_lib.baseboard_fab2(sch_1):page224_i129" )
			)
			( gate "CT32"
				( objectStatus "@baseboard_fab2_lib.baseboard_fab2(sch_1):page224_i130" )
			)
			( gate "CT36"
				( objectStatus "@baseboard_fab2_lib.baseboard_fab2(sch_1):page204_i85" )
			)
			( gate "RT25"
				( objectStatus "@baseboard_fab2_lib.baseboard_fab2(sch_1):page203_i110" )
			)
			( gate "CT34"
				( objectStatus "@baseboard_fab2_lib.baseboard_fab2(sch_1):page204_i88" )
			)
			( gate "CT35"
				( objectStatus "@baseboard_fab2_lib.baseboard_fab2(sch_1):page204_i90" )
			)
			( gate "RT24"
				( objectStatus "@baseboard_fab2_lib.baseboard_fab2(sch_1):page204_i91" )
			)
			( gate "CT40"
				( objectStatus "@baseboard_fab2_lib.baseboard_fab2(sch_1):page203_i93" )
			)
			( gate "RT31"
				( objectStatus "@baseboard_fab2_lib.baseboard_fab2(sch_1):page219_i130" )
			)
			( gate "CT39"
				( objectStatus "@baseboard_fab2_lib.baseboard_fab2(sch_1):page203_i96" )
			)
			( gate "RT30"
				( objectStatus "@baseboard_fab2_lib.baseboard_fab2(sch_1):page219_i129" )
			)
			( gate "CT37"
				( objectStatus "@baseboard_fab2_lib.baseboard_fab2(sch_1):page203_i99" )
			)
			( gate "CT38"
				( objectStatus "@baseboard_fab2_lib.baseboard_fab2(sch_1):page203_i101" )
			)
			( gate "RT26"
				( objectStatus "@baseboard_fab2_lib.baseboard_fab2(sch_1):page203_i102" )
			)
			( gate "RT27"
				( objectStatus "@baseboard_fab2_lib.baseboard_fab2(sch_1):page203_i105" )
			)
			( gate "CT41"
				( objectStatus "@baseboard_fab2_lib.baseboard_fab2(sch_1):page203_i106" )
			)
			( gate "CT42"
				( objectStatus "@baseboard_fab2_lib.baseboard_fab2(sch_1):page203_i108" )
			)
			( gate "CT46"
				( objectStatus "@baseboard_fab2_lib.baseboard_fab2(sch_1):page219_i113" )
			)
			( gate "RT36"
				( objectStatus "@baseboard_fab2_lib.baseboard_fab2(sch_1):page216_i127" )
			)
			( gate "CT45"
				( objectStatus "@baseboard_fab2_lib.baseboard_fab2(sch_1):page219_i116" )
			)
			( gate "RT33"
				( objectStatus "@baseboard_fab2_lib.baseboard_fab2(sch_1):page216_i126" )
			)
			( gate "CT48"
				( objectStatus "@baseboard_fab2_lib.baseboard_fab2(sch_1):page219_i119" )
			)
			( gate "CT47"
				( objectStatus "@baseboard_fab2_lib.baseboard_fab2(sch_1):page219_i121" )
			)
			( gate "RT32"
				( objectStatus "@baseboard_fab2_lib.baseboard_fab2(sch_1):page219_i123" )
			)
			( gate "CT43"
				( objectStatus "@baseboard_fab2_lib.baseboard_fab2(sch_1):page219_i124" )
			)
			( gate "RT29"
				( objectStatus "@baseboard_fab2_lib.baseboard_fab2(sch_1):page219_i126" )
			)
			( gate "CT44"
				( objectStatus "@baseboard_fab2_lib.baseboard_fab2(sch_1):page219_i127" )
			)
			( gate "CT51"
				( objectStatus "@baseboard_fab2_lib.baseboard_fab2(sch_1):page216_i108" )
			)
			( gate "C7G38"
				( objectStatus "@baseboard_fab2_lib.baseboard_fab2(sch_1):page216_i128" )
			)
			( gate "CT52"
				( objectStatus "@baseboard_fab2_lib.baseboard_fab2(sch_1):page216_i111" )
			)
			( gate "RT37"
				( objectStatus "@baseboard_fab2_lib.baseboard_fab2(sch_1):page210_i62" )
			)
			( gate "RT34"
				( objectStatus "@baseboard_fab2_lib.baseboard_fab2(sch_1):page216_i114" )
			)
			( gate "CT49"
				( objectStatus "@baseboard_fab2_lib.baseboard_fab2(sch_1):page216_i118" )
			)
			( gate "CT53"
				( objectStatus "@baseboard_fab2_lib.baseboard_fab2(sch_1):page216_i119" )
			)
			( gate "CT54"
				( objectStatus "@baseboard_fab2_lib.baseboard_fab2(sch_1):page216_i121" )
			)
			( gate "RT35"
				( objectStatus "@baseboard_fab2_lib.baseboard_fab2(sch_1):page216_i123" )
			)
			( gate "CT50"
				( objectStatus "@baseboard_fab2_lib.baseboard_fab2(sch_1):page216_i124" )
			)
			( gate "L7G1"
				( objectStatus "@baseboard_fab2_lib.baseboard_fab2(sch_1):page216_i125" )
			)
			( gate "RT40"
				( objectStatus "@baseboard_fab2_lib.baseboard_fab2(sch_1):page205_i72" )
			)
			( gate "CT56"
				( objectStatus "@baseboard_fab2_lib.baseboard_fab2(sch_1):page210_i57" )
			)
			( gate "RT38"
				( objectStatus "@baseboard_fab2_lib.baseboard_fab2(sch_1):page210_i59" )
			)
			( gate "CT55"
				( objectStatus "@baseboard_fab2_lib.baseboard_fab2(sch_1):page210_i60" )
			)
			( gate "CT59"
				( objectStatus "@baseboard_fab2_lib.baseboard_fab2(sch_1):page205_i64" )
			)
			( gate "CT58"
				( objectStatus "@baseboard_fab2_lib.baseboard_fab2(sch_1):page205_i65" )
			)
			( gate "RT39"
				( objectStatus "@baseboard_fab2_lib.baseboard_fab2(sch_1):page205_i68" )
			)
			( gate "CT60"
				( objectStatus "@baseboard_fab2_lib.baseboard_fab2(sch_1):page205_i69" )
			)
			( gate "RT41"
				( objectStatus "@baseboard_fab2_lib.baseboard_fab2(sch_1):page214_i139" )
			)
			( gate "CT62"
				( objectStatus "@baseboard_fab2_lib.baseboard_fab2(sch_1):page214_i131" )
			)
			( gate "RT42"
				( objectStatus "@baseboard_fab2_lib.baseboard_fab2(sch_1):page214_i132" )
			)
			( gate "CT61"
				( objectStatus "@baseboard_fab2_lib.baseboard_fab2(sch_1):page214_i134" )
			)
			( gate "CT63"
				( objectStatus "@baseboard_fab2_lib.baseboard_fab2(sch_1):page214_i137" )
			)
			( gate "RT44"
				( objectStatus "@baseboard_fab2_lib.baseboard_fab2(sch_1):page236_i141" )
			)
			( gate "R9F70"
				( objectStatus "@baseboard_fab2_lib.baseboard_fab2(sch_1):page181_i280" )
			)
			( gate "CT67"
				( objectStatus "@baseboard_fab2_lib.baseboard_fab2(sch_1):page236_i124" )
			)
			( gate "CT66"
				( objectStatus "@baseboard_fab2_lib.baseboard_fab2(sch_1):page236_i127" )
			)
			( gate "RT47"
				( objectStatus "@baseboard_fab2_lib.baseboard_fab2(sch_1):page212_i114" )
			)
			( gate "CT65"
				( objectStatus "@baseboard_fab2_lib.baseboard_fab2(sch_1):page236_i131" )
			)
			( gate "RT43"
				( objectStatus "@baseboard_fab2_lib.baseboard_fab2(sch_1):page236_i132" )
			)
			( gate "CT69"
				( objectStatus "@baseboard_fab2_lib.baseboard_fab2(sch_1):page236_i134" )
			)
			( gate "CT64"
				( objectStatus "@baseboard_fab2_lib.baseboard_fab2(sch_1):page236_i136" )
			)
			( gate "RT45"
				( objectStatus "@baseboard_fab2_lib.baseboard_fab2(sch_1):page236_i137" )
			)
			( gate "CT68"
				( objectStatus "@baseboard_fab2_lib.baseboard_fab2(sch_1):page236_i140" )
			)
			( gate "CT70"
				( objectStatus "@baseboard_fab2_lib.baseboard_fab2(sch_1):page212_i106" )
			)
			( gate "R9F65"
				( objectStatus "@baseboard_fab2_lib.baseboard_fab2(sch_1):page158_i148" )
			)
			( gate "CT71"
				( objectStatus "@baseboard_fab2_lib.baseboard_fab2(sch_1):page212_i109" )
			)
			( gate "CT72"
				( objectStatus "@baseboard_fab2_lib.baseboard_fab2(sch_1):page212_i111" )
			)
			( gate "RT48"
				( objectStatus "@baseboard_fab2_lib.baseboard_fab2(sch_1):page212_i112" )
			)
			( gate "CT25"
				( objectStatus "@baseboard_fab2_lib.baseboard_fab2(sch_1):page207_i81" )
			)
			( gate "CT26"
				( objectStatus "@baseboard_fab2_lib.baseboard_fab2(sch_1):page207_i82" )
			)
			( gate "CT27"
				( objectStatus "@baseboard_fab2_lib.baseboard_fab2(sch_1):page207_i84" )
			)
			( gate "RT18"
				( objectStatus "@baseboard_fab2_lib.baseboard_fab2(sch_1):page207_i85" )
			)
			( gate "RT7"
				( objectStatus "@baseboard_fab2_lib.baseboard_fab2(sch_1):page227_i124" )
			)
			( gate "CT4"
				( objectStatus "@baseboard_fab2_lib.baseboard_fab2(sch_1):page202_i87" )
			)
			( gate "C831"
				( objectStatus "@baseboard_fab2_lib.baseboard_fab2(sch_1):page244_i2" )
			)
			( gate "C829"
				( objectStatus "@baseboard_fab2_lib.baseboard_fab2(sch_1):page244_i5" )
			)
			( gate "C833"
				( objectStatus "@baseboard_fab2_lib.baseboard_fab2(sch_1):page244_i8" )
			)
			( gate "C827"
				( objectStatus "@baseboard_fab2_lib.baseboard_fab2(sch_1):page244_i12" )
			)
			( gate "C841"
				( objectStatus "@baseboard_fab2_lib.baseboard_fab2(sch_1):page244_i17" )
			)
			( gate "C830"
				( objectStatus "@baseboard_fab2_lib.baseboard_fab2(sch_1):page244_i23" )
			)
			( gate "C826"
				( objectStatus "@baseboard_fab2_lib.baseboard_fab2(sch_1):page244_i24" )
			)
			( gate "C828"
				( objectStatus "@baseboard_fab2_lib.baseboard_fab2(sch_1):page244_i28" )
			)
			( gate "C840"
				( objectStatus "@baseboard_fab2_lib.baseboard_fab2(sch_1):page244_i29" )
			)
			( gate "C832"
				( objectStatus "@baseboard_fab2_lib.baseboard_fab2(sch_1):page244_i30" )
			)
			( gate "C845"
				( objectStatus "@baseboard_fab2_lib.baseboard_fab2(sch_1):page244_i35" )
			)
			( gate "R767"
				( objectStatus "@baseboard_fab2_lib.baseboard_fab2(sch_1):page244_i39" )
			)
			( gate "C835"
				( objectStatus "@baseboard_fab2_lib.baseboard_fab2(sch_1):page244_i41" )
			)
			( gate "C843"
				( objectStatus "@baseboard_fab2_lib.baseboard_fab2(sch_1):page244_i47" )
			)
			( gate "C834"
				( objectStatus "@baseboard_fab2_lib.baseboard_fab2(sch_1):page244_i50" )
			)
			( gate "C844"
				( objectStatus "@baseboard_fab2_lib.baseboard_fab2(sch_1):page244_i51" )
			)
			( gate "C842"
				( objectStatus "@baseboard_fab2_lib.baseboard_fab2(sch_1):page244_i52" )
			)
			( gate "R769"
				( objectStatus "@baseboard_fab2_lib.baseboard_fab2(sch_1):page244_i58" )
			)
			( gate "R760"
				( objectStatus "@baseboard_fab2_lib.baseboard_fab2(sch_1):page244_i64" )
			)
			( gate "R771"
				( objectStatus "@baseboard_fab2_lib.baseboard_fab2(sch_1):page244_i65" )
			)
			( gate "R768"
				( objectStatus "@baseboard_fab2_lib.baseboard_fab2(sch_1):page244_i66" )
			)
			( gate "R774"
				( objectStatus "@baseboard_fab2_lib.baseboard_fab2(sch_1):page244_i72" )
			)
			( gate "R779"
				( objectStatus "@baseboard_fab2_lib.baseboard_fab2(sch_1):page244_i74" )
			)
			( gate "R783"
				( objectStatus "@baseboard_fab2_lib.baseboard_fab2(sch_1):page244_i77" )
			)
			( gate "R777"
				( objectStatus "@baseboard_fab2_lib.baseboard_fab2(sch_1):page244_i80" )
			)
			( gate "R781"
				( objectStatus "@baseboard_fab2_lib.baseboard_fab2(sch_1):page244_i86" )
			)
			( gate "R775"
				( objectStatus "@baseboard_fab2_lib.baseboard_fab2(sch_1):page244_i93" )
			)
			( gate "R778"
				( objectStatus "@baseboard_fab2_lib.baseboard_fab2(sch_1):page244_i94" )
			)
			( gate "R780"
				( objectStatus "@baseboard_fab2_lib.baseboard_fab2(sch_1):page244_i97" )
			)
			( gate "R782"
				( objectStatus "@baseboard_fab2_lib.baseboard_fab2(sch_1):page244_i98" )
			)
			( gate "R784"
				( objectStatus "@baseboard_fab2_lib.baseboard_fab2(sch_1):page244_i99" )
			)
			( gate "R785"
				( objectStatus "@baseboard_fab2_lib.baseboard_fab2(sch_1):page244_i103" )
			)
			( gate "CONX8"
				( objectStatus "@baseboard_fab2_lib.baseboard_fab2(sch_1):page245_i48" )
			)
			( gate "J8G1"
				( objectStatus "@baseboard_fab2_lib.baseboard_fab2(sch_1):page109_i78" )
			)
			( gate "RN8F1"
				( objectStatus "@baseboard_fab2_lib.baseboard_fab2(sch_1):page246_i5" )
			)
			( gate "RN8F6"
				( objectStatus "@baseboard_fab2_lib.baseboard_fab2(sch_1):page246_i8" )
			)
			( gate "RN8F5"
				( objectStatus "@baseboard_fab2_lib.baseboard_fab2(sch_1):page246_i9" )
			)
			( gate "RN8F2"
				( objectStatus "@baseboard_fab2_lib.baseboard_fab2(sch_1):page246_i10" )
			)
			( gate "RN8F3"
				( objectStatus "@baseboard_fab2_lib.baseboard_fab2(sch_1):page246_i11" )
			)
			( gate "RN8F4"
				( objectStatus "@baseboard_fab2_lib.baseboard_fab2(sch_1):page246_i12" )
			)
			( gate "CN8F1"
				( objectStatus "@baseboard_fab2_lib.baseboard_fab2(sch_1):page246_i15" )
			)
			( gate "CN8F2"
				( objectStatus "@baseboard_fab2_lib.baseboard_fab2(sch_1):page246_i16" )
			)
			( gate "UN8F2"
				( objectStatus "@baseboard_fab2_lib.baseboard_fab2(sch_1):page246_i17" )
			)
			( gate "Q6W1"
				( objectStatus "@baseboard_fab2_lib.baseboard_fab2(sch_1):page200_i225" )
			)
			( gate "R6W10"
				( objectStatus "@baseboard_fab2_lib.baseboard_fab2(sch_1):page247_i1" )
			)
			( gate "R6W1"
				( objectStatus "@baseboard_fab2_lib.baseboard_fab2(sch_1):page200_i229" )
			)
			( gate "R6W2"
				( objectStatus "@baseboard_fab2_lib.baseboard_fab2(sch_1):page200_i230" )
			)
			( gate "C6W10"
				( objectStatus "@baseboard_fab2_lib.baseboard_fab2(sch_1):page176_i124" )
			)
			( gate "R6W7"
				( objectStatus "@baseboard_fab2_lib.baseboard_fab2(sch_1):page247_i3" )
			)
			( gate "R6W4"
				( objectStatus "@baseboard_fab2_lib.baseboard_fab2(sch_1):page247_i5" )
			)
			( gate "R6W8"
				( objectStatus "@baseboard_fab2_lib.baseboard_fab2(sch_1):page247_i8" )
			)
			( gate "R6W9"
				( objectStatus "@baseboard_fab2_lib.baseboard_fab2(sch_1):page247_i9" )
			)
			( gate "R6W5"
				( objectStatus "@baseboard_fab2_lib.baseboard_fab2(sch_1):page247_i10" )
			)
			( gate "R6W6"
				( objectStatus "@baseboard_fab2_lib.baseboard_fab2(sch_1):page247_i11" )
			)
			( gate "R25W63"
				( objectStatus "@baseboard_fab2_lib.baseboard_fab2(sch_1):page146_i65" )
			)
			( gate "C6W1"
				( objectStatus "@baseboard_fab2_lib.baseboard_fab2(sch_1):page247_i18" )
			)
			( gate "Q6W2"
				( objectStatus "@baseboard_fab2_lib.baseboard_fab2(sch_1):page168_i30" )
			)
			( gate "R6W14"
				( objectStatus "@baseboard_fab2_lib.baseboard_fab2(sch_1):page168_i33" )
			)
			( gate "R6W13"
				( objectStatus "@baseboard_fab2_lib.baseboard_fab2(sch_1):page168_i34" )
			)
			( gate "Q6W3"
				( objectStatus "@baseboard_fab2_lib.baseboard_fab2(sch_1):page168_i37" )
			)
			( gate "R6W16"
				( objectStatus "@baseboard_fab2_lib.baseboard_fab2(sch_1):page168_i39" )
			)
			( gate "R6W15"
				( objectStatus "@baseboard_fab2_lib.baseboard_fab2(sch_1):page168_i40" )
			)
			( gate "R9W31"
				( objectStatus "@baseboard_fab2_lib.baseboard_fab2(sch_1):page239_i99" )
			)
			( gate "R3W1"
				( objectStatus "@baseboard_fab2_lib.baseboard_fab2(sch_1):page249_i2" )
			)
			( gate "R3W9"
				( objectStatus "@baseboard_fab2_lib.baseboard_fab2(sch_1):page249_i7" )
			)
			( gate "R3W7"
				( objectStatus "@baseboard_fab2_lib.baseboard_fab2(sch_1):page249_i8" )
			)
			( gate "R3W2"
				( objectStatus "@baseboard_fab2_lib.baseboard_fab2(sch_1):page249_i12" )
			)
			( gate "R3W4"
				( objectStatus "@baseboard_fab2_lib.baseboard_fab2(sch_1):page249_i31" )
			)
			( gate "Q9W4"
				( objectStatus "@baseboard_fab2_lib.baseboard_fab2(sch_1):page249_i15" )
			)
			( gate "R3W3"
				( objectStatus "@baseboard_fab2_lib.baseboard_fab2(sch_1):page249_i17" )
			)
			( gate "C8W2"
				( objectStatus "@baseboard_fab2_lib.baseboard_fab2(sch_1):page249_i21" )
			)
			( gate "Q9W3"
				( objectStatus "@baseboard_fab2_lib.baseboard_fab2(sch_1):page249_i26" )
			)
			( gate "R3W6"
				( objectStatus "@baseboard_fab2_lib.baseboard_fab2(sch_1):page249_i27" )
			)
			( gate "Q9W2"
				( objectStatus "@baseboard_fab2_lib.baseboard_fab2(sch_1):page249_i29" )
			)
			( gate "R6W3"
				( objectStatus "@baseboard_fab2_lib.baseboard_fab2(sch_1):page200_i239" )
			)
			( gate "C25W41"
				( objectStatus "@baseboard_fab2_lib.baseboard_fab2(sch_1):page150_i81" )
			)
			( gate "C25W42"
				( objectStatus "@baseboard_fab2_lib.baseboard_fab2(sch_1):page150_i80" )
			)
			( gate "C25W31"
				( objectStatus "@baseboard_fab2_lib.baseboard_fab2(sch_1):page150_i79" )
			)
			( gate "C25W32"
				( objectStatus "@baseboard_fab2_lib.baseboard_fab2(sch_1):page150_i78" )
			)
			( gate "R25W35"
				( objectStatus "@baseboard_fab2_lib.baseboard_fab2(sch_1):page149_i194" )
			)
			( gate "R25W67"
				( objectStatus "@baseboard_fab2_lib.baseboard_fab2(sch_1):page145_i46" )
			)
			( gate "C25W20"
				( objectStatus "@baseboard_fab2_lib.baseboard_fab2(sch_1):page145_i45" )
			)
			( gate "C25W21"
				( objectStatus "@baseboard_fab2_lib.baseboard_fab2(sch_1):page145_i44" )
			)
			( gate "R25W65"
				( objectStatus "@baseboard_fab2_lib.baseboard_fab2(sch_1):page145_i38" )
			)
			( gate "R25W64"
				( objectStatus "@baseboard_fab2_lib.baseboard_fab2(sch_1):page145_i36" )
			)
			( gate "R25W34"
				( objectStatus "@baseboard_fab2_lib.baseboard_fab2(sch_1):page149_i193" )
			)
			( gate "R25W33"
				( objectStatus "@baseboard_fab2_lib.baseboard_fab2(sch_1):page149_i192" )
			)
			( gate "R25W32"
				( objectStatus "@baseboard_fab2_lib.baseboard_fab2(sch_1):page149_i191" )
			)
			( gate "C9F23"
				( objectStatus "@baseboard_fab2_lib.baseboard_fab2(sch_1):page145_i15" )
			)
			( gate "R9F33"
				( objectStatus "@baseboard_fab2_lib.baseboard_fab2(sch_1):page145_i20" )
			)
			( gate "R9F34"
				( objectStatus "@baseboard_fab2_lib.baseboard_fab2(sch_1):page149_i14" )
			)
			( gate "R1U52"
				( objectStatus "@baseboard_fab2_lib.baseboard_fab2(sch_1):page146_i51" )
			)
			( gate "R25W58"
				( objectStatus "@baseboard_fab2_lib.baseboard_fab2(sch_1):page144_i73" )
			)
			( gate "C25W7"
				( objectStatus "@baseboard_fab2_lib.baseboard_fab2(sch_1):page147_i36" )
			)
			( gate "R25W61"
				( objectStatus "@baseboard_fab2_lib.baseboard_fab2(sch_1):page145_i30" )
			)
			( gate "R25W62"
				( objectStatus "@baseboard_fab2_lib.baseboard_fab2(sch_1):page145_i31" )
			)
			( gate "C25W30"
				( objectStatus "@baseboard_fab2_lib.baseboard_fab2(sch_1):page150_i43" )
			)
			( gate "FB2T7"
				( objectStatus "@baseboard_fab2_lib.baseboard_fab2(sch_1):page150_i39" )
			)
			( gate "C25W48"
				( objectStatus "@baseboard_fab2_lib.baseboard_fab2(sch_1):page150_i38" )
			)
			( gate "C25W49"
				( objectStatus "@baseboard_fab2_lib.baseboard_fab2(sch_1):page150_i36" )
			)
			( gate "C25W37"
				( objectStatus "@baseboard_fab2_lib.baseboard_fab2(sch_1):page150_i35" )
			)
			( gate "C25W66"
				( objectStatus "@baseboard_fab2_lib.baseboard_fab2(sch_1):page150_i33" )
			)
			( gate "FB2T1"
				( objectStatus "@baseboard_fab2_lib.baseboard_fab2(sch_1):page150_i32" )
			)
			( gate "R25W94"
				( objectStatus "@baseboard_fab2_lib.baseboard_fab2(sch_1):page151_i9" )
			)
			( gate "C25W67"
				( objectStatus "@baseboard_fab2_lib.baseboard_fab2(sch_1):page150_i31" )
			)
			( gate "C25W68"
				( objectStatus "@baseboard_fab2_lib.baseboard_fab2(sch_1):page150_i30" )
			)
			( gate "R25W96"
				( objectStatus "@baseboard_fab2_lib.baseboard_fab2(sch_1):page151_i10" )
			)
			( gate "C25W69"
				( objectStatus "@baseboard_fab2_lib.baseboard_fab2(sch_1):page150_i28" )
			)
			( gate "FB2T6"
				( objectStatus "@baseboard_fab2_lib.baseboard_fab2(sch_1):page150_i26" )
			)
			( gate "C25W63"
				( objectStatus "@baseboard_fab2_lib.baseboard_fab2(sch_1):page150_i25" )
			)
			( gate "C25W64"
				( objectStatus "@baseboard_fab2_lib.baseboard_fab2(sch_1):page150_i24" )
			)
			( gate "C25W50"
				( objectStatus "@baseboard_fab2_lib.baseboard_fab2(sch_1):page150_i21" )
			)
			( gate "C25W51"
				( objectStatus "@baseboard_fab2_lib.baseboard_fab2(sch_1):page150_i19" )
			)
			( gate "C25W38"
				( objectStatus "@baseboard_fab2_lib.baseboard_fab2(sch_1):page150_i18" )
			)
			( gate "C25W39"
				( objectStatus "@baseboard_fab2_lib.baseboard_fab2(sch_1):page150_i17" )
			)
			( gate "C25W52"
				( objectStatus "@baseboard_fab2_lib.baseboard_fab2(sch_1):page150_i14" )
			)
			( gate "C25W53"
				( objectStatus "@baseboard_fab2_lib.baseboard_fab2(sch_1):page150_i13" )
			)
			( gate "C25W54"
				( objectStatus "@baseboard_fab2_lib.baseboard_fab2(sch_1):page150_i12" )
			)
			( gate "C25W55"
				( objectStatus "@baseboard_fab2_lib.baseboard_fab2(sch_1):page150_i10" )
			)
			( gate "R25W120"
				( objectStatus "@baseboard_fab2_lib.baseboard_fab2(sch_1):page150_i7" )
			)
			( gate "C25W70"
				( objectStatus "@baseboard_fab2_lib.baseboard_fab2(sch_1):page150_i6" )
			)
			( gate "R25W116"
				( objectStatus "@baseboard_fab2_lib.baseboard_fab2(sch_1):page151_i48" )
			)
			( gate "R25W115"
				( objectStatus "@baseboard_fab2_lib.baseboard_fab2(sch_1):page151_i47" )
			)
			( gate "R25W114"
				( objectStatus "@baseboard_fab2_lib.baseboard_fab2(sch_1):page151_i46" )
			)
			( gate "R25W113"
				( objectStatus "@baseboard_fab2_lib.baseboard_fab2(sch_1):page151_i45" )
			)
			( gate "R25W112"
				( objectStatus "@baseboard_fab2_lib.baseboard_fab2(sch_1):page151_i44" )
			)
			( gate "R25W111"
				( objectStatus "@baseboard_fab2_lib.baseboard_fab2(sch_1):page151_i43" )
			)
			( gate "R25W110"
				( objectStatus "@baseboard_fab2_lib.baseboard_fab2(sch_1):page151_i36" )
			)
			( gate "R25W109"
				( objectStatus "@baseboard_fab2_lib.baseboard_fab2(sch_1):page151_i35" )
			)
			( gate "R25W108"
				( objectStatus "@baseboard_fab2_lib.baseboard_fab2(sch_1):page151_i34" )
			)
			( gate "R25W107"
				( objectStatus "@baseboard_fab2_lib.baseboard_fab2(sch_1):page151_i33" )
			)
			( gate "R25W106"
				( objectStatus "@baseboard_fab2_lib.baseboard_fab2(sch_1):page151_i32" )
			)
			( gate "R25W105"
				( objectStatus "@baseboard_fab2_lib.baseboard_fab2(sch_1):page151_i31" )
			)
			( gate "R25W104"
				( objectStatus "@baseboard_fab2_lib.baseboard_fab2(sch_1):page151_i30" )
			)
			( gate "R25W103"
				( objectStatus "@baseboard_fab2_lib.baseboard_fab2(sch_1):page151_i29" )
			)
			( gate "R25W102"
				( objectStatus "@baseboard_fab2_lib.baseboard_fab2(sch_1):page151_i28" )
			)
			( gate "R25W101"
				( objectStatus "@baseboard_fab2_lib.baseboard_fab2(sch_1):page151_i27" )
			)
			( gate "R25W99"
				( objectStatus "@baseboard_fab2_lib.baseboard_fab2(sch_1):page151_i14" )
			)
			( gate "FB2T5"
				( objectStatus "@baseboard_fab2_lib.baseboard_fab2(sch_1):page150_i89" )
			)
			( gate "C25W56"
				( objectStatus "@baseboard_fab2_lib.baseboard_fab2(sch_1):page150_i87" )
			)
			( gate "C25W57"
				( objectStatus "@baseboard_fab2_lib.baseboard_fab2(sch_1):page150_i86" )
			)
			( gate "C25W58"
				( objectStatus "@baseboard_fab2_lib.baseboard_fab2(sch_1):page150_i85" )
			)
			( gate "FB2T4"
				( objectStatus "@baseboard_fab2_lib.baseboard_fab2(sch_1):page150_i84" )
			)
			( gate "R6W19"
				( objectStatus "@baseboard_fab2_lib.baseboard_fab2(sch_1):page155_i196" )
			)
			( gate "R25W82"
				( objectStatus "@baseboard_fab2_lib.baseboard_fab2(sch_1):page146_i68" )
			)
			( gate "U25W5"
				( objectStatus "@baseboard_fab2_lib.baseboard_fab2(sch_1):page149_i1" )
			)
			( gate "EU25F2"
				( objectStatus "@baseboard_fab2_lib.baseboard_fab2(sch_1):page239_i73" )
			)
			( gate "R1W9"
				( objectStatus "@baseboard_fab2_lib.baseboard_fab2(sch_1):page239_i77" )
			)
			( gate "R9W12"
				( objectStatus "@baseboard_fab2_lib.baseboard_fab2(sch_1):page239_i79" )
			)
			( gate "C9W13"
				( objectStatus "@baseboard_fab2_lib.baseboard_fab2(sch_1):page239_i81" )
			)
			( gate "C1W15"
				( objectStatus "@baseboard_fab2_lib.baseboard_fab2(sch_1):page239_i83" )
			)
			( gate "C9W10"
				( objectStatus "@baseboard_fab2_lib.baseboard_fab2(sch_1):page239_i84" )
			)
			( gate "R9W32"
				( objectStatus "@baseboard_fab2_lib.baseboard_fab2(sch_1):page239_i87" )
			)
			( gate "C9W5"
				( objectStatus "@baseboard_fab2_lib.baseboard_fab2(sch_1):page239_i90" )
			)
			( gate "C9W6"
				( objectStatus "@baseboard_fab2_lib.baseboard_fab2(sch_1):page239_i91" )
			)
			( gate "C1W7"
				( objectStatus "@baseboard_fab2_lib.baseboard_fab2(sch_1):page239_i92" )
			)
			( gate "C25W22"
				( objectStatus "@baseboard_fab2_lib.baseboard_fab2(sch_1):page143_i55" )
			)
			( gate "U25W4"
				( objectStatus "@baseboard_fab2_lib.baseboard_fab2(sch_1):page144_i95" )
			)
			( gate "Q9W1"
				( objectStatus "@baseboard_fab2_lib.baseboard_fab2(sch_1):page249_i30" )
			)
			( gate "R25W93"
				( objectStatus "@baseboard_fab2_lib.baseboard_fab2(sch_1):page150_i57" )
			)
			( gate "C25W33"
				( objectStatus "@baseboard_fab2_lib.baseboard_fab2(sch_1):page150_i59" )
			)
			( gate "C25W45"
				( objectStatus "@baseboard_fab2_lib.baseboard_fab2(sch_1):page150_i61" )
			)
			( gate "U25W4"
				( objectStatus "@baseboard_fab2_lib.baseboard_fab2(sch_1):page146_i104" )
			)
			( gate "C25W44"
				( objectStatus "@baseboard_fab2_lib.baseboard_fab2(sch_1):page150_i62" )
			)
			( gate "C25W43"
				( objectStatus "@baseboard_fab2_lib.baseboard_fab2(sch_1):page150_i63" )
			)
			( gate "C25W62"
				( objectStatus "@baseboard_fab2_lib.baseboard_fab2(sch_1):page150_i65" )
			)
			( gate "C9W1"
				( objectStatus "@baseboard_fab2_lib.baseboard_fab2(sch_1):page200_i235" )
			)
			( gate "C9W2"
				( objectStatus "@baseboard_fab2_lib.baseboard_fab2(sch_1):page200_i236" )
			)
			( gate "R1L45"
				( objectStatus "@baseboard_fab2_lib.baseboard_fab2(sch_1):page175_i89" )
			)
			( gate "R9T8"
				( objectStatus "@baseboard_fab2_lib.baseboard_fab2(sch_1):page181_i278" )
			)
			( gate "R25W81"
				( objectStatus "@baseboard_fab2_lib.baseboard_fab2(sch_1):page146_i67" )
			)
			( gate "R25W100"
				( objectStatus "@baseboard_fab2_lib.baseboard_fab2(sch_1):page151_i13" )
			)
			( gate "R25W98"
				( objectStatus "@baseboard_fab2_lib.baseboard_fab2(sch_1):page151_i12" )
			)
			( gate "R25W97"
				( objectStatus "@baseboard_fab2_lib.baseboard_fab2(sch_1):page151_i11" )
			)
			( gate "R25W95"
				( objectStatus "@baseboard_fab2_lib.baseboard_fab2(sch_1):page151_i2" )
			)
			( gate "RT1"
				( objectStatus "@baseboard_fab2_lib.baseboard_fab2(sch_1):page202_i88" )
			)
			( gate "RT5"
				( objectStatus "@baseboard_fab2_lib.baseboard_fab2(sch_1):page227_i126" )
			)
			( gate "RT8"
				( objectStatus "@baseboard_fab2_lib.baseboard_fab2(sch_1):page227_i127" )
			)
			( gate "RT9"
				( objectStatus "@baseboard_fab2_lib.baseboard_fab2(sch_1):page209_i69" )
			)
			( gate "RT14"
				( objectStatus "@baseboard_fab2_lib.baseboard_fab2(sch_1):page208_i97" )
			)
			( gate "RT15"
				( objectStatus "@baseboard_fab2_lib.baseboard_fab2(sch_1):page207_i87" )
			)
			( gate "RT17"
				( objectStatus "@baseboard_fab2_lib.baseboard_fab2(sch_1):page207_i88" )
			)
			( gate "RT19"
				( objectStatus "@baseboard_fab2_lib.baseboard_fab2(sch_1):page224_i132" )
			)
			( gate "RT21"
				( objectStatus "@baseboard_fab2_lib.baseboard_fab2(sch_1):page224_i133" )
			)
			( gate "RT23"
				( objectStatus "@baseboard_fab2_lib.baseboard_fab2(sch_1):page204_i93" )
			)
			( gate "RT28"
				( objectStatus "@baseboard_fab2_lib.baseboard_fab2(sch_1):page203_i111" )
			)
			( gate "R9F64"
				( objectStatus "@baseboard_fab2_lib.baseboard_fab2(sch_1):page181_i281" )
			)
			( gate "R9F63"
				( objectStatus "@baseboard_fab2_lib.baseboard_fab2(sch_1):page181_i282" )
			)
			( gate "R9F66"
				( objectStatus "@baseboard_fab2_lib.baseboard_fab2(sch_1):page158_i152" )
			)
			( gate "C25W2"
				( objectStatus "@baseboard_fab2_lib.baseboard_fab2(sch_1):page149_i72" )
			)
			( gate "R1U13"
				( objectStatus "@baseboard_fab2_lib.baseboard_fab2(sch_1):page144_i58" )
			)
			( gate "R1U14"
				( objectStatus "@baseboard_fab2_lib.baseboard_fab2(sch_1):page144_i57" )
			)
			( gate "U25W4"
				( objectStatus "@baseboard_fab2_lib.baseboard_fab2(sch_1):page148_i28" )
			)
			( gate "C25W3"
				( objectStatus "@baseboard_fab2_lib.baseboard_fab2(sch_1):page149_i73" )
			)
			( gate "C25W4"
				( objectStatus "@baseboard_fab2_lib.baseboard_fab2(sch_1):page149_i74" )
			)
			( gate "C1T21"
				( objectStatus "@baseboard_fab2_lib.baseboard_fab2(sch_1):page148_i20" )
			)
			( gate "R1U12"
				( objectStatus "@baseboard_fab2_lib.baseboard_fab2(sch_1):page144_i59" )
			)
			( gate "R25W59"
				( objectStatus "@baseboard_fab2_lib.baseboard_fab2(sch_1):page148_i16" )
			)
			( gate "R1U2"
				( objectStatus "@baseboard_fab2_lib.baseboard_fab2(sch_1):page147_i62" )
			)
			( gate "R25W60"
				( objectStatus "@baseboard_fab2_lib.baseboard_fab2(sch_1):page145_i34" )
			)
			( gate "U25W4"
				( objectStatus "@baseboard_fab2_lib.baseboard_fab2(sch_1):page147_i106" )
			)
			( gate "R1U1"
				( objectStatus "@baseboard_fab2_lib.baseboard_fab2(sch_1):page147_i61" )
			)
			( gate "R1T26"
				( objectStatus "@baseboard_fab2_lib.baseboard_fab2(sch_1):page146_i37" )
			)
			( gate "R1T25"
				( objectStatus "@baseboard_fab2_lib.baseboard_fab2(sch_1):page146_i35" )
			)
			( gate "R25W84"
				( objectStatus "@baseboard_fab2_lib.baseboard_fab2(sch_1):page146_i27" )
			)
			( gate "R25W83"
				( objectStatus "@baseboard_fab2_lib.baseboard_fab2(sch_1):page146_i26" )
			)
			( gate "R25W75"
				( objectStatus "@baseboard_fab2_lib.baseboard_fab2(sch_1):page148_i23" )
			)
			( gate "R25W90"
				( objectStatus "@baseboard_fab2_lib.baseboard_fab2(sch_1):page147_i21" )
			)
			( gate "C25W26"
				( objectStatus "@baseboard_fab2_lib.baseboard_fab2(sch_1):page150_i71" )
			)
			( gate "C25W59"
				( objectStatus "@baseboard_fab2_lib.baseboard_fab2(sch_1):page150_i69" )
			)
			( gate "C25W61"
				( objectStatus "@baseboard_fab2_lib.baseboard_fab2(sch_1):page150_i67" )
			)
			( gate "C25W60"
				( objectStatus "@baseboard_fab2_lib.baseboard_fab2(sch_1):page150_i1" )
			)
			( gate "U9F3"
				( objectStatus "@baseboard_fab2_lib.baseboard_fab2(sch_1):page149_i34" )
			)
			( gate "C25W16"
				( objectStatus "@baseboard_fab2_lib.baseboard_fab2(sch_1):page149_i37" )
			)
			( gate "C25W17"
				( objectStatus "@baseboard_fab2_lib.baseboard_fab2(sch_1):page149_i38" )
			)
			( gate "C25W15"
				( objectStatus "@baseboard_fab2_lib.baseboard_fab2(sch_1):page149_i39" )
			)
			( gate "C25W65"
				( objectStatus "@baseboard_fab2_lib.baseboard_fab2(sch_1):page150_i2" )
			)
			( gate "C25W71"
				( objectStatus "@baseboard_fab2_lib.baseboard_fab2(sch_1):page150_i4" )
			)
			( gate "R9F61"
				( objectStatus "@baseboard_fab2_lib.baseboard_fab2(sch_1):page145_i14" )
			)
			( gate "R9F62"
				( objectStatus "@baseboard_fab2_lib.baseboard_fab2(sch_1):page145_i11" )
			)
			( gate "R9F60"
				( objectStatus "@baseboard_fab2_lib.baseboard_fab2(sch_1):page145_i10" )
			)
			( gate "C25W25"
				( objectStatus "@baseboard_fab2_lib.baseboard_fab2(sch_1):page150_i72" )
			)
			( gate "Y9F2"
				( objectStatus "@baseboard_fab2_lib.baseboard_fab2(sch_1):page145_i8" )
			)
			( gate "R9F29"
				( objectStatus "@baseboard_fab2_lib.baseboard_fab2(sch_1):page149_i16" )
			)
			( gate "R25W42"
				( objectStatus "@baseboard_fab2_lib.baseboard_fab2(sch_1):page149_i201" )
			)
			( gate "R25W43"
				( objectStatus "@baseboard_fab2_lib.baseboard_fab2(sch_1):page149_i202" )
			)
			( gate "R25W44"
				( objectStatus "@baseboard_fab2_lib.baseboard_fab2(sch_1):page149_i203" )
			)
			( gate "R25W45"
				( objectStatus "@baseboard_fab2_lib.baseboard_fab2(sch_1):page149_i204" )
			)
			( gate "R25W46"
				( objectStatus "@baseboard_fab2_lib.baseboard_fab2(sch_1):page149_i205" )
			)
			( gate "R25W47"
				( objectStatus "@baseboard_fab2_lib.baseboard_fab2(sch_1):page149_i206" )
			)
			( gate "R25W48"
				( objectStatus "@baseboard_fab2_lib.baseboard_fab2(sch_1):page149_i207" )
			)
			( gate "R25W49"
				( objectStatus "@baseboard_fab2_lib.baseboard_fab2(sch_1):page149_i208" )
			)
			( gate "R25W50"
				( objectStatus "@baseboard_fab2_lib.baseboard_fab2(sch_1):page149_i209" )
			)
			( gate "R25W51"
				( objectStatus "@baseboard_fab2_lib.baseboard_fab2(sch_1):page149_i210" )
			)
			( gate "R25W2"
				( objectStatus "@baseboard_fab2_lib.baseboard_fab2(sch_1):page149_i161" )
			)
			( gate "C25W12"
				( objectStatus "@baseboard_fab2_lib.baseboard_fab2(sch_1):page149_i126" )
			)
			( gate "R1T29"
				( objectStatus "@baseboard_fab2_lib.baseboard_fab2(sch_1):page149_i125" )
			)
			( gate "R1T30"
				( objectStatus "@baseboard_fab2_lib.baseboard_fab2(sch_1):page149_i124" )
			)
			( gate "R25W118"
				( objectStatus "@baseboard_fab2_lib.baseboard_fab2(sch_1):page149_i122" )
			)
			( gate "R25W119"
				( objectStatus "@baseboard_fab2_lib.baseboard_fab2(sch_1):page149_i120" )
			)
			( gate "Q9E1"
				( objectStatus "@baseboard_fab2_lib.baseboard_fab2(sch_1):page149_i113" )
			)
			( gate "R9E21"
				( objectStatus "@baseboard_fab2_lib.baseboard_fab2(sch_1):page149_i111" )
			)
			( gate "Q9E1"
				( objectStatus "@baseboard_fab2_lib.baseboard_fab2(sch_1):page149_i109" )
			)
			( gate "R1T28"
				( objectStatus "@baseboard_fab2_lib.baseboard_fab2(sch_1):page149_i212" )
			)
			( gate "R2T41"
				( objectStatus "@baseboard_fab2_lib.baseboard_fab2(sch_1):page146_i96" )
			)
			( gate "DS9E1"
				( objectStatus "@baseboard_fab2_lib.baseboard_fab2(sch_1):page149_i98" )
			)
			( gate "C25W6"
				( objectStatus "@baseboard_fab2_lib.baseboard_fab2(sch_1):page149_i97" )
			)
			( gate "C25W5"
				( objectStatus "@baseboard_fab2_lib.baseboard_fab2(sch_1):page149_i96" )
			)
			( gate "R9E24"
				( objectStatus "@baseboard_fab2_lib.baseboard_fab2(sch_1):page149_i94" )
			)
			( gate "R1U5"
				( objectStatus "@baseboard_fab2_lib.baseboard_fab2(sch_1):page147_i66" )
			)
			( gate "R1U4"
				( objectStatus "@baseboard_fab2_lib.baseboard_fab2(sch_1):page147_i65" )
			)
			( gate "R25W80"
				( objectStatus "@baseboard_fab2_lib.baseboard_fab2(sch_1):page147_i43" )
			)
			( gate "R25W79"
				( objectStatus "@baseboard_fab2_lib.baseboard_fab2(sch_1):page147_i42" )
			)
			( gate "R25W57"
				( objectStatus "@baseboard_fab2_lib.baseboard_fab2(sch_1):page147_i40" )
			)
			( gate "C25W9"
				( objectStatus "@baseboard_fab2_lib.baseboard_fab2(sch_1):page147_i39" )
			)
			( gate "C25W8"
				( objectStatus "@baseboard_fab2_lib.baseboard_fab2(sch_1):page147_i38" )
			)
			( gate "R25W87"
				( objectStatus "@baseboard_fab2_lib.baseboard_fab2(sch_1):page147_i25" )
			)
			( gate "R25W86"
				( objectStatus "@baseboard_fab2_lib.baseboard_fab2(sch_1):page147_i24" )
			)
			( gate "R25W85"
				( objectStatus "@baseboard_fab2_lib.baseboard_fab2(sch_1):page147_i23" )
			)
			( gate "R25W89"
				( objectStatus "@baseboard_fab2_lib.baseboard_fab2(sch_1):page147_i22" )
			)
			( gate "R25W88"
				( objectStatus "@baseboard_fab2_lib.baseboard_fab2(sch_1):page147_i8" )
			)
			( gate "R25W91"
				( objectStatus "@baseboard_fab2_lib.baseboard_fab2(sch_1):page147_i4" )
			)
			( gate "R25W92"
				( objectStatus "@baseboard_fab2_lib.baseboard_fab2(sch_1):page147_i3" )
			)
			( gate "R25W69"
				( objectStatus "@baseboard_fab2_lib.baseboard_fab2(sch_1):page146_i85" )
			)
			( gate "R25W68"
				( objectStatus "@baseboard_fab2_lib.baseboard_fab2(sch_1):page146_i84" )
			)
			( gate "R1U7"
				( objectStatus "@baseboard_fab2_lib.baseboard_fab2(sch_1):page146_i78" )
			)
			( gate "R25W66"
				( objectStatus "@baseboard_fab2_lib.baseboard_fab2(sch_1):page146_i76" )
			)
			( gate "R3N26"
				( objectStatus "@baseboard_fab2_lib.baseboard_fab2(sch_1):page146_i75" )
			)
			( gate "R3N24"
				( objectStatus "@baseboard_fab2_lib.baseboard_fab2(sch_1):page146_i74" )
			)
			( gate "R25W73"
				( objectStatus "@baseboard_fab2_lib.baseboard_fab2(sch_1):page146_i73" )
			)
			( gate "R25W71"
				( objectStatus "@baseboard_fab2_lib.baseboard_fab2(sch_1):page146_i72" )
			)
			( gate "R25W72"
				( objectStatus "@baseboard_fab2_lib.baseboard_fab2(sch_1):page146_i71" )
			)
			( gate "R25W74"
				( objectStatus "@baseboard_fab2_lib.baseboard_fab2(sch_1):page146_i70" )
			)
			( gate "R25W78"
				( objectStatus "@baseboard_fab2_lib.baseboard_fab2(sch_1):page146_i69" )
			)
			( gate "R25W1"
				( objectStatus "@baseboard_fab2_lib.baseboard_fab2(sch_1):page149_i160" )
			)
			( gate "R25W4"
				( objectStatus "@baseboard_fab2_lib.baseboard_fab2(sch_1):page149_i162" )
			)
			( gate "R25W3"
				( objectStatus "@baseboard_fab2_lib.baseboard_fab2(sch_1):page149_i163" )
			)
			( gate "R25W5"
				( objectStatus "@baseboard_fab2_lib.baseboard_fab2(sch_1):page149_i164" )
			)
			( gate "R25W6"
				( objectStatus "@baseboard_fab2_lib.baseboard_fab2(sch_1):page149_i165" )
			)
			( gate "R25W7"
				( objectStatus "@baseboard_fab2_lib.baseboard_fab2(sch_1):page149_i166" )
			)
			( gate "R25W8"
				( objectStatus "@baseboard_fab2_lib.baseboard_fab2(sch_1):page149_i167" )
			)
			( gate "R25W9"
				( objectStatus "@baseboard_fab2_lib.baseboard_fab2(sch_1):page149_i168" )
			)
			( gate "R25W10"
				( objectStatus "@baseboard_fab2_lib.baseboard_fab2(sch_1):page149_i169" )
			)
			( gate "R25W12"
				( objectStatus "@baseboard_fab2_lib.baseboard_fab2(sch_1):page149_i170" )
			)
			( gate "R25W11"
				( objectStatus "@baseboard_fab2_lib.baseboard_fab2(sch_1):page149_i171" )
			)
			( gate "R25W13"
				( objectStatus "@baseboard_fab2_lib.baseboard_fab2(sch_1):page149_i172" )
			)
			( gate "R25W16"
				( objectStatus "@baseboard_fab2_lib.baseboard_fab2(sch_1):page149_i173" )
			)
			( gate "R25W15"
				( objectStatus "@baseboard_fab2_lib.baseboard_fab2(sch_1):page149_i174" )
			)
			( gate "R25W14"
				( objectStatus "@baseboard_fab2_lib.baseboard_fab2(sch_1):page149_i175" )
			)
			( gate "R25W22"
				( objectStatus "@baseboard_fab2_lib.baseboard_fab2(sch_1):page149_i176" )
			)
			( gate "R25W23"
				( objectStatus "@baseboard_fab2_lib.baseboard_fab2(sch_1):page149_i177" )
			)
			( gate "R25W24"
				( objectStatus "@baseboard_fab2_lib.baseboard_fab2(sch_1):page149_i178" )
			)
			( gate "R25W25"
				( objectStatus "@baseboard_fab2_lib.baseboard_fab2(sch_1):page149_i179" )
			)
			( gate "R25W26"
				( objectStatus "@baseboard_fab2_lib.baseboard_fab2(sch_1):page149_i180" )
			)
			( gate "R25W17"
				( objectStatus "@baseboard_fab2_lib.baseboard_fab2(sch_1):page149_i181" )
			)
			( gate "R25W18"
				( objectStatus "@baseboard_fab2_lib.baseboard_fab2(sch_1):page149_i182" )
			)
			( gate "R25W19"
				( objectStatus "@baseboard_fab2_lib.baseboard_fab2(sch_1):page149_i183" )
			)
			( gate "R25W20"
				( objectStatus "@baseboard_fab2_lib.baseboard_fab2(sch_1):page149_i184" )
			)
			( gate "R25W21"
				( objectStatus "@baseboard_fab2_lib.baseboard_fab2(sch_1):page149_i185" )
			)
			( gate "R25W52"
				( objectStatus "@baseboard_fab2_lib.baseboard_fab2(sch_1):page149_i211" )
			)
			( gate "R2N13"
				( objectStatus "@baseboard_fab2_lib.baseboard_fab2(sch_1):page147_i75" )
			)
			( gate "R1T24"
				( objectStatus "@baseboard_fab2_lib.baseboard_fab2(sch_1):page144_i82" )
			)
			( gate "R1T15"
				( objectStatus "@baseboard_fab2_lib.baseboard_fab2(sch_1):page145_i100" )
			)
			( gate "R1T23"
				( objectStatus "@baseboard_fab2_lib.baseboard_fab2(sch_1):page145_i101" )
			)
			( gate "C6W2"
				( objectStatus "@baseboard_fab2_lib.baseboard_fab2(sch_1):page247_i81" )
			)
			( gate "U6W2"
				( objectStatus "@baseboard_fab2_lib.baseboard_fab2(sch_1):page247_i77" )
			)
			( gate "C6W3"
				( objectStatus "@baseboard_fab2_lib.baseboard_fab2(sch_1):page247_i85" )
			)
			( gate "R6W20"
				( objectStatus "@baseboard_fab2_lib.baseboard_fab2(sch_1):page247_i87" )
			)
			( gate "U6W3"
				( objectStatus "@baseboard_fab2_lib.baseboard_fab2(sch_1):page247_i89" )
			)
			( gate "R6W21"
				( objectStatus "@baseboard_fab2_lib.baseboard_fab2(sch_1):page247_i90" )
			)
			( gate "R6W23"
				( objectStatus "@baseboard_fab2_lib.baseboard_fab2(sch_1):page247_i92" )
			)
			( gate "R6W22"
				( objectStatus "@baseboard_fab2_lib.baseboard_fab2(sch_1):page247_i94" )
			)
			( gate "U25W4"
				( objectStatus "@baseboard_fab2_lib.baseboard_fab2(sch_1):page143_i63" )
			)
			( gate "U25W4"
				( objectStatus "@baseboard_fab2_lib.baseboard_fab2(sch_1):page146_i105" )
			)
			( gate "U6W1"
				( objectStatus "@baseboard_fab2_lib.baseboard_fab2(sch_1):page247_i97" )
			)
			( pin "R6N10.1"
				( objectStatus "@baseboard_fab2_lib.baseboard_fab2(sch_1):page21_i149:a" )
			)
			( pin "R6N10.2"
				( objectStatus "@baseboard_fab2_lib.baseboard_fab2(sch_1):page21_i149:b" )
			)
			( pin "R6N12.1"
				( objectStatus "@baseboard_fab2_lib.baseboard_fab2(sch_1):page21_i150:a" )
			)
			( pin "R6N12.2"
				( objectStatus "@baseboard_fab2_lib.baseboard_fab2(sch_1):page21_i150:b" )
			)
			( pin "R6N11.1"
				( objectStatus "@baseboard_fab2_lib.baseboard_fab2(sch_1):page21_i151:a" )
			)
			( pin "R6N11.2"
				( objectStatus "@baseboard_fab2_lib.baseboard_fab2(sch_1):page21_i151:b" )
			)
			( pin "R6B3.1"
				( objectStatus "@baseboard_fab2_lib.baseboard_fab2(sch_1):page21_i152:a" )
			)
			( pin "R6B3.2"
				( objectStatus "@baseboard_fab2_lib.baseboard_fab2(sch_1):page21_i152:b" )
			)
			( pin "R6B5.1"
				( objectStatus "@baseboard_fab2_lib.baseboard_fab2(sch_1):page21_i153:a" )
			)
			( pin "R6B5.2"
				( objectStatus "@baseboard_fab2_lib.baseboard_fab2(sch_1):page21_i153:b" )
			)
			( pin "R6B4.1"
				( objectStatus "@baseboard_fab2_lib.baseboard_fab2(sch_1):page21_i154:a" )
			)
			( pin "R6B4.2"
				( objectStatus "@baseboard_fab2_lib.baseboard_fab2(sch_1):page21_i154:b" )
			)
			( pin "R6B2.1"
				( objectStatus "@baseboard_fab2_lib.baseboard_fab2(sch_1):page21_i159:a" )
			)
			( pin "R6B2.2"
				( objectStatus "@baseboard_fab2_lib.baseboard_fab2(sch_1):page21_i159:b" )
			)
			( pin "R6B1.1"
				( objectStatus "@baseboard_fab2_lib.baseboard_fab2(sch_1):page21_i161:a" )
			)
			( pin "R6B1.2"
				( objectStatus "@baseboard_fab2_lib.baseboard_fab2(sch_1):page21_i161:b" )
			)
			( pin "R6N2.1"
				( objectStatus "@baseboard_fab2_lib.baseboard_fab2(sch_1):page21_i163:a" )
			)
			( pin "R6N2.2"
				( objectStatus "@baseboard_fab2_lib.baseboard_fab2(sch_1):page21_i163:b" )
			)
			( pin "R6N1.1"
				( objectStatus "@baseboard_fab2_lib.baseboard_fab2(sch_1):page21_i164:a" )
			)
			( pin "R6N1.2"
				( objectStatus "@baseboard_fab2_lib.baseboard_fab2(sch_1):page21_i164:b" )
			)
			( pin "R5D1.1"
				( objectStatus "@baseboard_fab2_lib.baseboard_fab2(sch_1):page21_i177:a" )
			)
			( pin "R5D1.2"
				( objectStatus "@baseboard_fab2_lib.baseboard_fab2(sch_1):page21_i177:b" )
			)
			( pin "R5D2.1"
				( objectStatus "@baseboard_fab2_lib.baseboard_fab2(sch_1):page21_i178:a" )
			)
			( pin "R5D2.2"
				( objectStatus "@baseboard_fab2_lib.baseboard_fab2(sch_1):page21_i178:b" )
			)
			( pin "R6D1.1"
				( objectStatus "@baseboard_fab2_lib.baseboard_fab2(sch_1):page21_i179:a" )
			)
			( pin "R6D1.2"
				( objectStatus "@baseboard_fab2_lib.baseboard_fab2(sch_1):page21_i179:b" )
			)
			( pin "R4P8.1"
				( objectStatus "@baseboard_fab2_lib.baseboard_fab2(sch_1):page21_i180:a" )
			)
			( pin "R4P8.2"
				( objectStatus "@baseboard_fab2_lib.baseboard_fab2(sch_1):page21_i180:b" )
			)
			( pin "R4P10.1"
				( objectStatus "@baseboard_fab2_lib.baseboard_fab2(sch_1):page21_i181:a" )
			)
			( pin "R4P10.2"
				( objectStatus "@baseboard_fab2_lib.baseboard_fab2(sch_1):page21_i181:b" )
			)
			( pin "R4P11.1"
				( objectStatus "@baseboard_fab2_lib.baseboard_fab2(sch_1):page21_i182:a" )
			)
			( pin "R4P11.2"
				( objectStatus "@baseboard_fab2_lib.baseboard_fab2(sch_1):page21_i182:b" )
			)
			( pin "R6D11.1"
				( objectStatus "@baseboard_fab2_lib.baseboard_fab2(sch_1):page21_i184:a" )
			)
			( pin "R6D11.2"
				( objectStatus "@baseboard_fab2_lib.baseboard_fab2(sch_1):page21_i184:b" )
			)
			( pin "R4P3.1"
				( objectStatus "@baseboard_fab2_lib.baseboard_fab2(sch_1):page21_i186:a" )
			)
			( pin "R4P3.2"
				( objectStatus "@baseboard_fab2_lib.baseboard_fab2(sch_1):page21_i186:b" )
			)
			( pin "R4P2.1"
				( objectStatus "@baseboard_fab2_lib.baseboard_fab2(sch_1):page21_i188:a" )
			)
			( pin "R4P2.2"
				( objectStatus "@baseboard_fab2_lib.baseboard_fab2(sch_1):page21_i188:b" )
			)
			( pin "R4P4.1"
				( objectStatus "@baseboard_fab2_lib.baseboard_fab2(sch_1):page21_i189:a" )
			)
			( pin "R4P4.2"
				( objectStatus "@baseboard_fab2_lib.baseboard_fab2(sch_1):page21_i189:b" )
			)
			( pin "R6D2.1"
				( objectStatus "@baseboard_fab2_lib.baseboard_fab2(sch_1):page21_i204:a" )
			)
			( pin "R6D2.2"
				( objectStatus "@baseboard_fab2_lib.baseboard_fab2(sch_1):page21_i204:b" )
			)
			( pin "R4P19.1"
				( objectStatus "@baseboard_fab2_lib.baseboard_fab2(sch_1):page21_i219:a" )
			)
			( pin "R4P19.2"
				( objectStatus "@baseboard_fab2_lib.baseboard_fab2(sch_1):page21_i219:b" )
			)
			( pin "R5N2.1"
				( objectStatus "@baseboard_fab2_lib.baseboard_fab2(sch_1):page21_i227:a" )
			)
			( pin "R5N2.2"
				( objectStatus "@baseboard_fab2_lib.baseboard_fab2(sch_1):page21_i227:b" )
			)
			( pin "R5N1.1"
				( objectStatus "@baseboard_fab2_lib.baseboard_fab2(sch_1):page21_i238:a" )
			)
			( pin "R5N1.2"
				( objectStatus "@baseboard_fab2_lib.baseboard_fab2(sch_1):page21_i238:b" )
			)
			( pin "R5N5.1"
				( objectStatus "@baseboard_fab2_lib.baseboard_fab2(sch_1):page21_i239:a" )
			)
			( pin "R5N5.2"
				( objectStatus "@baseboard_fab2_lib.baseboard_fab2(sch_1):page21_i239:b" )
			)
			( pin "R5N3.1"
				( objectStatus "@baseboard_fab2_lib.baseboard_fab2(sch_1):page21_i240:a" )
			)
			( pin "R5N3.2"
				( objectStatus "@baseboard_fab2_lib.baseboard_fab2(sch_1):page21_i240:b" )
			)
			( pin "R5N4.1"
				( objectStatus "@baseboard_fab2_lib.baseboard_fab2(sch_1):page21_i241:a" )
			)
			( pin "R5N4.2"
				( objectStatus "@baseboard_fab2_lib.baseboard_fab2(sch_1):page21_i241:b" )
			)
			( pin "R4P18.1"
				( objectStatus "@baseboard_fab2_lib.baseboard_fab2(sch_1):page21_i244:a" )
			)
			( pin "R4P18.2"
				( objectStatus "@baseboard_fab2_lib.baseboard_fab2(sch_1):page21_i244:b" )
			)
			( pin "R4R5.1"
				( objectStatus "@baseboard_fab2_lib.baseboard_fab2(sch_1):page21_i258:a" )
			)
			( pin "R4R5.2"
				( objectStatus "@baseboard_fab2_lib.baseboard_fab2(sch_1):page21_i258:b" )
			)
			( pin "U5D1.AU24"
				( objectStatus "@baseboard_fab2_lib.baseboard_fab2(sch_1):page21_i259:bclk0_dn" )
			)
			( pin "U5D1.AW24"
				( objectStatus "@baseboard_fab2_lib.baseboard_fab2(sch_1):page21_i259:bclk0_dp" )
			)
			( pin "U5D1.CR26"
				( objectStatus "@baseboard_fab2_lib.baseboard_fab2(sch_1):page21_i259:bclk1_dn" )
			)
			( pin "U5D1.CP27"
				( objectStatus "@baseboard_fab2_lib.baseboard_fab2(sch_1):page21_i259:bclk1_dp" )
			)
			( pin "U5D1.CT25"
				( objectStatus "@baseboard_fab2_lib.baseboard_fab2(sch_1):page21_i259:bclk2_dn" )
			)
			( pin "U5D1.CU26"
				( objectStatus "@baseboard_fab2_lib.baseboard_fab2(sch_1):page21_i259:bclk2_dp" )
			)
			( pin "U5D1.BA20"
				( objectStatus "@baseboard_fab2_lib.baseboard_fab2(sch_1):page21_i259:bist_enable" )
			)
			( pin "U5D1.BD23"
				( objectStatus "@baseboard_fab2_lib.baseboard_fab2(sch_1):page21_i259:bmcinit" )
			)
			( pin "U5D1.AJ10"
				( objectStatus "@baseboard_fab2_lib.baseboard_fab2(sch_1):page21_i259:bpm_n(0)" )
			)
			( pin "U5D1.AH11"
				( objectStatus "@baseboard_fab2_lib.baseboard_fab2(sch_1):page21_i259:bpm_n(1)" )
			)
			( pin "U5D1.AG10"
				( objectStatus "@baseboard_fab2_lib.baseboard_fab2(sch_1):page21_i259:bpm_n(2)" )
			)
			( pin "U5D1.AF11"
				( objectStatus "@baseboard_fab2_lib.baseboard_fab2(sch_1):page21_i259:bpm_n(3)" )
			)
			( pin "U5D1.AA12"
				( objectStatus "@baseboard_fab2_lib.baseboard_fab2(sch_1):page21_i259:bpm_n(4)" )
			)
			( pin "U5D1.Y11"
				( objectStatus "@baseboard_fab2_lib.baseboard_fab2(sch_1):page21_i259:bpm_n(5)" )
			)
			( pin "U5D1.AE12"
				( objectStatus "@baseboard_fab2_lib.baseboard_fab2(sch_1):page21_i259:bpm_n(6)" )
			)
			( pin "U5D1.AC12"
				( objectStatus "@baseboard_fab2_lib.baseboard_fab2(sch_1):page21_i259:bpm_n(7)" )
			)
			( pin "U5D1.AL14"
				( objectStatus "@baseboard_fab2_lib.baseboard_fab2(sch_1):page21_i259:caterr_n" )
			)
			( pin "U5D1.AJ64"
				( objectStatus "@baseboard_fab2_lib.baseboard_fab2(sch_1):page21_i259:ddr0_cavref" )
			)
			( pin "U5D1.AK63"
				( objectStatus "@baseboard_fab2_lib.baseboard_fab2(sch_1):page21_i259:ddr1_cavref" )
			)
			( pin "U5D1.AH63"
				( objectStatus "@baseboard_fab2_lib.baseboard_fab2(sch_1):page21_i259:ddr2_cavref" )
			)
			( pin "U5D1.CP61"
				( objectStatus "@baseboard_fab2_lib.baseboard_fab2(sch_1):page21_i259:ddr3_cavref" )
			)
			( pin "U5D1.CT61"
				( objectStatus "@baseboard_fab2_lib.baseboard_fab2(sch_1):page21_i259:ddr4_cavref" )
			)
			( pin "U5D1.CV61"
				( objectStatus "@baseboard_fab2_lib.baseboard_fab2(sch_1):page21_i259:ddr5_cavref" )
			)
			( pin "U5D1.AN30"
				( objectStatus "@baseboard_fab2_lib.baseboard_fab2(sch_1):page21_i259:ddr012_dram_pwr_ok" )
			)
			( pin "U5D1.Y43"
				( objectStatus "@baseboard_fab2_lib.baseboard_fab2(sch_1):page21_i259:ddr012_rcomp(0)" )
			)
			( pin "U5D1.AB43"
				( objectStatus "@baseboard_fab2_lib.baseboard_fab2(sch_1):page21_i259:ddr012_rcomp(1)" )
			)
			( pin "U5D1.AC42"
				( objectStatus "@baseboard_fab2_lib.baseboard_fab2(sch_1):page21_i259:ddr012_rcomp(2)" )
			)
			( pin "U5D1.U64"
				( objectStatus "@baseboard_fab2_lib.baseboard_fab2(sch_1):page21_i259:ddr012_reset_n" )
			)
			( pin "U5D1.AJ18"
				( objectStatus "@baseboard_fab2_lib.baseboard_fab2(sch_1):page21_i259:ddr012_spdscl" )
			)
			( pin "U5D1.AF17"
				( objectStatus "@baseboard_fab2_lib.baseboard_fab2(sch_1):page21_i259:ddr012_spdsda" )
			)
			( pin "U5D1.CR28"
				( objectStatus "@baseboard_fab2_lib.baseboard_fab2(sch_1):page21_i259:ddr345_dram_pwr_ok" )
			)
			( pin "U5D1.DC48"
				( objectStatus "@baseboard_fab2_lib.baseboard_fab2(sch_1):page21_i259:ddr345_rcomp(0)" )
			)
			( pin "U5D1.DD47"
				( objectStatus "@baseboard_fab2_lib.baseboard_fab2(sch_1):page21_i259:ddr345_rcomp(1)" )
			)
			( pin "U5D1.DD49"
				( objectStatus "@baseboard_fab2_lib.baseboard_fab2(sch_1):page21_i259:ddr345_rcomp(2)" )
			)
			( pin "U5D1.DV63"
				( objectStatus "@baseboard_fab2_lib.baseboard_fab2(sch_1):page21_i259:ddr345_reset_n" )
			)
			( pin "U5D1.AE18"
				( objectStatus "@baseboard_fab2_lib.baseboard_fab2(sch_1):page21_i259:ddr345_spdscl" )
			)
			( pin "U5D1.AD17"
				( objectStatus "@baseboard_fab2_lib.baseboard_fab2(sch_1):page21_i259:ddr345_spdsda" )
			)
			( pin "U5D1.AJ14"
				( objectStatus "@baseboard_fab2_lib.baseboard_fab2(sch_1):page21_i259:ear_n" )
			)
			( pin "U5D1.AJ12"
				( objectStatus "@baseboard_fab2_lib.baseboard_fab2(sch_1):page21_i259:error_n(0)" )
			)
			( pin "U5D1.AK11"
				( objectStatus "@baseboard_fab2_lib.baseboard_fab2(sch_1):page21_i259:error_n(1)" )
			)
			( pin "U5D1.AL12"
				( objectStatus "@baseboard_fab2_lib.baseboard_fab2(sch_1):page21_i259:error_n(2)" )
			)
			( pin "U5D1.AV17"
				( objectStatus "@baseboard_fab2_lib.baseboard_fab2(sch_1):page21_i259:frmagent" )
			)
			( pin "U5D1.AE20"
				( objectStatus "@baseboard_fab2_lib.baseboard_fab2(sch_1):page21_i259:legacy_skt" )
			)
			( pin "U5D1.CU32"
				( objectStatus "@baseboard_fab2_lib.baseboard_fab2(sch_1):page21_i259:mcp01_rbias(0)" )
			)
			( pin "U5D1.CT31"
				( objectStatus "@baseboard_fab2_lib.baseboard_fab2(sch_1):page21_i259:mcp01_rbias(1)" )
			)
			( pin "U5D1.AH13"
				( objectStatus "@baseboard_fab2_lib.baseboard_fab2(sch_1):page21_i259:mem_hot_c012_n" )
			)
			( pin "U5D1.AF13"
				( objectStatus "@baseboard_fab2_lib.baseboard_fab2(sch_1):page21_i259:mem_hot_c345_n" )
			)
			( pin "U5D1.AN20"
				( objectStatus "@baseboard_fab2_lib.baseboard_fab2(sch_1):page21_i259:msmi_n" )
			)
			( pin "U5D1.AP11"
				( objectStatus "@baseboard_fab2_lib.baseboard_fab2(sch_1):page21_i259:nmi" )
			)
			( pin "U5D1.CP29"
				( objectStatus "@baseboard_fab2_lib.baseboard_fab2(sch_1):page21_i259:pe3_rbias(0)" )
			)
			( pin "U5D1.CR30"
				( objectStatus "@baseboard_fab2_lib.baseboard_fab2(sch_1):page21_i259:pe3_rbias(1)" )
			)
			( pin "U5D1.CN30"
				( objectStatus "@baseboard_fab2_lib.baseboard_fab2(sch_1):page21_i259:pe012_rbias(0)" )
			)
			( pin "U5D1.CL30"
				( objectStatus "@baseboard_fab2_lib.baseboard_fab2(sch_1):page21_i259:pe012_rbias(1)" )
			)
			( pin "U5D1.AM19"
				( objectStatus "@baseboard_fab2_lib.baseboard_fab2(sch_1):page21_i259:pe_hp_scl" )
			)
			( pin "U5D1.AL18"
				( objectStatus "@baseboard_fab2_lib.baseboard_fab2(sch_1):page21_i259:pe_hp_sda" )
			)
			( pin "U5D1.AU12"
				( objectStatus "@baseboard_fab2_lib.baseboard_fab2(sch_1):page21_i259:peci" )
			)
			( pin "U5D1.CU58"
				( objectStatus "@baseboard_fab2_lib.baseboard_fab2(sch_1):page21_i259:pirom_addr(0)" )
			)
			( pin "U5D1.CV57"
				( objectStatus "@baseboard_fab2_lib.baseboard_fab2(sch_1):page21_i259:pirom_addr(1)" )
			)
			( pin "U5D1.CW56"
				( objectStatus "@baseboard_fab2_lib.baseboard_fab2(sch_1):page21_i259:pirom_addr(2)" )
			)
			( pin "U5D1.DC72"
				( objectStatus "@baseboard_fab2_lib.baseboard_fab2(sch_1):page21_i259:pkgid(0)" )
			)
			( pin "U5D1.CW72"
				( objectStatus "@baseboard_fab2_lib.baseboard_fab2(sch_1):page21_i259:pkgid(1)" )
			)
			( pin "U5D1.DA72"
				( objectStatus "@baseboard_fab2_lib.baseboard_fab2(sch_1):page21_i259:pkgid(2)" )
			)
			( pin "U5D1.AF15"
				( objectStatus "@baseboard_fab2_lib.baseboard_fab2(sch_1):page21_i259:pm_fast_wake_n" )
			)
			( pin "U5D1.AR14"
				( objectStatus "@baseboard_fab2_lib.baseboard_fab2(sch_1):page21_i259:pmsync" )
			)
			( pin "U5D1.AT19"
				( objectStatus "@baseboard_fab2_lib.baseboard_fab2(sch_1):page21_i259:pmsync_clk" )
			)
			( pin "U5D1.AG16"
				( objectStatus "@baseboard_fab2_lib.baseboard_fab2(sch_1):page21_i259:prdy_n" )
			)
			( pin "U5D1.AR12"
				( objectStatus "@baseboard_fab2_lib.baseboard_fab2(sch_1):page21_i259:preq_n" )
			)
			( pin "U5D1.CY71"
				( objectStatus "@baseboard_fab2_lib.baseboard_fab2(sch_1):page21_i259:proc_id(0)" )
			)
			( pin "U5D1.DB71"
				( objectStatus "@baseboard_fab2_lib.baseboard_fab2(sch_1):page21_i259:proc_id(1)" )
			)
			( pin "U5D1.AB17"
				( objectStatus "@baseboard_fab2_lib.baseboard_fab2(sch_1):page21_i259:procdis_n" )
			)
			( pin "U5D1.AC16"
				( objectStatus "@baseboard_fab2_lib.baseboard_fab2(sch_1):page21_i259:prochot_n" )
			)
			( pin "U5D1.BC24"
				( objectStatus "@baseboard_fab2_lib.baseboard_fab2(sch_1):page21_i259:pwrgood" )
			)
			( pin "U5D1.AP21"
				( objectStatus "@baseboard_fab2_lib.baseboard_fab2(sch_1):page21_i259:reset_n" )
			)
			( pin "U5D1.AR18"
				( objectStatus "@baseboard_fab2_lib.baseboard_fab2(sch_1):page21_i259:safe_mode_boot" )
			)
			( pin "U5D1.AB13"
				( objectStatus "@baseboard_fab2_lib.baseboard_fab2(sch_1):page21_i259:sktocc_n" )
			)
			( pin "U5D1.CV59"
				( objectStatus "@baseboard_fab2_lib.baseboard_fab2(sch_1):page21_i259:sm_wp" )
			)
			( pin "U5D1.CT59"
				( objectStatus "@baseboard_fab2_lib.baseboard_fab2(sch_1):page21_i259:smbclk" )
			)
			( pin "U5D1.CW58"
				( objectStatus "@baseboard_fab2_lib.baseboard_fab2(sch_1):page21_i259:smbdat" )
			)
			( pin "U5D1.AU22"
				( objectStatus "@baseboard_fab2_lib.baseboard_fab2(sch_1):page21_i259:socket_id(0)" )
			)
			( pin "U5D1.AU16"
				( objectStatus "@baseboard_fab2_lib.baseboard_fab2(sch_1):page21_i259:socket_id(1)" )
			)
			( pin "U5D1.AU20"
				( objectStatus "@baseboard_fab2_lib.baseboard_fab2(sch_1):page21_i259:socket_id(2)" )
			)
			( pin "U5D1.DE44"
				( objectStatus "@baseboard_fab2_lib.baseboard_fab2(sch_1):page21_i259:svidalert_n(0)" )
			)
			( pin "U5D1.DL44"
				( objectStatus "@baseboard_fab2_lib.baseboard_fab2(sch_1):page21_i259:svidalert_n(1)" )
			)
			( pin "U5D1.DC44"
				( objectStatus "@baseboard_fab2_lib.baseboard_fab2(sch_1):page21_i259:svidclk(0)" )
			)
			( pin "U5D1.DG44"
				( objectStatus "@baseboard_fab2_lib.baseboard_fab2(sch_1):page21_i259:svidclk(1)" )
			)
			( pin "U5D1.DB45"
				( objectStatus "@baseboard_fab2_lib.baseboard_fab2(sch_1):page21_i259:sviddata(0)" )
			)
			( pin "U5D1.DJ44"
				( objectStatus "@baseboard_fab2_lib.baseboard_fab2(sch_1):page21_i259:sviddata(1)" )
			)
			( pin "U5D1.AA14"
				( objectStatus "@baseboard_fab2_lib.baseboard_fab2(sch_1):page21_i259:tck" )
			)
			( pin "U5D1.AC14"
				( objectStatus "@baseboard_fab2_lib.baseboard_fab2(sch_1):page21_i259:tdi" )
			)
			( pin "U5D1.AE14"
				( objectStatus "@baseboard_fab2_lib.baseboard_fab2(sch_1):page21_i259:tdo" )
			)
			( pin "U5D1.AY19"
				( objectStatus "@baseboard_fab2_lib.baseboard_fab2(sch_1):page21_i259:test_12" )
			)
			( pin "U5D1.DB51"
				( objectStatus "@baseboard_fab2_lib.baseboard_fab2(sch_1):page21_i259:test_13" )
			)
			( pin "U5D1.DC50"
				( objectStatus "@baseboard_fab2_lib.baseboard_fab2(sch_1):page21_i259:test_14" )
			)
			( pin "U5D1.AW14"
				( objectStatus "@baseboard_fab2_lib.baseboard_fab2(sch_1):page21_i259:test_15" )
			)
			( pin "U5D1.AB15"
				( objectStatus "@baseboard_fab2_lib.baseboard_fab2(sch_1):page21_i259:thermtrip_n" )
			)
			( pin "U5D1.W14"
				( objectStatus "@baseboard_fab2_lib.baseboard_fab2(sch_1):page21_i259:tms" )
			)
			( pin "U5D1.Y13"
				( objectStatus "@baseboard_fab2_lib.baseboard_fab2(sch_1):page21_i259:trst_n" )
			)
			( pin "U5D1.AM11"
				( objectStatus "@baseboard_fab2_lib.baseboard_fab2(sch_1):page21_i259:tsc_sync" )
			)
			( pin "U5D1.AW18"
				( objectStatus "@baseboard_fab2_lib.baseboard_fab2(sch_1):page21_i259:txt_agent" )
			)
			( pin "U5D1.AV15"
				( objectStatus "@baseboard_fab2_lib.baseboard_fab2(sch_1):page21_i259:txt_plten" )
			)
			( pin "U5D1.AT29"
				( objectStatus "@baseboard_fab2_lib.baseboard_fab2(sch_1):page21_i259:upi01_rbias(0)" )
			)
			( pin "U5D1.AP29"
				( objectStatus "@baseboard_fab2_lib.baseboard_fab2(sch_1):page21_i259:upi01_rbias(1)" )
			)
			( pin "U5D1.CL28"
				( objectStatus "@baseboard_fab2_lib.baseboard_fab2(sch_1):page21_i259:upi2_rbias(0)" )
			)
			( pin "U5D1.CK29"
				( objectStatus "@baseboard_fab2_lib.baseboard_fab2(sch_1):page21_i259:upi2_rbias(1)" )
			)
			( pin "R5R1.1"
				( objectStatus "@baseboard_fab2_lib.baseboard_fab2(sch_1):page22_i188:a" )
			)
			( pin "R5R1.2"
				( objectStatus "@baseboard_fab2_lib.baseboard_fab2(sch_1):page22_i188:b" )
			)
			( pin "R5P4.1"
				( objectStatus "@baseboard_fab2_lib.baseboard_fab2(sch_1):page22_i190:a" )
			)
			( pin "R5P4.2"
				( objectStatus "@baseboard_fab2_lib.baseboard_fab2(sch_1):page22_i190:b" )
			)
			( pin "U5D1.AV21"
				( objectStatus "@baseboard_fab2_lib.baseboard_fab2(sch_1):page22_i204:debug_en_n" )
			)
			( pin "U5D1.AW12"
				( objectStatus "@baseboard_fab2_lib.baseboard_fab2(sch_1):page22_i204:dmimode_override" )
			)
			( pin "U5D1.AU14"
				( objectStatus "@baseboard_fab2_lib.baseboard_fab2(sch_1):page22_i204:fivr_fault" )
			)
			( pin "U5D1.AP17"
				( objectStatus "@baseboard_fab2_lib.baseboard_fab2(sch_1):page22_i204:pwr_debug_n" )
			)
			( pin "U5D1.AP61"
				( objectStatus "@baseboard_fab2_lib.baseboard_fab2(sch_1):page22_i204:rsvd(194)" )
			)
			( pin "U5D1.AP27"
				( objectStatus "@baseboard_fab2_lib.baseboard_fab2(sch_1):page22_i204:rsvd(195)" )
			)
			( pin "U5D1.AP25"
				( objectStatus "@baseboard_fab2_lib.baseboard_fab2(sch_1):page22_i204:rsvd(196)" )
			)
			( pin "U5D1.AP23"
				( objectStatus "@baseboard_fab2_lib.baseboard_fab2(sch_1):page22_i204:rsvd(197)" )
			)
			( pin "U5D1.AN62"
				( objectStatus "@baseboard_fab2_lib.baseboard_fab2(sch_1):page22_i204:rsvd(198)" )
			)
			( pin "U5D1.AN60"
				( objectStatus "@baseboard_fab2_lib.baseboard_fab2(sch_1):page22_i204:rsvd(199)" )
			)
			( pin "U5D1.AN26"
				( objectStatus "@baseboard_fab2_lib.baseboard_fab2(sch_1):page22_i204:rsvd(200)" )
			)
			( pin "U5D1.AN24"
				( objectStatus "@baseboard_fab2_lib.baseboard_fab2(sch_1):page22_i204:rsvd(201)" )
			)
			( pin "U5D1.AN22"
				( objectStatus "@baseboard_fab2_lib.baseboard_fab2(sch_1):page22_i204:rsvd(202)" )
			)
			( pin "U5D1.AN18"
				( objectStatus "@baseboard_fab2_lib.baseboard_fab2(sch_1):page22_i204:rsvd(203)" )
			)
			( pin "U5D1.AM61"
				( objectStatus "@baseboard_fab2_lib.baseboard_fab2(sch_1):page22_i204:rsvd(204)" )
			)
			( pin "U5D1.AM59"
				( objectStatus "@baseboard_fab2_lib.baseboard_fab2(sch_1):page22_i204:rsvd(205)" )
			)
			( pin "U5D1.AM27"
				( objectStatus "@baseboard_fab2_lib.baseboard_fab2(sch_1):page22_i204:rsvd(206)" )
			)
			( pin "U5D1.AM25"
				( objectStatus "@baseboard_fab2_lib.baseboard_fab2(sch_1):page22_i204:rsvd(207)" )
			)
			( pin "U5D1.AM23"
				( objectStatus "@baseboard_fab2_lib.baseboard_fab2(sch_1):page22_i204:rsvd(208)" )
			)
			( pin "U5D1.AM21"
				( objectStatus "@baseboard_fab2_lib.baseboard_fab2(sch_1):page22_i204:rsvd(209)" )
			)
			( pin "U5D1.AL62"
				( objectStatus "@baseboard_fab2_lib.baseboard_fab2(sch_1):page22_i204:rsvd(210)" )
			)
			( pin "U5D1.AL60"
				( objectStatus "@baseboard_fab2_lib.baseboard_fab2(sch_1):page22_i204:rsvd(211)" )
			)
			( pin "U5D1.AL58"
				( objectStatus "@baseboard_fab2_lib.baseboard_fab2(sch_1):page22_i204:rsvd(212)" )
			)
			( pin "U5D1.AL26"
				( objectStatus "@baseboard_fab2_lib.baseboard_fab2(sch_1):page22_i204:rsvd(213)" )
			)
			( pin "U5D1.AL22"
				( objectStatus "@baseboard_fab2_lib.baseboard_fab2(sch_1):page22_i204:rsvd(214)" )
			)
			( pin "U5D1.AL20"
				( objectStatus "@baseboard_fab2_lib.baseboard_fab2(sch_1):page22_i204:rsvd(215)" )
			)
			( pin "U5D1.AK69"
				( objectStatus "@baseboard_fab2_lib.baseboard_fab2(sch_1):page22_i204:rsvd(216)" )
			)
			( pin "U5D1.AK61"
				( objectStatus "@baseboard_fab2_lib.baseboard_fab2(sch_1):page22_i204:rsvd(217)" )
			)
			( pin "U5D1.AK59"
				( objectStatus "@baseboard_fab2_lib.baseboard_fab2(sch_1):page22_i204:rsvd(218)" )
			)
			( pin "U5D1.AK57"
				( objectStatus "@baseboard_fab2_lib.baseboard_fab2(sch_1):page22_i204:rsvd(219)" )
			)
			( pin "U5D1.AK27"
				( objectStatus "@baseboard_fab2_lib.baseboard_fab2(sch_1):page22_i204:rsvd(220)" )
			)
			( pin "U5D1.AK21"
				( objectStatus "@baseboard_fab2_lib.baseboard_fab2(sch_1):page22_i204:rsvd(221)" )
			)
			( pin "U5D1.AJ70"
				( objectStatus "@baseboard_fab2_lib.baseboard_fab2(sch_1):page22_i204:rsvd(222)" )
			)
			( pin "U5D1.AJ62"
				( objectStatus "@baseboard_fab2_lib.baseboard_fab2(sch_1):page22_i204:rsvd(223)" )
			)
			( pin "U5D1.AJ60"
				( objectStatus "@baseboard_fab2_lib.baseboard_fab2(sch_1):page22_i204:rsvd(224)" )
			)
			( pin "U5D1.AJ58"
				( objectStatus "@baseboard_fab2_lib.baseboard_fab2(sch_1):page22_i204:rsvd(225)" )
			)
			( pin "U5D1.AJ56"
				( objectStatus "@baseboard_fab2_lib.baseboard_fab2(sch_1):page22_i204:rsvd(226)" )
			)
			( pin "U5D1.AJ20"
				( objectStatus "@baseboard_fab2_lib.baseboard_fab2(sch_1):page22_i204:rsvd(227)" )
			)
			( pin "U5D1.AH73"
				( objectStatus "@baseboard_fab2_lib.baseboard_fab2(sch_1):page22_i204:rsvd(228)" )
			)
			( pin "U5D1.AH71"
				( objectStatus "@baseboard_fab2_lib.baseboard_fab2(sch_1):page22_i204:rsvd(229)" )
			)
			( pin "U5D1.AH57"
				( objectStatus "@baseboard_fab2_lib.baseboard_fab2(sch_1):page22_i204:rsvd(230)" )
			)
			( pin "U5D1.AH55"
				( objectStatus "@baseboard_fab2_lib.baseboard_fab2(sch_1):page22_i204:rsvd(231)" )
			)
			( pin "U5D1.AH19"
				( objectStatus "@baseboard_fab2_lib.baseboard_fab2(sch_1):page22_i204:rsvd(232)" )
			)
			( pin "U5D1.AH15"
				( objectStatus "@baseboard_fab2_lib.baseboard_fab2(sch_1):page22_i204:rsvd(233)" )
			)
			( pin "U5D1.AG72"
				( objectStatus "@baseboard_fab2_lib.baseboard_fab2(sch_1):page22_i204:rsvd(234)" )
			)
			( pin "U5D1.AG56"
				( objectStatus "@baseboard_fab2_lib.baseboard_fab2(sch_1):page22_i204:rsvd(235)" )
			)
			( pin "U5D1.AG54"
				( objectStatus "@baseboard_fab2_lib.baseboard_fab2(sch_1):page22_i204:rsvd(236)" )
			)
			( pin "U5D1.AG52"
				( objectStatus "@baseboard_fab2_lib.baseboard_fab2(sch_1):page22_i204:rsvd(237)" )
			)
			( pin "U5D1.AG50"
				( objectStatus "@baseboard_fab2_lib.baseboard_fab2(sch_1):page22_i204:rsvd(238)" )
			)
			( pin "U5D1.AG48"
				( objectStatus "@baseboard_fab2_lib.baseboard_fab2(sch_1):page22_i204:rsvd(239)" )
			)
			( pin "U5D1.AG20"
				( objectStatus "@baseboard_fab2_lib.baseboard_fab2(sch_1):page22_i204:rsvd(240)" )
			)
			( pin "U5D1.AF71"
				( objectStatus "@baseboard_fab2_lib.baseboard_fab2(sch_1):page22_i204:rsvd(241)" )
			)
			( pin "U5D1.AF53"
				( objectStatus "@baseboard_fab2_lib.baseboard_fab2(sch_1):page22_i204:rsvd(242)" )
			)
			( pin "U5D1.AF51"
				( objectStatus "@baseboard_fab2_lib.baseboard_fab2(sch_1):page22_i204:rsvd(243)" )
			)
			( pin "U5D1.AF49"
				( objectStatus "@baseboard_fab2_lib.baseboard_fab2(sch_1):page22_i204:rsvd(244)" )
			)
			( pin "U5D1.AF47"
				( objectStatus "@baseboard_fab2_lib.baseboard_fab2(sch_1):page22_i204:rsvd(245)" )
			)
			( pin "U5D1.AF19"
				( objectStatus "@baseboard_fab2_lib.baseboard_fab2(sch_1):page22_i204:rsvd(246)" )
			)
			( pin "U5D1.AE72"
				( objectStatus "@baseboard_fab2_lib.baseboard_fab2(sch_1):page22_i204:rsvd(247)" )
			)
			( pin "U5D1.AE52"
				( objectStatus "@baseboard_fab2_lib.baseboard_fab2(sch_1):page22_i204:rsvd(248)" )
			)
			( pin "U5D1.AE50"
				( objectStatus "@baseboard_fab2_lib.baseboard_fab2(sch_1):page22_i204:rsvd(249)" )
			)
			( pin "U5D1.AE48"
				( objectStatus "@baseboard_fab2_lib.baseboard_fab2(sch_1):page22_i204:rsvd(250)" )
			)
			( pin "U5D1.AE46"
				( objectStatus "@baseboard_fab2_lib.baseboard_fab2(sch_1):page22_i204:rsvd(251)" )
			)
			( pin "U5D1.AD51"
				( objectStatus "@baseboard_fab2_lib.baseboard_fab2(sch_1):page22_i204:rsvd(252)" )
			)
			( pin "U5D1.AD49"
				( objectStatus "@baseboard_fab2_lib.baseboard_fab2(sch_1):page22_i204:rsvd(253)" )
			)
			( pin "U5D1.AD47"
				( objectStatus "@baseboard_fab2_lib.baseboard_fab2(sch_1):page22_i204:rsvd(254)" )
			)
			( pin "U5D1.Y65"
				( objectStatus "@baseboard_fab2_lib.baseboard_fab2(sch_1):page22_i204:rsvd(256)" )
			)
			( pin "U5D1.Y23"
				( objectStatus "@baseboard_fab2_lib.baseboard_fab2(sch_1):page22_i204:rsvd(257)" )
			)
			( pin "U5D1.W66"
				( objectStatus "@baseboard_fab2_lib.baseboard_fab2(sch_1):page22_i204:rsvd(258)" )
			)
			( pin "U5D1.V67"
				( objectStatus "@baseboard_fab2_lib.baseboard_fab2(sch_1):page22_i204:rsvd(259)" )
			)
			( pin "U5D1.V65"
				( objectStatus "@baseboard_fab2_lib.baseboard_fab2(sch_1):page22_i204:rsvd(260)" )
			)
			( pin "U5D1.U66"
				( objectStatus "@baseboard_fab2_lib.baseboard_fab2(sch_1):page22_i204:rsvd(261)" )
			)
			( pin "U5D1.T67"
				( objectStatus "@baseboard_fab2_lib.baseboard_fab2(sch_1):page22_i204:rsvd(262)" )
			)
			( pin "U5D1.R66"
				( objectStatus "@baseboard_fab2_lib.baseboard_fab2(sch_1):page22_i204:rsvd(263)" )
			)
			( pin "U5D1.R62"
				( objectStatus "@baseboard_fab2_lib.baseboard_fab2(sch_1):page22_i204:rsvd(264)" )
			)
			( pin "U5D1.P65"
				( objectStatus "@baseboard_fab2_lib.baseboard_fab2(sch_1):page22_i204:rsvd(265)" )
			)
			( pin "U5D1.M63"
				( objectStatus "@baseboard_fab2_lib.baseboard_fab2(sch_1):page22_i204:rsvd(266)" )
			)
			( pin "U5D1.K61"
				( objectStatus "@baseboard_fab2_lib.baseboard_fab2(sch_1):page22_i204:rsvd(267)" )
			)
			( pin "U5D1.J62"
				( objectStatus "@baseboard_fab2_lib.baseboard_fab2(sch_1):page22_i204:rsvd(268)" )
			)
			( pin "U5D1.J46"
				( objectStatus "@baseboard_fab2_lib.baseboard_fab2(sch_1):page22_i204:rsvd(269)" )
			)
			( pin "U5D1.H85"
				( objectStatus "@baseboard_fab2_lib.baseboard_fab2(sch_1):page22_i204:rsvd(270)" )
			)
			( pin "U5D1.H83"
				( objectStatus "@baseboard_fab2_lib.baseboard_fab2(sch_1):page22_i204:rsvd(271)" )
			)
			( pin "U5D1.H1"
				( objectStatus "@baseboard_fab2_lib.baseboard_fab2(sch_1):page22_i204:rsvd(272)" )
			)
			( pin "U5D1.G84"
				( objectStatus "@baseboard_fab2_lib.baseboard_fab2(sch_1):page22_i204:rsvd(273)" )
			)
			( pin "U5D1.G64"
				( objectStatus "@baseboard_fab2_lib.baseboard_fab2(sch_1):page22_i204:rsvd(274)" )
			)
			( pin "U5D1.G2"
				( objectStatus "@baseboard_fab2_lib.baseboard_fab2(sch_1):page22_i204:rsvd(275)" )
			)
			( pin "U5D1.F83"
				( objectStatus "@baseboard_fab2_lib.baseboard_fab2(sch_1):page22_i204:rsvd(276)" )
			)
			( pin "U5D1.F65"
				( objectStatus "@baseboard_fab2_lib.baseboard_fab2(sch_1):page22_i204:rsvd(277)" )
			)
			( pin "U5D1.F23"
				( objectStatus "@baseboard_fab2_lib.baseboard_fab2(sch_1):page22_i204:rsvd(278)" )
			)
			( pin "U5D1.F3"
				( objectStatus "@baseboard_fab2_lib.baseboard_fab2(sch_1):page22_i204:rsvd(279)" )
			)
			( pin "U5D1.E84"
				( objectStatus "@baseboard_fab2_lib.baseboard_fab2(sch_1):page22_i204:rsvd(280)" )
			)
			( pin "U5D1.E24"
				( objectStatus "@baseboard_fab2_lib.baseboard_fab2(sch_1):page22_i204:rsvd(281)" )
			)
			( pin "U5D1.E4"
				( objectStatus "@baseboard_fab2_lib.baseboard_fab2(sch_1):page22_i204:rsvd(282)" )
			)
			( pin "U5D1.E2"
				( objectStatus "@baseboard_fab2_lib.baseboard_fab2(sch_1):page22_i204:rsvd(283)" )
			)
			( pin "U5D1.D83"
				( objectStatus "@baseboard_fab2_lib.baseboard_fab2(sch_1):page22_i204:rsvd(284)" )
			)
			( pin "U5D1.D65"
				( objectStatus "@baseboard_fab2_lib.baseboard_fab2(sch_1):page22_i204:rsvd(285)" )
			)
			( pin "U5D1.D17"
				( objectStatus "@baseboard_fab2_lib.baseboard_fab2(sch_1):page22_i204:rsvd(286)" )
			)
			( pin "U5D1.D5"
				( objectStatus "@baseboard_fab2_lib.baseboard_fab2(sch_1):page22_i204:rsvd(287)" )
			)
			( pin "U5D1.C82"
				( objectStatus "@baseboard_fab2_lib.baseboard_fab2(sch_1):page22_i204:rsvd(288)" )
			)
			( pin "U5D1.C24"
				( objectStatus "@baseboard_fab2_lib.baseboard_fab2(sch_1):page22_i204:rsvd(289)" )
			)
			( pin "U5D1.C18"
				( objectStatus "@baseboard_fab2_lib.baseboard_fab2(sch_1):page22_i204:rsvd(290)" )
			)
			( pin "U5D1.C6"
				( objectStatus "@baseboard_fab2_lib.baseboard_fab2(sch_1):page22_i204:rsvd(291)" )
			)
			( pin "U5D1.B81"
				( objectStatus "@baseboard_fab2_lib.baseboard_fab2(sch_1):page22_i204:rsvd(292)" )
			)
			( pin "U5D1.B77"
				( objectStatus "@baseboard_fab2_lib.baseboard_fab2(sch_1):page22_i204:rsvd(293)" )
			)
			( pin "U5D1.B17"
				( objectStatus "@baseboard_fab2_lib.baseboard_fab2(sch_1):page22_i204:rsvd(294)" )
			)
			( pin "U5D1.B15"
				( objectStatus "@baseboard_fab2_lib.baseboard_fab2(sch_1):page22_i204:rsvd(295)" )
			)
			( pin "U5D1.B13"
				( objectStatus "@baseboard_fab2_lib.baseboard_fab2(sch_1):page22_i204:rsvd(296)" )
			)
			( pin "U5D1.B7"
				( objectStatus "@baseboard_fab2_lib.baseboard_fab2(sch_1):page22_i204:rsvd(298)" )
			)
			( pin "U5D1.B3"
				( objectStatus "@baseboard_fab2_lib.baseboard_fab2(sch_1):page22_i204:rsvd(299)" )
			)
			( pin "U5D1.A24"
				( objectStatus "@baseboard_fab2_lib.baseboard_fab2(sch_1):page22_i204:rsvd(300)" )
			)
			( pin "U5D1.A16"
				( objectStatus "@baseboard_fab2_lib.baseboard_fab2(sch_1):page22_i204:rsvd(301)" )
			)
			( pin "U5D1.A14"
				( objectStatus "@baseboard_fab2_lib.baseboard_fab2(sch_1):page22_i204:rsvd(302)" )
			)
			( pin "U5D1.A6"
				( objectStatus "@baseboard_fab2_lib.baseboard_fab2(sch_1):page22_i204:rsvd(303)" )
			)
			( pin "U5D1.A4"
				( objectStatus "@baseboard_fab2_lib.baseboard_fab2(sch_1):page22_i204:rsvd(304)" )
			)
			( pin "U5D1.AF45"
				( objectStatus "@baseboard_fab2_lib.baseboard_fab2(sch_1):page22_i204:test_1" )
			)
			( pin "U5D1.AG46"
				( objectStatus "@baseboard_fab2_lib.baseboard_fab2(sch_1):page22_i204:test_2" )
			)
			( pin "U5D1.AM13"
				( objectStatus "@baseboard_fab2_lib.baseboard_fab2(sch_1):page22_i204:test_3" )
			)
			( pin "U5D1.AN12"
				( objectStatus "@baseboard_fab2_lib.baseboard_fab2(sch_1):page22_i204:test_4" )
			)
			( pin "U5D1.AN14"
				( objectStatus "@baseboard_fab2_lib.baseboard_fab2(sch_1):page22_i204:test_5" )
			)
			( pin "U5D1.AY13"
				( objectStatus "@baseboard_fab2_lib.baseboard_fab2(sch_1):page22_i204:test_11" )
			)
			( pin "U5D1.J60"
				( objectStatus "@baseboard_fab2_lib.baseboard_fab2(sch_1):page23_i172:ddr0_act_n" )
			)
			( pin "U5D1.B61"
				( objectStatus "@baseboard_fab2_lib.baseboard_fab2(sch_1):page23_i172:ddr0_alert_n" )
			)
			( pin "U5D1.C52"
				( objectStatus "@baseboard_fab2_lib.baseboard_fab2(sch_1):page23_i172:ddr0_ba(0)" )
			)
			( pin "U5D1.G54"
				( objectStatus "@baseboard_fab2_lib.baseboard_fab2(sch_1):page23_i172:ddr0_ba(1)" )
			)
			( pin "U5D1.D61"
				( objectStatus "@baseboard_fab2_lib.baseboard_fab2(sch_1):page23_i172:ddr0_bg(0)" )
			)
			( pin "U5D1.F63"
				( objectStatus "@baseboard_fab2_lib.baseboard_fab2(sch_1):page23_i172:ddr0_bg(1)" )
			)
			( pin "U5D1.G46"
				( objectStatus "@baseboard_fab2_lib.baseboard_fab2(sch_1):page23_i172:ddr0_cid(2)" )
			)
			( pin "U5D1.C62"
				( objectStatus "@baseboard_fab2_lib.baseboard_fab2(sch_1):page23_i172:ddr0_cke(0)" )
			)
			( pin "U5D1.C64"
				( objectStatus "@baseboard_fab2_lib.baseboard_fab2(sch_1):page23_i172:ddr0_cke(1)" )
			)
			( pin "U5D1.B63"
				( objectStatus "@baseboard_fab2_lib.baseboard_fab2(sch_1):page23_i172:ddr0_cke(2)" )
			)
			( pin "U5D1.D63"
				( objectStatus "@baseboard_fab2_lib.baseboard_fab2(sch_1):page23_i172:ddr0_cke(3)" )
			)
			( pin "U5D1.F55"
				( objectStatus "@baseboard_fab2_lib.baseboard_fab2(sch_1):page23_i172:ddr0_clk_dn(0)" )
			)
			( pin "U5D1.C54"
				( objectStatus "@baseboard_fab2_lib.baseboard_fab2(sch_1):page23_i172:ddr0_clk_dn(1)" )
			)
			( pin "U5D1.J56"
				( objectStatus "@baseboard_fab2_lib.baseboard_fab2(sch_1):page23_i172:ddr0_clk_dn(2)" )
			)
			( pin "U5D1.C56"
				( objectStatus "@baseboard_fab2_lib.baseboard_fab2(sch_1):page23_i172:ddr0_clk_dn(3)" )
			)
			( pin "U5D1.D55"
				( objectStatus "@baseboard_fab2_lib.baseboard_fab2(sch_1):page23_i172:ddr0_clk_dp(0)" )
			)
			( pin "U5D1.B55"
				( objectStatus "@baseboard_fab2_lib.baseboard_fab2(sch_1):page23_i172:ddr0_clk_dp(1)" )
			)
			( pin "U5D1.G56"
				( objectStatus "@baseboard_fab2_lib.baseboard_fab2(sch_1):page23_i172:ddr0_clk_dp(2)" )
			)
			( pin "U5D1.B57"
				( objectStatus "@baseboard_fab2_lib.baseboard_fab2(sch_1):page23_i172:ddr0_clk_dp(3)" )
			)
			( pin "U5D1.G52"
				( objectStatus "@baseboard_fab2_lib.baseboard_fab2(sch_1):page23_i172:ddr0_cs_n(0)" )
			)
			( pin "U5D1.F49"
				( objectStatus "@baseboard_fab2_lib.baseboard_fab2(sch_1):page23_i172:ddr0_cs_n(1)" )
			)
			( pin "U5D1.D47"
				( objectStatus "@baseboard_fab2_lib.baseboard_fab2(sch_1):page23_i172:ddr0_cs_n(2)" )
			)
			( pin "U5D1.F47"
				( objectStatus "@baseboard_fab2_lib.baseboard_fab2(sch_1):page23_i172:ddr0_cs_n(3)" )
			)
			( pin "U5D1.B51"
				( objectStatus "@baseboard_fab2_lib.baseboard_fab2(sch_1):page23_i172:ddr0_cs_n(4)" )
			)
			( pin "U5D1.D49"
				( objectStatus "@baseboard_fab2_lib.baseboard_fab2(sch_1):page23_i172:ddr0_cs_n(5)" )
			)
			( pin "U5D1.F45"
				( objectStatus "@baseboard_fab2_lib.baseboard_fab2(sch_1):page23_i172:ddr0_cs_n(6)" )
			)
			( pin "U5D1.K45"
				( objectStatus "@baseboard_fab2_lib.baseboard_fab2(sch_1):page23_i172:ddr0_cs_n(7)" )
			)
			( pin "U5D1.AN86"
				( objectStatus "@baseboard_fab2_lib.baseboard_fab2(sch_1):page23_i172:ddr0_dq(0)" )
			)
			( pin "U5D1.AN84"
				( objectStatus "@baseboard_fab2_lib.baseboard_fab2(sch_1):page23_i172:ddr0_dq(1)" )
			)
			( pin "U5D1.AE86"
				( objectStatus "@baseboard_fab2_lib.baseboard_fab2(sch_1):page23_i172:ddr0_dq(2)" )
			)
			( pin "U5D1.AE84"
				( objectStatus "@baseboard_fab2_lib.baseboard_fab2(sch_1):page23_i172:ddr0_dq(3)" )
			)
			( pin "U5D1.AR86"
				( objectStatus "@baseboard_fab2_lib.baseboard_fab2(sch_1):page23_i172:ddr0_dq(4)" )
			)
			( pin "U5D1.AR84"
				( objectStatus "@baseboard_fab2_lib.baseboard_fab2(sch_1):page23_i172:ddr0_dq(5)" )
			)
			( pin "U5D1.AG86"
				( objectStatus "@baseboard_fab2_lib.baseboard_fab2(sch_1):page23_i172:ddr0_dq(6)" )
			)
			( pin "U5D1.AG84"
				( objectStatus "@baseboard_fab2_lib.baseboard_fab2(sch_1):page23_i172:ddr0_dq(7)" )
			)
			( pin "U5D1.W86"
				( objectStatus "@baseboard_fab2_lib.baseboard_fab2(sch_1):page23_i172:ddr0_dq(8)" )
			)
			( pin "U5D1.W84"
				( objectStatus "@baseboard_fab2_lib.baseboard_fab2(sch_1):page23_i172:ddr0_dq(9)" )
			)
			( pin "U5D1.L86"
				( objectStatus "@baseboard_fab2_lib.baseboard_fab2(sch_1):page23_i172:ddr0_dq(10)" )
			)
			( pin "U5D1.L84"
				( objectStatus "@baseboard_fab2_lib.baseboard_fab2(sch_1):page23_i172:ddr0_dq(11)" )
			)
			( pin "U5D1.AA86"
				( objectStatus "@baseboard_fab2_lib.baseboard_fab2(sch_1):page23_i172:ddr0_dq(12)" )
			)
			( pin "U5D1.AA84"
				( objectStatus "@baseboard_fab2_lib.baseboard_fab2(sch_1):page23_i172:ddr0_dq(13)" )
			)
			( pin "U5D1.N86"
				( objectStatus "@baseboard_fab2_lib.baseboard_fab2(sch_1):page23_i172:ddr0_dq(14)" )
			)
			( pin "U5D1.N84"
				( objectStatus "@baseboard_fab2_lib.baseboard_fab2(sch_1):page23_i172:ddr0_dq(15)" )
			)
			( pin "U5D1.V81"
				( objectStatus "@baseboard_fab2_lib.baseboard_fab2(sch_1):page23_i172:ddr0_dq(16)" )
			)
			( pin "U5D1.T79"
				( objectStatus "@baseboard_fab2_lib.baseboard_fab2(sch_1):page23_i172:ddr0_dq(17)" )
			)
			( pin "U5D1.N82"
				( objectStatus "@baseboard_fab2_lib.baseboard_fab2(sch_1):page23_i172:ddr0_dq(18)" )
			)
			( pin "U5D1.M81"
				( objectStatus "@baseboard_fab2_lib.baseboard_fab2(sch_1):page23_i172:ddr0_dq(19)" )
			)
			( pin "U5D1.W80"
				( objectStatus "@baseboard_fab2_lib.baseboard_fab2(sch_1):page23_i172:ddr0_dq(20)" )
			)
			( pin "U5D1.V79"
				( objectStatus "@baseboard_fab2_lib.baseboard_fab2(sch_1):page23_i172:ddr0_dq(21)" )
			)
			( pin "U5D1.R82"
				( objectStatus "@baseboard_fab2_lib.baseboard_fab2(sch_1):page23_i172:ddr0_dq(22)" )
			)
			( pin "U5D1.N80"
				( objectStatus "@baseboard_fab2_lib.baseboard_fab2(sch_1):page23_i172:ddr0_dq(23)" )
			)
			( pin "U5D1.L76"
				( objectStatus "@baseboard_fab2_lib.baseboard_fab2(sch_1):page23_i172:ddr0_dq(24)" )
			)
			( pin "U5D1.R76"
				( objectStatus "@baseboard_fab2_lib.baseboard_fab2(sch_1):page23_i172:ddr0_dq(25)" )
			)
			( pin "U5D1.M73"
				( objectStatus "@baseboard_fab2_lib.baseboard_fab2(sch_1):page23_i172:ddr0_dq(26)" )
			)
			( pin "U5D1.P73"
				( objectStatus "@baseboard_fab2_lib.baseboard_fab2(sch_1):page23_i172:ddr0_dq(27)" )
			)
			( pin "U5D1.M77"
				( objectStatus "@baseboard_fab2_lib.baseboard_fab2(sch_1):page23_i172:ddr0_dq(28)" )
			)
			( pin "U5D1.P77"
				( objectStatus "@baseboard_fab2_lib.baseboard_fab2(sch_1):page23_i172:ddr0_dq(29)" )
			)
			( pin "U5D1.L74"
				( objectStatus "@baseboard_fab2_lib.baseboard_fab2(sch_1):page23_i172:ddr0_dq(30)" )
			)
			( pin "U5D1.R74"
				( objectStatus "@baseboard_fab2_lib.baseboard_fab2(sch_1):page23_i172:ddr0_dq(31)" )
			)
			( pin "U5D1.C42"
				( objectStatus "@baseboard_fab2_lib.baseboard_fab2(sch_1):page23_i172:ddr0_dq(32)" )
			)
			( pin "U5D1.B41"
				( objectStatus "@baseboard_fab2_lib.baseboard_fab2(sch_1):page23_i172:ddr0_dq(33)" )
			)
			( pin "U5D1.C38"
				( objectStatus "@baseboard_fab2_lib.baseboard_fab2(sch_1):page23_i172:ddr0_dq(34)" )
			)
			( pin "U5D1.E38"
				( objectStatus "@baseboard_fab2_lib.baseboard_fab2(sch_1):page23_i172:ddr0_dq(35)" )
			)
			( pin "U5D1.E42"
				( objectStatus "@baseboard_fab2_lib.baseboard_fab2(sch_1):page23_i172:ddr0_dq(36)" )
			)
			( pin "U5D1.F41"
				( objectStatus "@baseboard_fab2_lib.baseboard_fab2(sch_1):page23_i172:ddr0_dq(37)" )
			)
			( pin "U5D1.B39"
				( objectStatus "@baseboard_fab2_lib.baseboard_fab2(sch_1):page23_i172:ddr0_dq(38)" )
			)
			( pin "U5D1.F39"
				( objectStatus "@baseboard_fab2_lib.baseboard_fab2(sch_1):page23_i172:ddr0_dq(39)" )
			)
			( pin "U5D1.K37"
				( objectStatus "@baseboard_fab2_lib.baseboard_fab2(sch_1):page23_i172:ddr0_dq(40)" )
			)
			( pin "U5D1.P37"
				( objectStatus "@baseboard_fab2_lib.baseboard_fab2(sch_1):page23_i172:ddr0_dq(41)" )
			)
			( pin "U5D1.L34"
				( objectStatus "@baseboard_fab2_lib.baseboard_fab2(sch_1):page23_i172:ddr0_dq(42)" )
			)
			( pin "U5D1.N34"
				( objectStatus "@baseboard_fab2_lib.baseboard_fab2(sch_1):page23_i172:ddr0_dq(43)" )
			)
			( pin "U5D1.L38"
				( objectStatus "@baseboard_fab2_lib.baseboard_fab2(sch_1):page23_i172:ddr0_dq(44)" )
			)
			( pin "U5D1.N38"
				( objectStatus "@baseboard_fab2_lib.baseboard_fab2(sch_1):page23_i172:ddr0_dq(45)" )
			)
			( pin "U5D1.K35"
				( objectStatus "@baseboard_fab2_lib.baseboard_fab2(sch_1):page23_i172:ddr0_dq(46)" )
			)
			( pin "U5D1.P35"
				( objectStatus "@baseboard_fab2_lib.baseboard_fab2(sch_1):page23_i172:ddr0_dq(47)" )
			)
			( pin "U5D1.K31"
				( objectStatus "@baseboard_fab2_lib.baseboard_fab2(sch_1):page23_i172:ddr0_dq(48)" )
			)
			( pin "U5D1.P31"
				( objectStatus "@baseboard_fab2_lib.baseboard_fab2(sch_1):page23_i172:ddr0_dq(49)" )
			)
			( pin "U5D1.L28"
				( objectStatus "@baseboard_fab2_lib.baseboard_fab2(sch_1):page23_i172:ddr0_dq(50)" )
			)
			( pin "U5D1.N28"
				( objectStatus "@baseboard_fab2_lib.baseboard_fab2(sch_1):page23_i172:ddr0_dq(51)" )
			)
			( pin "U5D1.L32"
				( objectStatus "@baseboard_fab2_lib.baseboard_fab2(sch_1):page23_i172:ddr0_dq(52)" )
			)
			( pin "U5D1.N32"
				( objectStatus "@baseboard_fab2_lib.baseboard_fab2(sch_1):page23_i172:ddr0_dq(53)" )
			)
			( pin "U5D1.K29"
				( objectStatus "@baseboard_fab2_lib.baseboard_fab2(sch_1):page23_i172:ddr0_dq(54)" )
			)
			( pin "U5D1.P29"
				( objectStatus "@baseboard_fab2_lib.baseboard_fab2(sch_1):page23_i172:ddr0_dq(55)" )
			)
			( pin "U5D1.K25"
				( objectStatus "@baseboard_fab2_lib.baseboard_fab2(sch_1):page23_i172:ddr0_dq(56)" )
			)
			( pin "U5D1.P25"
				( objectStatus "@baseboard_fab2_lib.baseboard_fab2(sch_1):page23_i172:ddr0_dq(57)" )
			)
			( pin "U5D1.P23"
				( objectStatus "@baseboard_fab2_lib.baseboard_fab2(sch_1):page23_i172:ddr0_dq(58)" )
			)
			( pin "U5D1.T23"
				( objectStatus "@baseboard_fab2_lib.baseboard_fab2(sch_1):page23_i172:ddr0_dq(59)" )
			)
			( pin "U5D1.L26"
				( objectStatus "@baseboard_fab2_lib.baseboard_fab2(sch_1):page23_i172:ddr0_dq(60)" )
			)
			( pin "U5D1.N26"
				( objectStatus "@baseboard_fab2_lib.baseboard_fab2(sch_1):page23_i172:ddr0_dq(61)" )
			)
			( pin "U5D1.H23"
				( objectStatus "@baseboard_fab2_lib.baseboard_fab2(sch_1):page23_i172:ddr0_dq(62)" )
			)
			( pin "U5D1.K23"
				( objectStatus "@baseboard_fab2_lib.baseboard_fab2(sch_1):page23_i172:ddr0_dq(63)" )
			)
			( pin "U5D1.AJ84"
				( objectStatus "@baseboard_fab2_lib.baseboard_fab2(sch_1):page23_i172:ddr0_dqs_dn(0)" )
			)
			( pin "U5D1.R84"
				( objectStatus "@baseboard_fab2_lib.baseboard_fab2(sch_1):page23_i172:ddr0_dqs_dn(1)" )
			)
			( pin "U5D1.P79"
				( objectStatus "@baseboard_fab2_lib.baseboard_fab2(sch_1):page23_i172:ddr0_dqs_dn(2)" )
			)
			( pin "U5D1.T75"
				( objectStatus "@baseboard_fab2_lib.baseboard_fab2(sch_1):page23_i172:ddr0_dqs_dn(3)" )
			)
			( pin "U5D1.G40"
				( objectStatus "@baseboard_fab2_lib.baseboard_fab2(sch_1):page23_i172:ddr0_dqs_dn(4)" )
			)
			( pin "U5D1.R36"
				( objectStatus "@baseboard_fab2_lib.baseboard_fab2(sch_1):page23_i172:ddr0_dqs_dn(5)" )
			)
			( pin "U5D1.R30"
				( objectStatus "@baseboard_fab2_lib.baseboard_fab2(sch_1):page23_i172:ddr0_dqs_dn(6)" )
			)
			( pin "U5D1.N24"
				( objectStatus "@baseboard_fab2_lib.baseboard_fab2(sch_1):page23_i172:ddr0_dqs_dn(7)" )
			)
			( pin "U5D1.AH67"
				( objectStatus "@baseboard_fab2_lib.baseboard_fab2(sch_1):page23_i172:ddr0_dqs_dn(8)" )
			)
			( pin "U5D1.AL84"
				( objectStatus "@baseboard_fab2_lib.baseboard_fab2(sch_1):page23_i172:ddr0_dqs_dn(9)" )
			)
			( pin "U5D1.U84"
				( objectStatus "@baseboard_fab2_lib.baseboard_fab2(sch_1):page23_i172:ddr0_dqs_dn(10)" )
			)
			( pin "U5D1.U82"
				( objectStatus "@baseboard_fab2_lib.baseboard_fab2(sch_1):page23_i172:ddr0_dqs_dn(11)" )
			)
			( pin "U5D1.K75"
				( objectStatus "@baseboard_fab2_lib.baseboard_fab2(sch_1):page23_i172:ddr0_dqs_dn(12)" )
			)
			( pin "U5D1.A40"
				( objectStatus "@baseboard_fab2_lib.baseboard_fab2(sch_1):page23_i172:ddr0_dqs_dn(13)" )
			)
			( pin "U5D1.J36"
				( objectStatus "@baseboard_fab2_lib.baseboard_fab2(sch_1):page23_i172:ddr0_dqs_dn(14)" )
			)
			( pin "U5D1.J30"
				( objectStatus "@baseboard_fab2_lib.baseboard_fab2(sch_1):page23_i172:ddr0_dqs_dn(15)" )
			)
			( pin "U5D1.J24"
				( objectStatus "@baseboard_fab2_lib.baseboard_fab2(sch_1):page23_i172:ddr0_dqs_dn(16)" )
			)
			( pin "U5D1.AB67"
				( objectStatus "@baseboard_fab2_lib.baseboard_fab2(sch_1):page23_i172:ddr0_dqs_dn(17)" )
			)
			( pin "U5D1.AH85"
				( objectStatus "@baseboard_fab2_lib.baseboard_fab2(sch_1):page23_i172:ddr0_dqs_dp(0)" )
			)
			( pin "U5D1.P85"
				( objectStatus "@baseboard_fab2_lib.baseboard_fab2(sch_1):page23_i172:ddr0_dqs_dp(1)" )
			)
			( pin "U5D1.R80"
				( objectStatus "@baseboard_fab2_lib.baseboard_fab2(sch_1):page23_i172:ddr0_dqs_dp(2)" )
			)
			( pin "U5D1.P75"
				( objectStatus "@baseboard_fab2_lib.baseboard_fab2(sch_1):page23_i172:ddr0_dqs_dp(3)" )
			)
			( pin "U5D1.E40"
				( objectStatus "@baseboard_fab2_lib.baseboard_fab2(sch_1):page23_i172:ddr0_dqs_dp(4)" )
			)
			( pin "U5D1.N36"
				( objectStatus "@baseboard_fab2_lib.baseboard_fab2(sch_1):page23_i172:ddr0_dqs_dp(5)" )
			)
			( pin "U5D1.N30"
				( objectStatus "@baseboard_fab2_lib.baseboard_fab2(sch_1):page23_i172:ddr0_dqs_dp(6)" )
			)
			( pin "U5D1.R24"
				( objectStatus "@baseboard_fab2_lib.baseboard_fab2(sch_1):page23_i172:ddr0_dqs_dp(7)" )
			)
			( pin "U5D1.AF67"
				( objectStatus "@baseboard_fab2_lib.baseboard_fab2(sch_1):page23_i172:ddr0_dqs_dp(8)" )
			)
			( pin "U5D1.AM85"
				( objectStatus "@baseboard_fab2_lib.baseboard_fab2(sch_1):page23_i172:ddr0_dqs_dp(9)" )
			)
			( pin "U5D1.V85"
				( objectStatus "@baseboard_fab2_lib.baseboard_fab2(sch_1):page23_i172:ddr0_dqs_dp(10)" )
			)
			( pin "U5D1.T81"
				( objectStatus "@baseboard_fab2_lib.baseboard_fab2(sch_1):page23_i172:ddr0_dqs_dp(11)" )
			)
			( pin "U5D1.M75"
				( objectStatus "@baseboard_fab2_lib.baseboard_fab2(sch_1):page23_i172:ddr0_dqs_dp(12)" )
			)
			( pin "U5D1.C40"
				( objectStatus "@baseboard_fab2_lib.baseboard_fab2(sch_1):page23_i172:ddr0_dqs_dp(13)" )
			)
			( pin "U5D1.L36"
				( objectStatus "@baseboard_fab2_lib.baseboard_fab2(sch_1):page23_i172:ddr0_dqs_dp(14)" )
			)
			( pin "U5D1.L30"
				( objectStatus "@baseboard_fab2_lib.baseboard_fab2(sch_1):page23_i172:ddr0_dqs_dp(15)" )
			)
			( pin "U5D1.L24"
				( objectStatus "@baseboard_fab2_lib.baseboard_fab2(sch_1):page23_i172:ddr0_dqs_dp(16)" )
			)
			( pin "U5D1.AD67"
				( objectStatus "@baseboard_fab2_lib.baseboard_fab2(sch_1):page23_i172:ddr0_dqs_dp(17)" )
			)
			( pin "U5D1.AC68"
				( objectStatus "@baseboard_fab2_lib.baseboard_fab2(sch_1):page23_i172:ddr0_ecc(0)" )
			)
			( pin "U5D1.AG68"
				( objectStatus "@baseboard_fab2_lib.baseboard_fab2(sch_1):page23_i172:ddr0_ecc(1)" )
			)
			( pin "U5D1.AD65"
				( objectStatus "@baseboard_fab2_lib.baseboard_fab2(sch_1):page23_i172:ddr0_ecc(2)" )
			)
			( pin "U5D1.AF65"
				( objectStatus "@baseboard_fab2_lib.baseboard_fab2(sch_1):page23_i172:ddr0_ecc(3)" )
			)
			( pin "U5D1.AD69"
				( objectStatus "@baseboard_fab2_lib.baseboard_fab2(sch_1):page23_i172:ddr0_ecc(4)" )
			)
			( pin "U5D1.AF69"
				( objectStatus "@baseboard_fab2_lib.baseboard_fab2(sch_1):page23_i172:ddr0_ecc(5)" )
			)
			( pin "U5D1.AC66"
				( objectStatus "@baseboard_fab2_lib.baseboard_fab2(sch_1):page23_i172:ddr0_ecc(6)" )
			)
			( pin "U5D1.AG66"
				( objectStatus "@baseboard_fab2_lib.baseboard_fab2(sch_1):page23_i172:ddr0_ecc(7)" )
			)
			( pin "U5D1.F53"
				( objectStatus "@baseboard_fab2_lib.baseboard_fab2(sch_1):page23_i172:ddr0_ma(0)" )
			)
			( pin "U5D1.F57"
				( objectStatus "@baseboard_fab2_lib.baseboard_fab2(sch_1):page23_i172:ddr0_ma(1)" )
			)
			( pin "U5D1.D57"
				( objectStatus "@baseboard_fab2_lib.baseboard_fab2(sch_1):page23_i172:ddr0_ma(2)" )
			)
			( pin "U5D1.C58"
				( objectStatus "@baseboard_fab2_lib.baseboard_fab2(sch_1):page23_i172:ddr0_ma(3)" )
			)
			( pin "U5D1.G58"
				( objectStatus "@baseboard_fab2_lib.baseboard_fab2(sch_1):page23_i172:ddr0_ma(4)" )
			)
			( pin "U5D1.F59"
				( objectStatus "@baseboard_fab2_lib.baseboard_fab2(sch_1):page23_i172:ddr0_ma(5)" )
			)
			( pin "U5D1.D59"
				( objectStatus "@baseboard_fab2_lib.baseboard_fab2(sch_1):page23_i172:ddr0_ma(6)" )
			)
			( pin "U5D1.G60"
				( objectStatus "@baseboard_fab2_lib.baseboard_fab2(sch_1):page23_i172:ddr0_ma(7)" )
			)
			( pin "U5D1.C60"
				( objectStatus "@baseboard_fab2_lib.baseboard_fab2(sch_1):page23_i172:ddr0_ma(8)" )
			)
			( pin "U5D1.F61"
				( objectStatus "@baseboard_fab2_lib.baseboard_fab2(sch_1):page23_i172:ddr0_ma(9)" )
			)
			( pin "U5D1.J54"
				( objectStatus "@baseboard_fab2_lib.baseboard_fab2(sch_1):page23_i172:ddr0_ma(10)" )
			)
			( pin "U5D1.G62"
				( objectStatus "@baseboard_fab2_lib.baseboard_fab2(sch_1):page23_i172:ddr0_ma(11)" )
			)
			( pin "U5D1.J64"
				( objectStatus "@baseboard_fab2_lib.baseboard_fab2(sch_1):page23_i172:ddr0_ma(12)" )
			)
			( pin "U5D1.J48"
				( objectStatus "@baseboard_fab2_lib.baseboard_fab2(sch_1):page23_i172:ddr0_ma(13)" )
			)
			( pin "U5D1.F51"
				( objectStatus "@baseboard_fab2_lib.baseboard_fab2(sch_1):page23_i172:ddr0_ma(14)" )
			)
			( pin "U5D1.K49"
				( objectStatus "@baseboard_fab2_lib.baseboard_fab2(sch_1):page23_i172:ddr0_ma(15)" )
			)
			( pin "U5D1.D51"
				( objectStatus "@baseboard_fab2_lib.baseboard_fab2(sch_1):page23_i172:ddr0_ma(16)" )
			)
			( pin "U5D1.K47"
				( objectStatus "@baseboard_fab2_lib.baseboard_fab2(sch_1):page23_i172:ddr0_ma(17)" )
			)
			( pin "U5D1.C50"
				( objectStatus "@baseboard_fab2_lib.baseboard_fab2(sch_1):page23_i172:ddr0_odt(0)" )
			)
			( pin "U5D1.C48"
				( objectStatus "@baseboard_fab2_lib.baseboard_fab2(sch_1):page23_i172:ddr0_odt(1)" )
			)
			( pin "U5D1.G50"
				( objectStatus "@baseboard_fab2_lib.baseboard_fab2(sch_1):page23_i172:ddr0_odt(2)" )
			)
			( pin "U5D1.G48"
				( objectStatus "@baseboard_fab2_lib.baseboard_fab2(sch_1):page23_i172:ddr0_odt(3)" )
			)
			( pin "U5D1.D53"
				( objectStatus "@baseboard_fab2_lib.baseboard_fab2(sch_1):page23_i172:ddr0_par" )
			)
			( pin "U5D1.T63"
				( objectStatus "@baseboard_fab2_lib.baseboard_fab2(sch_1):page24_i172:ddr1_act_n" )
			)
			( pin "U5D1.W62"
				( objectStatus "@baseboard_fab2_lib.baseboard_fab2(sch_1):page24_i172:ddr1_alert_n" )
			)
			( pin "U5D1.T53"
				( objectStatus "@baseboard_fab2_lib.baseboard_fab2(sch_1):page24_i172:ddr1_ba(0)" )
			)
			( pin "U5D1.K55"
				( objectStatus "@baseboard_fab2_lib.baseboard_fab2(sch_1):page24_i172:ddr1_ba(1)" )
			)
			( pin "U5D1.M61"
				( objectStatus "@baseboard_fab2_lib.baseboard_fab2(sch_1):page24_i172:ddr1_bg(0)" )
			)
			( pin "U5D1.N60"
				( objectStatus "@baseboard_fab2_lib.baseboard_fab2(sch_1):page24_i172:ddr1_bg(1)" )
			)
			( pin "U5D1.M47"
				( objectStatus "@baseboard_fab2_lib.baseboard_fab2(sch_1):page24_i172:ddr1_cid(2)" )
			)
			( pin "U5D1.N62"
				( objectStatus "@baseboard_fab2_lib.baseboard_fab2(sch_1):page24_i172:ddr1_cke(0)" )
			)
			( pin "U5D1.R64"
				( objectStatus "@baseboard_fab2_lib.baseboard_fab2(sch_1):page24_i172:ddr1_cke(1)" )
			)
			( pin "U5D1.K63"
				( objectStatus "@baseboard_fab2_lib.baseboard_fab2(sch_1):page24_i172:ddr1_cke(2)" )
			)
			( pin "U5D1.L64"
				( objectStatus "@baseboard_fab2_lib.baseboard_fab2(sch_1):page24_i172:ddr1_cke(3)" )
			)
			( pin "U5D1.M53"
				( objectStatus "@baseboard_fab2_lib.baseboard_fab2(sch_1):page24_i172:ddr1_clk_dn(0)" )
			)
			( pin "U5D1.R54"
				( objectStatus "@baseboard_fab2_lib.baseboard_fab2(sch_1):page24_i172:ddr1_clk_dn(1)" )
			)
			( pin "U5D1.N56"
				( objectStatus "@baseboard_fab2_lib.baseboard_fab2(sch_1):page24_i172:ddr1_clk_dn(2)" )
			)
			( pin "U5D1.R56"
				( objectStatus "@baseboard_fab2_lib.baseboard_fab2(sch_1):page24_i172:ddr1_clk_dn(3)" )
			)
			( pin "U5D1.N54"
				( objectStatus "@baseboard_fab2_lib.baseboard_fab2(sch_1):page24_i172:ddr1_clk_dp(0)" )
			)
			( pin "U5D1.T55"
				( objectStatus "@baseboard_fab2_lib.baseboard_fab2(sch_1):page24_i172:ddr1_clk_dp(1)" )
			)
			( pin "U5D1.M57"
				( objectStatus "@baseboard_fab2_lib.baseboard_fab2(sch_1):page24_i172:ddr1_clk_dp(2)" )
			)
			( pin "U5D1.T57"
				( objectStatus "@baseboard_fab2_lib.baseboard_fab2(sch_1):page24_i172:ddr1_clk_dp(3)" )
			)
			( pin "U5D1.K51"
				( objectStatus "@baseboard_fab2_lib.baseboard_fab2(sch_1):page24_i172:ddr1_cs_n(0)" )
			)
			( pin "U5D1.R50"
				( objectStatus "@baseboard_fab2_lib.baseboard_fab2(sch_1):page24_i172:ddr1_cs_n(1)" )
			)
			( pin "U5D1.N46"
				( objectStatus "@baseboard_fab2_lib.baseboard_fab2(sch_1):page24_i172:ddr1_cs_n(2)" )
			)
			( pin "U5D1.V47"
				( objectStatus "@baseboard_fab2_lib.baseboard_fab2(sch_1):page24_i172:ddr1_cs_n(3)" )
			)
			( pin "U5D1.J50"
				( objectStatus "@baseboard_fab2_lib.baseboard_fab2(sch_1):page24_i172:ddr1_cs_n(4)" )
			)
			( pin "U5D1.T49"
				( objectStatus "@baseboard_fab2_lib.baseboard_fab2(sch_1):page24_i172:ddr1_cs_n(5)" )
			)
			( pin "U5D1.M45"
				( objectStatus "@baseboard_fab2_lib.baseboard_fab2(sch_1):page24_i172:ddr1_cs_n(6)" )
			)
			( pin "U5D1.R46"
				( objectStatus "@baseboard_fab2_lib.baseboard_fab2(sch_1):page24_i172:ddr1_cs_n(7)" )
			)
			( pin "U5D1.AV81"
				( objectStatus "@baseboard_fab2_lib.baseboard_fab2(sch_1):page24_i172:ddr1_dq(0)" )
			)
			( pin "U5D1.AT79"
				( objectStatus "@baseboard_fab2_lib.baseboard_fab2(sch_1):page24_i172:ddr1_dq(1)" )
			)
			( pin "U5D1.AN82"
				( objectStatus "@baseboard_fab2_lib.baseboard_fab2(sch_1):page24_i172:ddr1_dq(2)" )
			)
			( pin "U5D1.AM81"
				( objectStatus "@baseboard_fab2_lib.baseboard_fab2(sch_1):page24_i172:ddr1_dq(3)" )
			)
			( pin "U5D1.AW80"
				( objectStatus "@baseboard_fab2_lib.baseboard_fab2(sch_1):page24_i172:ddr1_dq(4)" )
			)
			( pin "U5D1.AV79"
				( objectStatus "@baseboard_fab2_lib.baseboard_fab2(sch_1):page24_i172:ddr1_dq(5)" )
			)
			( pin "U5D1.AR82"
				( objectStatus "@baseboard_fab2_lib.baseboard_fab2(sch_1):page24_i172:ddr1_dq(6)" )
			)
			( pin "U5D1.AN80"
				( objectStatus "@baseboard_fab2_lib.baseboard_fab2(sch_1):page24_i172:ddr1_dq(7)" )
			)
			( pin "U5D1.AH81"
				( objectStatus "@baseboard_fab2_lib.baseboard_fab2(sch_1):page24_i172:ddr1_dq(8)" )
			)
			( pin "U5D1.AF79"
				( objectStatus "@baseboard_fab2_lib.baseboard_fab2(sch_1):page24_i172:ddr1_dq(9)" )
			)
			( pin "U5D1.AC82"
				( objectStatus "@baseboard_fab2_lib.baseboard_fab2(sch_1):page24_i172:ddr1_dq(10)" )
			)
			( pin "U5D1.AB81"
				( objectStatus "@baseboard_fab2_lib.baseboard_fab2(sch_1):page24_i172:ddr1_dq(11)" )
			)
			( pin "U5D1.AJ80"
				( objectStatus "@baseboard_fab2_lib.baseboard_fab2(sch_1):page24_i172:ddr1_dq(12)" )
			)
			( pin "U5D1.AH79"
				( objectStatus "@baseboard_fab2_lib.baseboard_fab2(sch_1):page24_i172:ddr1_dq(13)" )
			)
			( pin "U5D1.AE82"
				( objectStatus "@baseboard_fab2_lib.baseboard_fab2(sch_1):page24_i172:ddr1_dq(14)" )
			)
			( pin "U5D1.AC80"
				( objectStatus "@baseboard_fab2_lib.baseboard_fab2(sch_1):page24_i172:ddr1_dq(15)" )
			)
			( pin "U5D1.E80"
				( objectStatus "@baseboard_fab2_lib.baseboard_fab2(sch_1):page24_i172:ddr1_dq(16)" )
			)
			( pin "U5D1.J80"
				( objectStatus "@baseboard_fab2_lib.baseboard_fab2(sch_1):page24_i172:ddr1_dq(17)" )
			)
			( pin "U5D1.F77"
				( objectStatus "@baseboard_fab2_lib.baseboard_fab2(sch_1):page24_i172:ddr1_dq(18)" )
			)
			( pin "U5D1.H77"
				( objectStatus "@baseboard_fab2_lib.baseboard_fab2(sch_1):page24_i172:ddr1_dq(19)" )
			)
			( pin "U5D1.F81"
				( objectStatus "@baseboard_fab2_lib.baseboard_fab2(sch_1):page24_i172:ddr1_dq(20)" )
			)
			( pin "U5D1.H81"
				( objectStatus "@baseboard_fab2_lib.baseboard_fab2(sch_1):page24_i172:ddr1_dq(21)" )
			)
			( pin "U5D1.E78"
				( objectStatus "@baseboard_fab2_lib.baseboard_fab2(sch_1):page24_i172:ddr1_dq(22)" )
			)
			( pin "U5D1.J78"
				( objectStatus "@baseboard_fab2_lib.baseboard_fab2(sch_1):page24_i172:ddr1_dq(23)" )
			)
			( pin "U5D1.D75"
				( objectStatus "@baseboard_fab2_lib.baseboard_fab2(sch_1):page24_i172:ddr1_dq(24)" )
			)
			( pin "U5D1.C74"
				( objectStatus "@baseboard_fab2_lib.baseboard_fab2(sch_1):page24_i172:ddr1_dq(25)" )
			)
			( pin "U5D1.D71"
				( objectStatus "@baseboard_fab2_lib.baseboard_fab2(sch_1):page24_i172:ddr1_dq(26)" )
			)
			( pin "U5D1.F71"
				( objectStatus "@baseboard_fab2_lib.baseboard_fab2(sch_1):page24_i172:ddr1_dq(27)" )
			)
			( pin "U5D1.F75"
				( objectStatus "@baseboard_fab2_lib.baseboard_fab2(sch_1):page24_i172:ddr1_dq(28)" )
			)
			( pin "U5D1.G74"
				( objectStatus "@baseboard_fab2_lib.baseboard_fab2(sch_1):page24_i172:ddr1_dq(29)" )
			)
			( pin "U5D1.C72"
				( objectStatus "@baseboard_fab2_lib.baseboard_fab2(sch_1):page24_i172:ddr1_dq(30)" )
			)
			( pin "U5D1.G72"
				( objectStatus "@baseboard_fab2_lib.baseboard_fab2(sch_1):page24_i172:ddr1_dq(31)" )
			)
			( pin "U5D1.K43"
				( objectStatus "@baseboard_fab2_lib.baseboard_fab2(sch_1):page24_i172:ddr1_dq(32)" )
			)
			( pin "U5D1.H43"
				( objectStatus "@baseboard_fab2_lib.baseboard_fab2(sch_1):page24_i172:ddr1_dq(33)" )
			)
			( pin "U5D1.L40"
				( objectStatus "@baseboard_fab2_lib.baseboard_fab2(sch_1):page24_i172:ddr1_dq(34)" )
			)
			( pin "U5D1.N40"
				( objectStatus "@baseboard_fab2_lib.baseboard_fab2(sch_1):page24_i172:ddr1_dq(35)" )
			)
			( pin "U5D1.P43"
				( objectStatus "@baseboard_fab2_lib.baseboard_fab2(sch_1):page24_i172:ddr1_dq(36)" )
			)
			( pin "U5D1.T43"
				( objectStatus "@baseboard_fab2_lib.baseboard_fab2(sch_1):page24_i172:ddr1_dq(37)" )
			)
			( pin "U5D1.K41"
				( objectStatus "@baseboard_fab2_lib.baseboard_fab2(sch_1):page24_i172:ddr1_dq(38)" )
			)
			( pin "U5D1.P41"
				( objectStatus "@baseboard_fab2_lib.baseboard_fab2(sch_1):page24_i172:ddr1_dq(39)" )
			)
			( pin "U5D1.C36"
				( objectStatus "@baseboard_fab2_lib.baseboard_fab2(sch_1):page24_i172:ddr1_dq(40)" )
			)
			( pin "U5D1.B35"
				( objectStatus "@baseboard_fab2_lib.baseboard_fab2(sch_1):page24_i172:ddr1_dq(41)" )
			)
			( pin "U5D1.C32"
				( objectStatus "@baseboard_fab2_lib.baseboard_fab2(sch_1):page24_i172:ddr1_dq(42)" )
			)
			( pin "U5D1.E32"
				( objectStatus "@baseboard_fab2_lib.baseboard_fab2(sch_1):page24_i172:ddr1_dq(43)" )
			)
			( pin "U5D1.E36"
				( objectStatus "@baseboard_fab2_lib.baseboard_fab2(sch_1):page24_i172:ddr1_dq(44)" )
			)
			( pin "U5D1.F35"
				( objectStatus "@baseboard_fab2_lib.baseboard_fab2(sch_1):page24_i172:ddr1_dq(45)" )
			)
			( pin "U5D1.B33"
				( objectStatus "@baseboard_fab2_lib.baseboard_fab2(sch_1):page24_i172:ddr1_dq(46)" )
			)
			( pin "U5D1.F33"
				( objectStatus "@baseboard_fab2_lib.baseboard_fab2(sch_1):page24_i172:ddr1_dq(47)" )
			)
			( pin "U5D1.C30"
				( objectStatus "@baseboard_fab2_lib.baseboard_fab2(sch_1):page24_i172:ddr1_dq(48)" )
			)
			( pin "U5D1.B29"
				( objectStatus "@baseboard_fab2_lib.baseboard_fab2(sch_1):page24_i172:ddr1_dq(49)" )
			)
			( pin "U5D1.C26"
				( objectStatus "@baseboard_fab2_lib.baseboard_fab2(sch_1):page24_i172:ddr1_dq(50)" )
			)
			( pin "U5D1.E26"
				( objectStatus "@baseboard_fab2_lib.baseboard_fab2(sch_1):page24_i172:ddr1_dq(51)" )
			)
			( pin "U5D1.E30"
				( objectStatus "@baseboard_fab2_lib.baseboard_fab2(sch_1):page24_i172:ddr1_dq(52)" )
			)
			( pin "U5D1.F29"
				( objectStatus "@baseboard_fab2_lib.baseboard_fab2(sch_1):page24_i172:ddr1_dq(53)" )
			)
			( pin "U5D1.B27"
				( objectStatus "@baseboard_fab2_lib.baseboard_fab2(sch_1):page24_i172:ddr1_dq(54)" )
			)
			( pin "U5D1.F27"
				( objectStatus "@baseboard_fab2_lib.baseboard_fab2(sch_1):page24_i172:ddr1_dq(55)" )
			)
			( pin "U5D1.U28"
				( objectStatus "@baseboard_fab2_lib.baseboard_fab2(sch_1):page24_i172:ddr1_dq(56)" )
			)
			( pin "U5D1.AA28"
				( objectStatus "@baseboard_fab2_lib.baseboard_fab2(sch_1):page24_i172:ddr1_dq(57)" )
			)
			( pin "U5D1.V25"
				( objectStatus "@baseboard_fab2_lib.baseboard_fab2(sch_1):page24_i172:ddr1_dq(58)" )
			)
			( pin "U5D1.Y25"
				( objectStatus "@baseboard_fab2_lib.baseboard_fab2(sch_1):page24_i172:ddr1_dq(59)" )
			)
			( pin "U5D1.V29"
				( objectStatus "@baseboard_fab2_lib.baseboard_fab2(sch_1):page24_i172:ddr1_dq(60)" )
			)
			( pin "U5D1.Y29"
				( objectStatus "@baseboard_fab2_lib.baseboard_fab2(sch_1):page24_i172:ddr1_dq(61)" )
			)
			( pin "U5D1.U26"
				( objectStatus "@baseboard_fab2_lib.baseboard_fab2(sch_1):page24_i172:ddr1_dq(62)" )
			)
			( pin "U5D1.AA26"
				( objectStatus "@baseboard_fab2_lib.baseboard_fab2(sch_1):page24_i172:ddr1_dq(63)" )
			)
			( pin "U5D1.AP79"
				( objectStatus "@baseboard_fab2_lib.baseboard_fab2(sch_1):page24_i172:ddr1_dqs_dn(0)" )
			)
			( pin "U5D1.AD79"
				( objectStatus "@baseboard_fab2_lib.baseboard_fab2(sch_1):page24_i172:ddr1_dqs_dn(1)" )
			)
			( pin "U5D1.K79"
				( objectStatus "@baseboard_fab2_lib.baseboard_fab2(sch_1):page24_i172:ddr1_dqs_dn(2)" )
			)
			( pin "U5D1.H73"
				( objectStatus "@baseboard_fab2_lib.baseboard_fab2(sch_1):page24_i172:ddr1_dqs_dn(3)" )
			)
			( pin "U5D1.N42"
				( objectStatus "@baseboard_fab2_lib.baseboard_fab2(sch_1):page24_i172:ddr1_dqs_dn(4)" )
			)
			( pin "U5D1.G34"
				( objectStatus "@baseboard_fab2_lib.baseboard_fab2(sch_1):page24_i172:ddr1_dqs_dn(5)" )
			)
			( pin "U5D1.G28"
				( objectStatus "@baseboard_fab2_lib.baseboard_fab2(sch_1):page24_i172:ddr1_dqs_dn(6)" )
			)
			( pin "U5D1.AB27"
				( objectStatus "@baseboard_fab2_lib.baseboard_fab2(sch_1):page24_i172:ddr1_dqs_dn(7)" )
			)
			( pin "U5D1.N68"
				( objectStatus "@baseboard_fab2_lib.baseboard_fab2(sch_1):page24_i172:ddr1_dqs_dn(8)" )
			)
			( pin "U5D1.AU82"
				( objectStatus "@baseboard_fab2_lib.baseboard_fab2(sch_1):page24_i172:ddr1_dqs_dn(9)" )
			)
			( pin "U5D1.AG82"
				( objectStatus "@baseboard_fab2_lib.baseboard_fab2(sch_1):page24_i172:ddr1_dqs_dn(10)" )
			)
			( pin "U5D1.D79"
				( objectStatus "@baseboard_fab2_lib.baseboard_fab2(sch_1):page24_i172:ddr1_dqs_dn(11)" )
			)
			( pin "U5D1.B73"
				( objectStatus "@baseboard_fab2_lib.baseboard_fab2(sch_1):page24_i172:ddr1_dqs_dn(12)" )
			)
			( pin "U5D1.J42"
				( objectStatus "@baseboard_fab2_lib.baseboard_fab2(sch_1):page24_i172:ddr1_dqs_dn(13)" )
			)
			( pin "U5D1.A34"
				( objectStatus "@baseboard_fab2_lib.baseboard_fab2(sch_1):page24_i172:ddr1_dqs_dn(14)" )
			)
			( pin "U5D1.A28"
				( objectStatus "@baseboard_fab2_lib.baseboard_fab2(sch_1):page24_i172:ddr1_dqs_dn(15)" )
			)
			( pin "U5D1.T27"
				( objectStatus "@baseboard_fab2_lib.baseboard_fab2(sch_1):page24_i172:ddr1_dqs_dn(16)" )
			)
			( pin "U5D1.G68"
				( objectStatus "@baseboard_fab2_lib.baseboard_fab2(sch_1):page24_i172:ddr1_dqs_dn(17)" )
			)
			( pin "U5D1.AR80"
				( objectStatus "@baseboard_fab2_lib.baseboard_fab2(sch_1):page24_i172:ddr1_dqs_dp(0)" )
			)
			( pin "U5D1.AE80"
				( objectStatus "@baseboard_fab2_lib.baseboard_fab2(sch_1):page24_i172:ddr1_dqs_dp(1)" )
			)
			( pin "U5D1.H79"
				( objectStatus "@baseboard_fab2_lib.baseboard_fab2(sch_1):page24_i172:ddr1_dqs_dp(2)" )
			)
			( pin "U5D1.F73"
				( objectStatus "@baseboard_fab2_lib.baseboard_fab2(sch_1):page24_i172:ddr1_dqs_dp(3)" )
			)
			( pin "U5D1.R42"
				( objectStatus "@baseboard_fab2_lib.baseboard_fab2(sch_1):page24_i172:ddr1_dqs_dp(4)" )
			)
			( pin "U5D1.E34"
				( objectStatus "@baseboard_fab2_lib.baseboard_fab2(sch_1):page24_i172:ddr1_dqs_dp(5)" )
			)
			( pin "U5D1.E28"
				( objectStatus "@baseboard_fab2_lib.baseboard_fab2(sch_1):page24_i172:ddr1_dqs_dp(6)" )
			)
			( pin "U5D1.Y27"
				( objectStatus "@baseboard_fab2_lib.baseboard_fab2(sch_1):page24_i172:ddr1_dqs_dp(7)" )
			)
			( pin "U5D1.L68"
				( objectStatus "@baseboard_fab2_lib.baseboard_fab2(sch_1):page24_i172:ddr1_dqs_dp(8)" )
			)
			( pin "U5D1.AT81"
				( objectStatus "@baseboard_fab2_lib.baseboard_fab2(sch_1):page24_i172:ddr1_dqs_dp(9)" )
			)
			( pin "U5D1.AF81"
				( objectStatus "@baseboard_fab2_lib.baseboard_fab2(sch_1):page24_i172:ddr1_dqs_dp(10)" )
			)
			( pin "U5D1.F79"
				( objectStatus "@baseboard_fab2_lib.baseboard_fab2(sch_1):page24_i172:ddr1_dqs_dp(11)" )
			)
			( pin "U5D1.D73"
				( objectStatus "@baseboard_fab2_lib.baseboard_fab2(sch_1):page24_i172:ddr1_dqs_dp(12)" )
			)
			( pin "U5D1.L42"
				( objectStatus "@baseboard_fab2_lib.baseboard_fab2(sch_1):page24_i172:ddr1_dqs_dp(13)" )
			)
			( pin "U5D1.C34"
				( objectStatus "@baseboard_fab2_lib.baseboard_fab2(sch_1):page24_i172:ddr1_dqs_dp(14)" )
			)
			( pin "U5D1.C28"
				( objectStatus "@baseboard_fab2_lib.baseboard_fab2(sch_1):page24_i172:ddr1_dqs_dp(15)" )
			)
			( pin "U5D1.V27"
				( objectStatus "@baseboard_fab2_lib.baseboard_fab2(sch_1):page24_i172:ddr1_dqs_dp(16)" )
			)
			( pin "U5D1.J68"
				( objectStatus "@baseboard_fab2_lib.baseboard_fab2(sch_1):page24_i172:ddr1_dqs_dp(17)" )
			)
			( pin "U5D1.J70"
				( objectStatus "@baseboard_fab2_lib.baseboard_fab2(sch_1):page24_i172:ddr1_ecc(0)" )
			)
			( pin "U5D1.H69"
				( objectStatus "@baseboard_fab2_lib.baseboard_fab2(sch_1):page24_i172:ddr1_ecc(1)" )
			)
			( pin "U5D1.J66"
				( objectStatus "@baseboard_fab2_lib.baseboard_fab2(sch_1):page24_i172:ddr1_ecc(2)" )
			)
			( pin "U5D1.L66"
				( objectStatus "@baseboard_fab2_lib.baseboard_fab2(sch_1):page24_i172:ddr1_ecc(3)" )
			)
			( pin "U5D1.L70"
				( objectStatus "@baseboard_fab2_lib.baseboard_fab2(sch_1):page24_i172:ddr1_ecc(4)" )
			)
			( pin "U5D1.M69"
				( objectStatus "@baseboard_fab2_lib.baseboard_fab2(sch_1):page24_i172:ddr1_ecc(5)" )
			)
			( pin "U5D1.H67"
				( objectStatus "@baseboard_fab2_lib.baseboard_fab2(sch_1):page24_i172:ddr1_ecc(6)" )
			)
			( pin "U5D1.M67"
				( objectStatus "@baseboard_fab2_lib.baseboard_fab2(sch_1):page24_i172:ddr1_ecc(7)" )
			)
			( pin "U5D1.J52"
				( objectStatus "@baseboard_fab2_lib.baseboard_fab2(sch_1):page24_i172:ddr1_ma(0)" )
			)
			( pin "U5D1.J58"
				( objectStatus "@baseboard_fab2_lib.baseboard_fab2(sch_1):page24_i172:ddr1_ma(1)" )
			)
			( pin "U5D1.K57"
				( objectStatus "@baseboard_fab2_lib.baseboard_fab2(sch_1):page24_i172:ddr1_ma(2)" )
			)
			( pin "U5D1.N58"
				( objectStatus "@baseboard_fab2_lib.baseboard_fab2(sch_1):page24_i172:ddr1_ma(3)" )
			)
			( pin "U5D1.M59"
				( objectStatus "@baseboard_fab2_lib.baseboard_fab2(sch_1):page24_i172:ddr1_ma(4)" )
			)
			( pin "U5D1.R58"
				( objectStatus "@baseboard_fab2_lib.baseboard_fab2(sch_1):page24_i172:ddr1_ma(5)" )
			)
			( pin "U5D1.T59"
				( objectStatus "@baseboard_fab2_lib.baseboard_fab2(sch_1):page24_i172:ddr1_ma(6)" )
			)
			( pin "U5D1.V61"
				( objectStatus "@baseboard_fab2_lib.baseboard_fab2(sch_1):page24_i172:ddr1_ma(7)" )
			)
			( pin "U5D1.W60"
				( objectStatus "@baseboard_fab2_lib.baseboard_fab2(sch_1):page24_i172:ddr1_ma(8)" )
			)
			( pin "U5D1.K59"
				( objectStatus "@baseboard_fab2_lib.baseboard_fab2(sch_1):page24_i172:ddr1_ma(9)" )
			)
			( pin "U5D1.M55"
				( objectStatus "@baseboard_fab2_lib.baseboard_fab2(sch_1):page24_i172:ddr1_ma(10)" )
			)
			( pin "U5D1.R60"
				( objectStatus "@baseboard_fab2_lib.baseboard_fab2(sch_1):page24_i172:ddr1_ma(11)" )
			)
			( pin "U5D1.T61"
				( objectStatus "@baseboard_fab2_lib.baseboard_fab2(sch_1):page24_i172:ddr1_ma(12)" )
			)
			( pin "U5D1.M51"
				( objectStatus "@baseboard_fab2_lib.baseboard_fab2(sch_1):page24_i172:ddr1_ma(13)" )
			)
			( pin "U5D1.T51"
				( objectStatus "@baseboard_fab2_lib.baseboard_fab2(sch_1):page24_i172:ddr1_ma(14)" )
			)
			( pin "U5D1.N52"
				( objectStatus "@baseboard_fab2_lib.baseboard_fab2(sch_1):page24_i172:ddr1_ma(15)" )
			)
			( pin "U5D1.R52"
				( objectStatus "@baseboard_fab2_lib.baseboard_fab2(sch_1):page24_i172:ddr1_ma(16)" )
			)
			( pin "U5D1.N48"
				( objectStatus "@baseboard_fab2_lib.baseboard_fab2(sch_1):page24_i172:ddr1_ma(17)" )
			)
			( pin "U5D1.N50"
				( objectStatus "@baseboard_fab2_lib.baseboard_fab2(sch_1):page24_i172:ddr1_odt(0)" )
			)
			( pin "U5D1.R48"
				( objectStatus "@baseboard_fab2_lib.baseboard_fab2(sch_1):page24_i172:ddr1_odt(1)" )
			)
			( pin "U5D1.M49"
				( objectStatus "@baseboard_fab2_lib.baseboard_fab2(sch_1):page24_i172:ddr1_odt(2)" )
			)
			( pin "U5D1.T47"
				( objectStatus "@baseboard_fab2_lib.baseboard_fab2(sch_1):page24_i172:ddr1_odt(3)" )
			)
			( pin "U5D1.K53"
				( objectStatus "@baseboard_fab2_lib.baseboard_fab2(sch_1):page24_i172:ddr1_par" )
			)
			( pin "U5D1.AB61"
				( objectStatus "@baseboard_fab2_lib.baseboard_fab2(sch_1):page25_i172:ddr2_act_n" )
			)
			( pin "U5D1.AD61"
				( objectStatus "@baseboard_fab2_lib.baseboard_fab2(sch_1):page25_i172:ddr2_alert_n" )
			)
			( pin "U5D1.W52"
				( objectStatus "@baseboard_fab2_lib.baseboard_fab2(sch_1):page25_i172:ddr2_ba(0)" )
			)
			( pin "U5D1.AE56"
				( objectStatus "@baseboard_fab2_lib.baseboard_fab2(sch_1):page25_i172:ddr2_ba(1)" )
			)
			( pin "U5D1.AA60"
				( objectStatus "@baseboard_fab2_lib.baseboard_fab2(sch_1):page25_i172:ddr2_bg(0)" )
			)
			( pin "U5D1.AE62"
				( objectStatus "@baseboard_fab2_lib.baseboard_fab2(sch_1):page25_i172:ddr2_bg(1)" )
			)
			( pin "U5D1.AB45"
				( objectStatus "@baseboard_fab2_lib.baseboard_fab2(sch_1):page25_i172:ddr2_cid(2)" )
			)
			( pin "U5D1.AA62"
				( objectStatus "@baseboard_fab2_lib.baseboard_fab2(sch_1):page25_i172:ddr2_cke(0)" )
			)
			( pin "U5D1.AD63"
				( objectStatus "@baseboard_fab2_lib.baseboard_fab2(sch_1):page25_i172:ddr2_cke(1)" )
			)
			( pin "U5D1.V63"
				( objectStatus "@baseboard_fab2_lib.baseboard_fab2(sch_1):page25_i172:ddr2_cke(2)" )
			)
			( pin "U5D1.AB63"
				( objectStatus "@baseboard_fab2_lib.baseboard_fab2(sch_1):page25_i172:ddr2_cke(3)" )
			)
			( pin "U5D1.AA54"
				( objectStatus "@baseboard_fab2_lib.baseboard_fab2(sch_1):page25_i172:ddr2_clk_dn(0)" )
			)
			( pin "U5D1.W54"
				( objectStatus "@baseboard_fab2_lib.baseboard_fab2(sch_1):page25_i172:ddr2_clk_dn(1)" )
			)
			( pin "U5D1.AA56"
				( objectStatus "@baseboard_fab2_lib.baseboard_fab2(sch_1):page25_i172:ddr2_clk_dn(2)" )
			)
			( pin "U5D1.W56"
				( objectStatus "@baseboard_fab2_lib.baseboard_fab2(sch_1):page25_i172:ddr2_clk_dn(3)" )
			)
			( pin "U5D1.AB55"
				( objectStatus "@baseboard_fab2_lib.baseboard_fab2(sch_1):page25_i172:ddr2_clk_dp(0)" )
			)
			( pin "U5D1.V55"
				( objectStatus "@baseboard_fab2_lib.baseboard_fab2(sch_1):page25_i172:ddr2_clk_dp(1)" )
			)
			( pin "U5D1.AB57"
				( objectStatus "@baseboard_fab2_lib.baseboard_fab2(sch_1):page25_i172:ddr2_clk_dp(2)" )
			)
			( pin "U5D1.V57"
				( objectStatus "@baseboard_fab2_lib.baseboard_fab2(sch_1):page25_i172:ddr2_clk_dp(3)" )
			)
			( pin "U5D1.V51"
				( objectStatus "@baseboard_fab2_lib.baseboard_fab2(sch_1):page25_i172:ddr2_cs_n(0)" )
			)
			( pin "U5D1.AB49"
				( objectStatus "@baseboard_fab2_lib.baseboard_fab2(sch_1):page25_i172:ddr2_cs_n(1)" )
			)
			( pin "U5D1.W46"
				( objectStatus "@baseboard_fab2_lib.baseboard_fab2(sch_1):page25_i172:ddr2_cs_n(2)" )
			)
			( pin "U5D1.AA46"
				( objectStatus "@baseboard_fab2_lib.baseboard_fab2(sch_1):page25_i172:ddr2_cs_n(3)" )
			)
			( pin "U5D1.AB51"
				( objectStatus "@baseboard_fab2_lib.baseboard_fab2(sch_1):page25_i172:ddr2_cs_n(4)" )
			)
			( pin "U5D1.W48"
				( objectStatus "@baseboard_fab2_lib.baseboard_fab2(sch_1):page25_i172:ddr2_cs_n(5)" )
			)
			( pin "U5D1.T45"
				( objectStatus "@baseboard_fab2_lib.baseboard_fab2(sch_1):page25_i172:ddr2_cs_n(6)" )
			)
			( pin "U5D1.V45"
				( objectStatus "@baseboard_fab2_lib.baseboard_fab2(sch_1):page25_i172:ddr2_cs_n(7)" )
			)
			( pin "U5D1.AR76"
				( objectStatus "@baseboard_fab2_lib.baseboard_fab2(sch_1):page25_i172:ddr2_dq(0)" )
			)
			( pin "U5D1.AN74"
				( objectStatus "@baseboard_fab2_lib.baseboard_fab2(sch_1):page25_i172:ddr2_dq(1)" )
			)
			( pin "U5D1.AK77"
				( objectStatus "@baseboard_fab2_lib.baseboard_fab2(sch_1):page25_i172:ddr2_dq(2)" )
			)
			( pin "U5D1.AJ76"
				( objectStatus "@baseboard_fab2_lib.baseboard_fab2(sch_1):page25_i172:ddr2_dq(3)" )
			)
			( pin "U5D1.AT75"
				( objectStatus "@baseboard_fab2_lib.baseboard_fab2(sch_1):page25_i172:ddr2_dq(4)" )
			)
			( pin "U5D1.AR74"
				( objectStatus "@baseboard_fab2_lib.baseboard_fab2(sch_1):page25_i172:ddr2_dq(5)" )
			)
			( pin "U5D1.AM77"
				( objectStatus "@baseboard_fab2_lib.baseboard_fab2(sch_1):page25_i172:ddr2_dq(6)" )
			)
			( pin "U5D1.AK75"
				( objectStatus "@baseboard_fab2_lib.baseboard_fab2(sch_1):page25_i172:ddr2_dq(7)" )
			)
			( pin "U5D1.AE76"
				( objectStatus "@baseboard_fab2_lib.baseboard_fab2(sch_1):page25_i172:ddr2_dq(8)" )
			)
			( pin "U5D1.AC74"
				( objectStatus "@baseboard_fab2_lib.baseboard_fab2(sch_1):page25_i172:ddr2_dq(9)" )
			)
			( pin "U5D1.Y77"
				( objectStatus "@baseboard_fab2_lib.baseboard_fab2(sch_1):page25_i172:ddr2_dq(10)" )
			)
			( pin "U5D1.W76"
				( objectStatus "@baseboard_fab2_lib.baseboard_fab2(sch_1):page25_i172:ddr2_dq(11)" )
			)
			( pin "U5D1.AF75"
				( objectStatus "@baseboard_fab2_lib.baseboard_fab2(sch_1):page25_i172:ddr2_dq(12)" )
			)
			( pin "U5D1.AE74"
				( objectStatus "@baseboard_fab2_lib.baseboard_fab2(sch_1):page25_i172:ddr2_dq(13)" )
			)
			( pin "U5D1.AB77"
				( objectStatus "@baseboard_fab2_lib.baseboard_fab2(sch_1):page25_i172:ddr2_dq(14)" )
			)
			( pin "U5D1.Y75"
				( objectStatus "@baseboard_fab2_lib.baseboard_fab2(sch_1):page25_i172:ddr2_dq(15)" )
			)
			( pin "U5D1.W72"
				( objectStatus "@baseboard_fab2_lib.baseboard_fab2(sch_1):page25_i172:ddr2_dq(16)" )
			)
			( pin "U5D1.AA70"
				( objectStatus "@baseboard_fab2_lib.baseboard_fab2(sch_1):page25_i172:ddr2_dq(17)" )
			)
			( pin "U5D1.R70"
				( objectStatus "@baseboard_fab2_lib.baseboard_fab2(sch_1):page25_i172:ddr2_dq(18)" )
			)
			( pin "U5D1.T69"
				( objectStatus "@baseboard_fab2_lib.baseboard_fab2(sch_1):page25_i172:ddr2_dq(19)" )
			)
			( pin "U5D1.AA72"
				( objectStatus "@baseboard_fab2_lib.baseboard_fab2(sch_1):page25_i172:ddr2_dq(20)" )
			)
			( pin "U5D1.AB71"
				( objectStatus "@baseboard_fab2_lib.baseboard_fab2(sch_1):page25_i172:ddr2_dq(21)" )
			)
			( pin "U5D1.T71"
				( objectStatus "@baseboard_fab2_lib.baseboard_fab2(sch_1):page25_i172:ddr2_dq(22)" )
			)
			( pin "U5D1.V69"
				( objectStatus "@baseboard_fab2_lib.baseboard_fab2(sch_1):page25_i172:ddr2_dq(23)" )
			)
			( pin "U5D1.AM67"
				( objectStatus "@baseboard_fab2_lib.baseboard_fab2(sch_1):page25_i172:ddr2_dq(24)" )
			)
			( pin "U5D1.AT67"
				( objectStatus "@baseboard_fab2_lib.baseboard_fab2(sch_1):page25_i172:ddr2_dq(25)" )
			)
			( pin "U5D1.AN64"
				( objectStatus "@baseboard_fab2_lib.baseboard_fab2(sch_1):page25_i172:ddr2_dq(26)" )
			)
			( pin "U5D1.AR64"
				( objectStatus "@baseboard_fab2_lib.baseboard_fab2(sch_1):page25_i172:ddr2_dq(27)" )
			)
			( pin "U5D1.AN68"
				( objectStatus "@baseboard_fab2_lib.baseboard_fab2(sch_1):page25_i172:ddr2_dq(28)" )
			)
			( pin "U5D1.AR68"
				( objectStatus "@baseboard_fab2_lib.baseboard_fab2(sch_1):page25_i172:ddr2_dq(29)" )
			)
			( pin "U5D1.AM65"
				( objectStatus "@baseboard_fab2_lib.baseboard_fab2(sch_1):page25_i172:ddr2_dq(30)" )
			)
			( pin "U5D1.AT65"
				( objectStatus "@baseboard_fab2_lib.baseboard_fab2(sch_1):page25_i172:ddr2_dq(31)" )
			)
			( pin "U5D1.U40"
				( objectStatus "@baseboard_fab2_lib.baseboard_fab2(sch_1):page25_i172:ddr2_dq(32)" )
			)
			( pin "U5D1.AA40"
				( objectStatus "@baseboard_fab2_lib.baseboard_fab2(sch_1):page25_i172:ddr2_dq(33)" )
			)
			( pin "U5D1.V37"
				( objectStatus "@baseboard_fab2_lib.baseboard_fab2(sch_1):page25_i172:ddr2_dq(34)" )
			)
			( pin "U5D1.Y37"
				( objectStatus "@baseboard_fab2_lib.baseboard_fab2(sch_1):page25_i172:ddr2_dq(35)" )
			)
			( pin "U5D1.V41"
				( objectStatus "@baseboard_fab2_lib.baseboard_fab2(sch_1):page25_i172:ddr2_dq(36)" )
			)
			( pin "U5D1.Y41"
				( objectStatus "@baseboard_fab2_lib.baseboard_fab2(sch_1):page25_i172:ddr2_dq(37)" )
			)
			( pin "U5D1.U38"
				( objectStatus "@baseboard_fab2_lib.baseboard_fab2(sch_1):page25_i172:ddr2_dq(38)" )
			)
			( pin "U5D1.AA38"
				( objectStatus "@baseboard_fab2_lib.baseboard_fab2(sch_1):page25_i172:ddr2_dq(39)" )
			)
			( pin "U5D1.U34"
				( objectStatus "@baseboard_fab2_lib.baseboard_fab2(sch_1):page25_i172:ddr2_dq(40)" )
			)
			( pin "U5D1.AA34"
				( objectStatus "@baseboard_fab2_lib.baseboard_fab2(sch_1):page25_i172:ddr2_dq(41)" )
			)
			( pin "U5D1.V31"
				( objectStatus "@baseboard_fab2_lib.baseboard_fab2(sch_1):page25_i172:ddr2_dq(42)" )
			)
			( pin "U5D1.Y31"
				( objectStatus "@baseboard_fab2_lib.baseboard_fab2(sch_1):page25_i172:ddr2_dq(43)" )
			)
			( pin "U5D1.V35"
				( objectStatus "@baseboard_fab2_lib.baseboard_fab2(sch_1):page25_i172:ddr2_dq(44)" )
			)
			( pin "U5D1.Y35"
				( objectStatus "@baseboard_fab2_lib.baseboard_fab2(sch_1):page25_i172:ddr2_dq(45)" )
			)
			( pin "U5D1.U32"
				( objectStatus "@baseboard_fab2_lib.baseboard_fab2(sch_1):page25_i172:ddr2_dq(46)" )
			)
			( pin "U5D1.AA32"
				( objectStatus "@baseboard_fab2_lib.baseboard_fab2(sch_1):page25_i172:ddr2_dq(47)" )
			)
			( pin "U5D1.AD31"
				( objectStatus "@baseboard_fab2_lib.baseboard_fab2(sch_1):page25_i172:ddr2_dq(48)" )
			)
			( pin "U5D1.AH31"
				( objectStatus "@baseboard_fab2_lib.baseboard_fab2(sch_1):page25_i172:ddr2_dq(49)" )
			)
			( pin "U5D1.AE28"
				( objectStatus "@baseboard_fab2_lib.baseboard_fab2(sch_1):page25_i172:ddr2_dq(50)" )
			)
			( pin "U5D1.AG28"
				( objectStatus "@baseboard_fab2_lib.baseboard_fab2(sch_1):page25_i172:ddr2_dq(51)" )
			)
			( pin "U5D1.AE32"
				( objectStatus "@baseboard_fab2_lib.baseboard_fab2(sch_1):page25_i172:ddr2_dq(52)" )
			)
			( pin "U5D1.AG32"
				( objectStatus "@baseboard_fab2_lib.baseboard_fab2(sch_1):page25_i172:ddr2_dq(53)" )
			)
			( pin "U5D1.AD29"
				( objectStatus "@baseboard_fab2_lib.baseboard_fab2(sch_1):page25_i172:ddr2_dq(54)" )
			)
			( pin "U5D1.AH29"
				( objectStatus "@baseboard_fab2_lib.baseboard_fab2(sch_1):page25_i172:ddr2_dq(55)" )
			)
			( pin "U5D1.AD25"
				( objectStatus "@baseboard_fab2_lib.baseboard_fab2(sch_1):page25_i172:ddr2_dq(56)" )
			)
			( pin "U5D1.AH25"
				( objectStatus "@baseboard_fab2_lib.baseboard_fab2(sch_1):page25_i172:ddr2_dq(57)" )
			)
			( pin "U5D1.AE22"
				( objectStatus "@baseboard_fab2_lib.baseboard_fab2(sch_1):page25_i172:ddr2_dq(58)" )
			)
			( pin "U5D1.AG22"
				( objectStatus "@baseboard_fab2_lib.baseboard_fab2(sch_1):page25_i172:ddr2_dq(59)" )
			)
			( pin "U5D1.AE26"
				( objectStatus "@baseboard_fab2_lib.baseboard_fab2(sch_1):page25_i172:ddr2_dq(60)" )
			)
			( pin "U5D1.AG26"
				( objectStatus "@baseboard_fab2_lib.baseboard_fab2(sch_1):page25_i172:ddr2_dq(61)" )
			)
			( pin "U5D1.AD23"
				( objectStatus "@baseboard_fab2_lib.baseboard_fab2(sch_1):page25_i172:ddr2_dq(62)" )
			)
			( pin "U5D1.AH23"
				( objectStatus "@baseboard_fab2_lib.baseboard_fab2(sch_1):page25_i172:ddr2_dq(63)" )
			)
			( pin "U5D1.AL74"
				( objectStatus "@baseboard_fab2_lib.baseboard_fab2(sch_1):page25_i172:ddr2_dqs_dn(0)" )
			)
			( pin "U5D1.AA74"
				( objectStatus "@baseboard_fab2_lib.baseboard_fab2(sch_1):page25_i172:ddr2_dqs_dn(1)" )
			)
			( pin "U5D1.Y69"
				( objectStatus "@baseboard_fab2_lib.baseboard_fab2(sch_1):page25_i172:ddr2_dqs_dn(2)" )
			)
			( pin "U5D1.AU66"
				( objectStatus "@baseboard_fab2_lib.baseboard_fab2(sch_1):page25_i172:ddr2_dqs_dn(3)" )
			)
			( pin "U5D1.AB39"
				( objectStatus "@baseboard_fab2_lib.baseboard_fab2(sch_1):page25_i172:ddr2_dqs_dn(4)" )
			)
			( pin "U5D1.AB33"
				( objectStatus "@baseboard_fab2_lib.baseboard_fab2(sch_1):page25_i172:ddr2_dqs_dn(5)" )
			)
			( pin "U5D1.AJ30"
				( objectStatus "@baseboard_fab2_lib.baseboard_fab2(sch_1):page25_i172:ddr2_dqs_dn(6)" )
			)
			( pin "U5D1.AJ24"
				( objectStatus "@baseboard_fab2_lib.baseboard_fab2(sch_1):page25_i172:ddr2_dqs_dn(7)" )
			)
			( pin "U5D1.BB71"
				( objectStatus "@baseboard_fab2_lib.baseboard_fab2(sch_1):page25_i172:ddr2_dqs_dn(8)" )
			)
			( pin "U5D1.AP77"
				( objectStatus "@baseboard_fab2_lib.baseboard_fab2(sch_1):page25_i172:ddr2_dqs_dn(9)" )
			)
			( pin "U5D1.AD77"
				( objectStatus "@baseboard_fab2_lib.baseboard_fab2(sch_1):page25_i172:ddr2_dqs_dn(10)" )
			)
			( pin "U5D1.U72"
				( objectStatus "@baseboard_fab2_lib.baseboard_fab2(sch_1):page25_i172:ddr2_dqs_dn(11)" )
			)
			( pin "U5D1.AL66"
				( objectStatus "@baseboard_fab2_lib.baseboard_fab2(sch_1):page25_i172:ddr2_dqs_dn(12)" )
			)
			( pin "U5D1.T39"
				( objectStatus "@baseboard_fab2_lib.baseboard_fab2(sch_1):page25_i172:ddr2_dqs_dn(13)" )
			)
			( pin "U5D1.T33"
				( objectStatus "@baseboard_fab2_lib.baseboard_fab2(sch_1):page25_i172:ddr2_dqs_dn(14)" )
			)
			( pin "U5D1.AC30"
				( objectStatus "@baseboard_fab2_lib.baseboard_fab2(sch_1):page25_i172:ddr2_dqs_dn(15)" )
			)
			( pin "U5D1.AC24"
				( objectStatus "@baseboard_fab2_lib.baseboard_fab2(sch_1):page25_i172:ddr2_dqs_dn(16)" )
			)
			( pin "U5D1.AT71"
				( objectStatus "@baseboard_fab2_lib.baseboard_fab2(sch_1):page25_i172:ddr2_dqs_dn(17)" )
			)
			( pin "U5D1.AM75"
				( objectStatus "@baseboard_fab2_lib.baseboard_fab2(sch_1):page25_i172:ddr2_dqs_dp(0)" )
			)
			( pin "U5D1.AB75"
				( objectStatus "@baseboard_fab2_lib.baseboard_fab2(sch_1):page25_i172:ddr2_dqs_dp(1)" )
			)
			( pin "U5D1.W70"
				( objectStatus "@baseboard_fab2_lib.baseboard_fab2(sch_1):page25_i172:ddr2_dqs_dp(2)" )
			)
			( pin "U5D1.AR66"
				( objectStatus "@baseboard_fab2_lib.baseboard_fab2(sch_1):page25_i172:ddr2_dqs_dp(3)" )
			)
			( pin "U5D1.Y39"
				( objectStatus "@baseboard_fab2_lib.baseboard_fab2(sch_1):page25_i172:ddr2_dqs_dp(4)" )
			)
			( pin "U5D1.Y33"
				( objectStatus "@baseboard_fab2_lib.baseboard_fab2(sch_1):page25_i172:ddr2_dqs_dp(5)" )
			)
			( pin "U5D1.AG30"
				( objectStatus "@baseboard_fab2_lib.baseboard_fab2(sch_1):page25_i172:ddr2_dqs_dp(6)" )
			)
			( pin "U5D1.AG24"
				( objectStatus "@baseboard_fab2_lib.baseboard_fab2(sch_1):page25_i172:ddr2_dqs_dp(7)" )
			)
			( pin "U5D1.AY71"
				( objectStatus "@baseboard_fab2_lib.baseboard_fab2(sch_1):page25_i172:ddr2_dqs_dp(8)" )
			)
			( pin "U5D1.AN76"
				( objectStatus "@baseboard_fab2_lib.baseboard_fab2(sch_1):page25_i172:ddr2_dqs_dp(9)" )
			)
			( pin "U5D1.AC76"
				( objectStatus "@baseboard_fab2_lib.baseboard_fab2(sch_1):page25_i172:ddr2_dqs_dp(10)" )
			)
			( pin "U5D1.V71"
				( objectStatus "@baseboard_fab2_lib.baseboard_fab2(sch_1):page25_i172:ddr2_dqs_dp(11)" )
			)
			( pin "U5D1.AN66"
				( objectStatus "@baseboard_fab2_lib.baseboard_fab2(sch_1):page25_i172:ddr2_dqs_dp(12)" )
			)
			( pin "U5D1.V39"
				( objectStatus "@baseboard_fab2_lib.baseboard_fab2(sch_1):page25_i172:ddr2_dqs_dp(13)" )
			)
			( pin "U5D1.V33"
				( objectStatus "@baseboard_fab2_lib.baseboard_fab2(sch_1):page25_i172:ddr2_dqs_dp(14)" )
			)
			( pin "U5D1.AE30"
				( objectStatus "@baseboard_fab2_lib.baseboard_fab2(sch_1):page25_i172:ddr2_dqs_dp(15)" )
			)
			( pin "U5D1.AE24"
				( objectStatus "@baseboard_fab2_lib.baseboard_fab2(sch_1):page25_i172:ddr2_dqs_dp(16)" )
			)
			( pin "U5D1.AV71"
				( objectStatus "@baseboard_fab2_lib.baseboard_fab2(sch_1):page25_i172:ddr2_dqs_dp(17)" )
			)
			( pin "U5D1.AU72"
				( objectStatus "@baseboard_fab2_lib.baseboard_fab2(sch_1):page25_i172:ddr2_ecc(0)" )
			)
			( pin "U5D1.BA72"
				( objectStatus "@baseboard_fab2_lib.baseboard_fab2(sch_1):page25_i172:ddr2_ecc(1)" )
			)
			( pin "U5D1.AV69"
				( objectStatus "@baseboard_fab2_lib.baseboard_fab2(sch_1):page25_i172:ddr2_ecc(2)" )
			)
			( pin "U5D1.AY69"
				( objectStatus "@baseboard_fab2_lib.baseboard_fab2(sch_1):page25_i172:ddr2_ecc(3)" )
			)
			( pin "U5D1.AV73"
				( objectStatus "@baseboard_fab2_lib.baseboard_fab2(sch_1):page25_i172:ddr2_ecc(4)" )
			)
			( pin "U5D1.AY73"
				( objectStatus "@baseboard_fab2_lib.baseboard_fab2(sch_1):page25_i172:ddr2_ecc(5)" )
			)
			( pin "U5D1.AU70"
				( objectStatus "@baseboard_fab2_lib.baseboard_fab2(sch_1):page25_i172:ddr2_ecc(6)" )
			)
			( pin "U5D1.BA70"
				( objectStatus "@baseboard_fab2_lib.baseboard_fab2(sch_1):page25_i172:ddr2_ecc(7)" )
			)
			( pin "U5D1.AB53"
				( objectStatus "@baseboard_fab2_lib.baseboard_fab2(sch_1):page25_i172:ddr2_ma(0)" )
			)
			( pin "U5D1.AE58"
				( objectStatus "@baseboard_fab2_lib.baseboard_fab2(sch_1):page25_i172:ddr2_ma(1)" )
			)
			( pin "U5D1.AD57"
				( objectStatus "@baseboard_fab2_lib.baseboard_fab2(sch_1):page25_i172:ddr2_ma(2)" )
			)
			( pin "U5D1.W58"
				( objectStatus "@baseboard_fab2_lib.baseboard_fab2(sch_1):page25_i172:ddr2_ma(3)" )
			)
			( pin "U5D1.AA58"
				( objectStatus "@baseboard_fab2_lib.baseboard_fab2(sch_1):page25_i172:ddr2_ma(4)" )
			)
			( pin "U5D1.V59"
				( objectStatus "@baseboard_fab2_lib.baseboard_fab2(sch_1):page25_i172:ddr2_ma(5)" )
			)
			( pin "U5D1.AB59"
				( objectStatus "@baseboard_fab2_lib.baseboard_fab2(sch_1):page25_i172:ddr2_ma(6)" )
			)
			( pin "U5D1.AE60"
				( objectStatus "@baseboard_fab2_lib.baseboard_fab2(sch_1):page25_i172:ddr2_ma(7)" )
			)
			( pin "U5D1.AD59"
				( objectStatus "@baseboard_fab2_lib.baseboard_fab2(sch_1):page25_i172:ddr2_ma(8)" )
			)
			( pin "U5D1.AG58"
				( objectStatus "@baseboard_fab2_lib.baseboard_fab2(sch_1):page25_i172:ddr2_ma(9)" )
			)
			( pin "U5D1.AD55"
				( objectStatus "@baseboard_fab2_lib.baseboard_fab2(sch_1):page25_i172:ddr2_ma(10)" )
			)
			( pin "U5D1.AG60"
				( objectStatus "@baseboard_fab2_lib.baseboard_fab2(sch_1):page25_i172:ddr2_ma(11)" )
			)
			( pin "U5D1.AG62"
				( objectStatus "@baseboard_fab2_lib.baseboard_fab2(sch_1):page25_i172:ddr2_ma(12)" )
			)
			( pin "U5D1.AD53"
				( objectStatus "@baseboard_fab2_lib.baseboard_fab2(sch_1):page25_i172:ddr2_ma(13)" )
			)
			( pin "U5D1.W50"
				( objectStatus "@baseboard_fab2_lib.baseboard_fab2(sch_1):page25_i172:ddr2_ma(14)" )
			)
			( pin "U5D1.AE54"
				( objectStatus "@baseboard_fab2_lib.baseboard_fab2(sch_1):page25_i172:ddr2_ma(15)" )
			)
			( pin "U5D1.AA52"
				( objectStatus "@baseboard_fab2_lib.baseboard_fab2(sch_1):page25_i172:ddr2_ma(16)" )
			)
			( pin "U5D1.AC46"
				( objectStatus "@baseboard_fab2_lib.baseboard_fab2(sch_1):page25_i172:ddr2_ma(17)" )
			)
			( pin "U5D1.AA50"
				( objectStatus "@baseboard_fab2_lib.baseboard_fab2(sch_1):page25_i172:ddr2_odt(0)" )
			)
			( pin "U5D1.AA48"
				( objectStatus "@baseboard_fab2_lib.baseboard_fab2(sch_1):page25_i172:ddr2_odt(1)" )
			)
			( pin "U5D1.V49"
				( objectStatus "@baseboard_fab2_lib.baseboard_fab2(sch_1):page25_i172:ddr2_odt(2)" )
			)
			( pin "U5D1.AB47"
				( objectStatus "@baseboard_fab2_lib.baseboard_fab2(sch_1):page25_i172:ddr2_odt(3)" )
			)
			( pin "U5D1.V53"
				( objectStatus "@baseboard_fab2_lib.baseboard_fab2(sch_1):page25_i172:ddr2_par" )
			)
			( pin "U5D1.DW60"
				( objectStatus "@baseboard_fab2_lib.baseboard_fab2(sch_1):page26_i172:ddr3_act_n" )
			)
			( pin "U5D1.ED63"
				( objectStatus "@baseboard_fab2_lib.baseboard_fab2(sch_1):page26_i172:ddr3_alert_n" )
			)
			( pin "U5D1.EE52"
				( objectStatus "@baseboard_fab2_lib.baseboard_fab2(sch_1):page26_i172:ddr3_ba(0)" )
			)
			( pin "U5D1.EA54"
				( objectStatus "@baseboard_fab2_lib.baseboard_fab2(sch_1):page26_i172:ddr3_ba(1)" )
			)
			( pin "U5D1.ED61"
				( objectStatus "@baseboard_fab2_lib.baseboard_fab2(sch_1):page26_i172:ddr3_bg(0)" )
			)
			( pin "U5D1.DW62"
				( objectStatus "@baseboard_fab2_lib.baseboard_fab2(sch_1):page26_i172:ddr3_bg(1)" )
			)
			( pin "U5D1.DV47"
				( objectStatus "@baseboard_fab2_lib.baseboard_fab2(sch_1):page26_i172:ddr3_cid(2)" )
			)
			( pin "U5D1.EE62"
				( objectStatus "@baseboard_fab2_lib.baseboard_fab2(sch_1):page26_i172:ddr3_cke(0)" )
			)
			( pin "U5D1.EF63"
				( objectStatus "@baseboard_fab2_lib.baseboard_fab2(sch_1):page26_i172:ddr3_cke(1)" )
			)
			( pin "U5D1.EA62"
				( objectStatus "@baseboard_fab2_lib.baseboard_fab2(sch_1):page26_i172:ddr3_cke(2)" )
			)
			( pin "U5D1.EB63"
				( objectStatus "@baseboard_fab2_lib.baseboard_fab2(sch_1):page26_i172:ddr3_cke(3)" )
			)
			( pin "U5D1.ED55"
				( objectStatus "@baseboard_fab2_lib.baseboard_fab2(sch_1):page26_i172:ddr3_clk_dn(0)" )
			)
			( pin "U5D1.EF55"
				( objectStatus "@baseboard_fab2_lib.baseboard_fab2(sch_1):page26_i172:ddr3_clk_dn(1)" )
			)
			( pin "U5D1.DW56"
				( objectStatus "@baseboard_fab2_lib.baseboard_fab2(sch_1):page26_i172:ddr3_clk_dn(2)" )
			)
			( pin "U5D1.EF57"
				( objectStatus "@baseboard_fab2_lib.baseboard_fab2(sch_1):page26_i172:ddr3_clk_dn(3)" )
			)
			( pin "U5D1.EB55"
				( objectStatus "@baseboard_fab2_lib.baseboard_fab2(sch_1):page26_i172:ddr3_clk_dp(0)" )
			)
			( pin "U5D1.EE54"
				( objectStatus "@baseboard_fab2_lib.baseboard_fab2(sch_1):page26_i172:ddr3_clk_dp(1)" )
			)
			( pin "U5D1.EA56"
				( objectStatus "@baseboard_fab2_lib.baseboard_fab2(sch_1):page26_i172:ddr3_clk_dp(2)" )
			)
			( pin "U5D1.EE56"
				( objectStatus "@baseboard_fab2_lib.baseboard_fab2(sch_1):page26_i172:ddr3_clk_dp(3)" )
			)
			( pin "U5D1.EF51"
				( objectStatus "@baseboard_fab2_lib.baseboard_fab2(sch_1):page26_i172:ddr3_cs_n(0)" )
			)
			( pin "U5D1.ED49"
				( objectStatus "@baseboard_fab2_lib.baseboard_fab2(sch_1):page26_i172:ddr3_cs_n(1)" )
			)
			( pin "U5D1.ED47"
				( objectStatus "@baseboard_fab2_lib.baseboard_fab2(sch_1):page26_i172:ddr3_cs_n(2)" )
			)
			( pin "U5D1.EB47"
				( objectStatus "@baseboard_fab2_lib.baseboard_fab2(sch_1):page26_i172:ddr3_cs_n(3)" )
			)
			( pin "U5D1.EB51"
				( objectStatus "@baseboard_fab2_lib.baseboard_fab2(sch_1):page26_i172:ddr3_cs_n(4)" )
			)
			( pin "U5D1.EB49"
				( objectStatus "@baseboard_fab2_lib.baseboard_fab2(sch_1):page26_i172:ddr3_cs_n(5)" )
			)
			( pin "U5D1.DV45"
				( objectStatus "@baseboard_fab2_lib.baseboard_fab2(sch_1):page26_i172:ddr3_cs_n(6)" )
			)
			( pin "U5D1.EB45"
				( objectStatus "@baseboard_fab2_lib.baseboard_fab2(sch_1):page26_i172:ddr3_cs_n(7)" )
			)
			( pin "U5D1.CN84"
				( objectStatus "@baseboard_fab2_lib.baseboard_fab2(sch_1):page26_i172:ddr3_dq(0)" )
			)
			( pin "U5D1.CN86"
				( objectStatus "@baseboard_fab2_lib.baseboard_fab2(sch_1):page26_i172:ddr3_dq(1)" )
			)
			( pin "U5D1.DA86"
				( objectStatus "@baseboard_fab2_lib.baseboard_fab2(sch_1):page26_i172:ddr3_dq(2)" )
			)
			( pin "U5D1.DA84"
				( objectStatus "@baseboard_fab2_lib.baseboard_fab2(sch_1):page26_i172:ddr3_dq(3)" )
			)
			( pin "U5D1.CL84"
				( objectStatus "@baseboard_fab2_lib.baseboard_fab2(sch_1):page26_i172:ddr3_dq(4)" )
			)
			( pin "U5D1.CL86"
				( objectStatus "@baseboard_fab2_lib.baseboard_fab2(sch_1):page26_i172:ddr3_dq(5)" )
			)
			( pin "U5D1.CW86"
				( objectStatus "@baseboard_fab2_lib.baseboard_fab2(sch_1):page26_i172:ddr3_dq(6)" )
			)
			( pin "U5D1.CW84"
				( objectStatus "@baseboard_fab2_lib.baseboard_fab2(sch_1):page26_i172:ddr3_dq(7)" )
			)
			( pin "U5D1.DG84"
				( objectStatus "@baseboard_fab2_lib.baseboard_fab2(sch_1):page26_i172:ddr3_dq(8)" )
			)
			( pin "U5D1.DH85"
				( objectStatus "@baseboard_fab2_lib.baseboard_fab2(sch_1):page26_i172:ddr3_dq(9)" )
			)
			( pin "U5D1.DV83"
				( objectStatus "@baseboard_fab2_lib.baseboard_fab2(sch_1):page26_i172:ddr3_dq(10)" )
			)
			( pin "U5D1.DY83"
				( objectStatus "@baseboard_fab2_lib.baseboard_fab2(sch_1):page26_i172:ddr3_dq(11)" )
			)
			( pin "U5D1.DD85"
				( objectStatus "@baseboard_fab2_lib.baseboard_fab2(sch_1):page26_i172:ddr3_dq(12)" )
			)
			( pin "U5D1.DE84"
				( objectStatus "@baseboard_fab2_lib.baseboard_fab2(sch_1):page26_i172:ddr3_dq(13)" )
			)
			( pin "U5D1.DR84"
				( objectStatus "@baseboard_fab2_lib.baseboard_fab2(sch_1):page26_i172:ddr3_dq(14)" )
			)
			( pin "U5D1.DV85"
				( objectStatus "@baseboard_fab2_lib.baseboard_fab2(sch_1):page26_i172:ddr3_dq(15)" )
			)
			( pin "U5D1.DM79"
				( objectStatus "@baseboard_fab2_lib.baseboard_fab2(sch_1):page26_i172:ddr3_dq(16)" )
			)
			( pin "U5D1.DK81"
				( objectStatus "@baseboard_fab2_lib.baseboard_fab2(sch_1):page26_i172:ddr3_dq(17)" )
			)
			( pin "U5D1.DT81"
				( objectStatus "@baseboard_fab2_lib.baseboard_fab2(sch_1):page26_i172:ddr3_dq(18)" )
			)
			( pin "U5D1.DR82"
				( objectStatus "@baseboard_fab2_lib.baseboard_fab2(sch_1):page26_i172:ddr3_dq(19)" )
			)
			( pin "U5D1.DK79"
				( objectStatus "@baseboard_fab2_lib.baseboard_fab2(sch_1):page26_i172:ddr3_dq(20)" )
			)
			( pin "U5D1.DJ80"
				( objectStatus "@baseboard_fab2_lib.baseboard_fab2(sch_1):page26_i172:ddr3_dq(21)" )
			)
			( pin "U5D1.DR80"
				( objectStatus "@baseboard_fab2_lib.baseboard_fab2(sch_1):page26_i172:ddr3_dq(22)" )
			)
			( pin "U5D1.DN82"
				( objectStatus "@baseboard_fab2_lib.baseboard_fab2(sch_1):page26_i172:ddr3_dq(23)" )
			)
			( pin "U5D1.DN76"
				( objectStatus "@baseboard_fab2_lib.baseboard_fab2(sch_1):page26_i172:ddr3_dq(24)" )
			)
			( pin "U5D1.DU76"
				( objectStatus "@baseboard_fab2_lib.baseboard_fab2(sch_1):page26_i172:ddr3_dq(25)" )
			)
			( pin "U5D1.DP73"
				( objectStatus "@baseboard_fab2_lib.baseboard_fab2(sch_1):page26_i172:ddr3_dq(26)" )
			)
			( pin "U5D1.DT73"
				( objectStatus "@baseboard_fab2_lib.baseboard_fab2(sch_1):page26_i172:ddr3_dq(27)" )
			)
			( pin "U5D1.DP77"
				( objectStatus "@baseboard_fab2_lib.baseboard_fab2(sch_1):page26_i172:ddr3_dq(28)" )
			)
			( pin "U5D1.DT77"
				( objectStatus "@baseboard_fab2_lib.baseboard_fab2(sch_1):page26_i172:ddr3_dq(29)" )
			)
			( pin "U5D1.DN74"
				( objectStatus "@baseboard_fab2_lib.baseboard_fab2(sch_1):page26_i172:ddr3_dq(30)" )
			)
			( pin "U5D1.DU74"
				( objectStatus "@baseboard_fab2_lib.baseboard_fab2(sch_1):page26_i172:ddr3_dq(31)" )
			)
			( pin "U5D1.EC40"
				( objectStatus "@baseboard_fab2_lib.baseboard_fab2(sch_1):page26_i172:ddr3_dq(32)" )
			)
			( pin "U5D1.ED39"
				( objectStatus "@baseboard_fab2_lib.baseboard_fab2(sch_1):page26_i172:ddr3_dq(33)" )
			)
			( pin "U5D1.EA36"
				( objectStatus "@baseboard_fab2_lib.baseboard_fab2(sch_1):page26_i172:ddr3_dq(34)" )
			)
			( pin "U5D1.EC36"
				( objectStatus "@baseboard_fab2_lib.baseboard_fab2(sch_1):page26_i172:ddr3_dq(35)" )
			)
			( pin "U5D1.DY39"
				( objectStatus "@baseboard_fab2_lib.baseboard_fab2(sch_1):page26_i172:ddr3_dq(36)" )
			)
			( pin "U5D1.EA40"
				( objectStatus "@baseboard_fab2_lib.baseboard_fab2(sch_1):page26_i172:ddr3_dq(37)" )
			)
			( pin "U5D1.DY37"
				( objectStatus "@baseboard_fab2_lib.baseboard_fab2(sch_1):page26_i172:ddr3_dq(38)" )
			)
			( pin "U5D1.ED37"
				( objectStatus "@baseboard_fab2_lib.baseboard_fab2(sch_1):page26_i172:ddr3_dq(39)" )
			)
			( pin "U5D1.DN36"
				( objectStatus "@baseboard_fab2_lib.baseboard_fab2(sch_1):page26_i172:ddr3_dq(40)" )
			)
			( pin "U5D1.DU36"
				( objectStatus "@baseboard_fab2_lib.baseboard_fab2(sch_1):page26_i172:ddr3_dq(41)" )
			)
			( pin "U5D1.DP33"
				( objectStatus "@baseboard_fab2_lib.baseboard_fab2(sch_1):page26_i172:ddr3_dq(42)" )
			)
			( pin "U5D1.DT33"
				( objectStatus "@baseboard_fab2_lib.baseboard_fab2(sch_1):page26_i172:ddr3_dq(43)" )
			)
			( pin "U5D1.DP37"
				( objectStatus "@baseboard_fab2_lib.baseboard_fab2(sch_1):page26_i172:ddr3_dq(44)" )
			)
			( pin "U5D1.DT37"
				( objectStatus "@baseboard_fab2_lib.baseboard_fab2(sch_1):page26_i172:ddr3_dq(45)" )
			)
			( pin "U5D1.DN34"
				( objectStatus "@baseboard_fab2_lib.baseboard_fab2(sch_1):page26_i172:ddr3_dq(46)" )
			)
			( pin "U5D1.DU34"
				( objectStatus "@baseboard_fab2_lib.baseboard_fab2(sch_1):page26_i172:ddr3_dq(47)" )
			)
			( pin "U5D1.DN30"
				( objectStatus "@baseboard_fab2_lib.baseboard_fab2(sch_1):page26_i172:ddr3_dq(48)" )
			)
			( pin "U5D1.DU30"
				( objectStatus "@baseboard_fab2_lib.baseboard_fab2(sch_1):page26_i172:ddr3_dq(49)" )
			)
			( pin "U5D1.DP27"
				( objectStatus "@baseboard_fab2_lib.baseboard_fab2(sch_1):page26_i172:ddr3_dq(50)" )
			)
			( pin "U5D1.DT27"
				( objectStatus "@baseboard_fab2_lib.baseboard_fab2(sch_1):page26_i172:ddr3_dq(51)" )
			)
			( pin "U5D1.DP31"
				( objectStatus "@baseboard_fab2_lib.baseboard_fab2(sch_1):page26_i172:ddr3_dq(52)" )
			)
			( pin "U5D1.DT31"
				( objectStatus "@baseboard_fab2_lib.baseboard_fab2(sch_1):page26_i172:ddr3_dq(53)" )
			)
			( pin "U5D1.DN28"
				( objectStatus "@baseboard_fab2_lib.baseboard_fab2(sch_1):page26_i172:ddr3_dq(54)" )
			)
			( pin "U5D1.DU28"
				( objectStatus "@baseboard_fab2_lib.baseboard_fab2(sch_1):page26_i172:ddr3_dq(55)" )
			)
			( pin "U5D1.DN24"
				( objectStatus "@baseboard_fab2_lib.baseboard_fab2(sch_1):page26_i172:ddr3_dq(56)" )
			)
			( pin "U5D1.DU24"
				( objectStatus "@baseboard_fab2_lib.baseboard_fab2(sch_1):page26_i172:ddr3_dq(57)" )
			)
			( pin "U5D1.DY21"
				( objectStatus "@baseboard_fab2_lib.baseboard_fab2(sch_1):page26_i172:ddr3_dq(58)" )
			)
			( pin "U5D1.EB21"
				( objectStatus "@baseboard_fab2_lib.baseboard_fab2(sch_1):page26_i172:ddr3_dq(59)" )
			)
			( pin "U5D1.DP25"
				( objectStatus "@baseboard_fab2_lib.baseboard_fab2(sch_1):page26_i172:ddr3_dq(60)" )
			)
			( pin "U5D1.DT25"
				( objectStatus "@baseboard_fab2_lib.baseboard_fab2(sch_1):page26_i172:ddr3_dq(61)" )
			)
			( pin "U5D1.EC22"
				( objectStatus "@baseboard_fab2_lib.baseboard_fab2(sch_1):page26_i172:ddr3_dq(62)" )
			)
			( pin "U5D1.DW22"
				( objectStatus "@baseboard_fab2_lib.baseboard_fab2(sch_1):page26_i172:ddr3_dq(63)" )
			)
			( pin "U5D1.CU84"
				( objectStatus "@baseboard_fab2_lib.baseboard_fab2(sch_1):page26_i172:ddr3_dqs_dn(0)" )
			)
			( pin "U5D1.DN84"
				( objectStatus "@baseboard_fab2_lib.baseboard_fab2(sch_1):page26_i172:ddr3_dqs_dn(1)" )
			)
			( pin "U5D1.DL82"
				( objectStatus "@baseboard_fab2_lib.baseboard_fab2(sch_1):page26_i172:ddr3_dqs_dn(2)" )
			)
			( pin "U5D1.DV75"
				( objectStatus "@baseboard_fab2_lib.baseboard_fab2(sch_1):page26_i172:ddr3_dqs_dn(3)" )
			)
			( pin "U5D1.EE38"
				( objectStatus "@baseboard_fab2_lib.baseboard_fab2(sch_1):page26_i172:ddr3_dqs_dn(4)" )
			)
			( pin "U5D1.DV35"
				( objectStatus "@baseboard_fab2_lib.baseboard_fab2(sch_1):page26_i172:ddr3_dqs_dn(5)" )
			)
			( pin "U5D1.DV29"
				( objectStatus "@baseboard_fab2_lib.baseboard_fab2(sch_1):page26_i172:ddr3_dqs_dn(6)" )
			)
			( pin "U5D1.DV23"
				( objectStatus "@baseboard_fab2_lib.baseboard_fab2(sch_1):page26_i172:ddr3_dqs_dn(7)" )
			)
			( pin "U5D1.DF67"
				( objectStatus "@baseboard_fab2_lib.baseboard_fab2(sch_1):page26_i172:ddr3_dqs_dn(8)" )
			)
			( pin "U5D1.CR84"
				( objectStatus "@baseboard_fab2_lib.baseboard_fab2(sch_1):page26_i172:ddr3_dqs_dn(9)" )
			)
			( pin "U5D1.DM85"
				( objectStatus "@baseboard_fab2_lib.baseboard_fab2(sch_1):page26_i172:ddr3_dqs_dn(10)" )
			)
			( pin "U5D1.DN80"
				( objectStatus "@baseboard_fab2_lib.baseboard_fab2(sch_1):page26_i172:ddr3_dqs_dn(11)" )
			)
			( pin "U5D1.DP75"
				( objectStatus "@baseboard_fab2_lib.baseboard_fab2(sch_1):page26_i172:ddr3_dqs_dn(12)" )
			)
			( pin "U5D1.EA38"
				( objectStatus "@baseboard_fab2_lib.baseboard_fab2(sch_1):page26_i172:ddr3_dqs_dn(13)" )
			)
			( pin "U5D1.DP35"
				( objectStatus "@baseboard_fab2_lib.baseboard_fab2(sch_1):page26_i172:ddr3_dqs_dn(14)" )
			)
			( pin "U5D1.DM29"
				( objectStatus "@baseboard_fab2_lib.baseboard_fab2(sch_1):page26_i172:ddr3_dqs_dn(15)" )
			)
			( pin "U5D1.DM23"
				( objectStatus "@baseboard_fab2_lib.baseboard_fab2(sch_1):page26_i172:ddr3_dqs_dn(16)" )
			)
			( pin "U5D1.DB67"
				( objectStatus "@baseboard_fab2_lib.baseboard_fab2(sch_1):page26_i172:ddr3_dqs_dn(17)" )
			)
			( pin "U5D1.CV85"
				( objectStatus "@baseboard_fab2_lib.baseboard_fab2(sch_1):page26_i172:ddr3_dqs_dp(0)" )
			)
			( pin "U5D1.DP85"
				( objectStatus "@baseboard_fab2_lib.baseboard_fab2(sch_1):page26_i172:ddr3_dqs_dp(1)" )
			)
			( pin "U5D1.DM81"
				( objectStatus "@baseboard_fab2_lib.baseboard_fab2(sch_1):page26_i172:ddr3_dqs_dp(2)" )
			)
			( pin "U5D1.DT75"
				( objectStatus "@baseboard_fab2_lib.baseboard_fab2(sch_1):page26_i172:ddr3_dqs_dp(3)" )
			)
			( pin "U5D1.EC38"
				( objectStatus "@baseboard_fab2_lib.baseboard_fab2(sch_1):page26_i172:ddr3_dqs_dp(4)" )
			)
			( pin "U5D1.DT35"
				( objectStatus "@baseboard_fab2_lib.baseboard_fab2(sch_1):page26_i172:ddr3_dqs_dp(5)" )
			)
			( pin "U5D1.DT29"
				( objectStatus "@baseboard_fab2_lib.baseboard_fab2(sch_1):page26_i172:ddr3_dqs_dp(6)" )
			)
			( pin "U5D1.DT23"
				( objectStatus "@baseboard_fab2_lib.baseboard_fab2(sch_1):page26_i172:ddr3_dqs_dp(7)" )
			)
			( pin "U5D1.DD67"
				( objectStatus "@baseboard_fab2_lib.baseboard_fab2(sch_1):page26_i172:ddr3_dqs_dp(8)" )
			)
			( pin "U5D1.CP85"
				( objectStatus "@baseboard_fab2_lib.baseboard_fab2(sch_1):page26_i172:ddr3_dqs_dp(9)" )
			)
			( pin "U5D1.DL84"
				( objectStatus "@baseboard_fab2_lib.baseboard_fab2(sch_1):page26_i172:ddr3_dqs_dp(10)" )
			)
			( pin "U5D1.DP79"
				( objectStatus "@baseboard_fab2_lib.baseboard_fab2(sch_1):page26_i172:ddr3_dqs_dp(11)" )
			)
			( pin "U5D1.DM75"
				( objectStatus "@baseboard_fab2_lib.baseboard_fab2(sch_1):page26_i172:ddr3_dqs_dp(12)" )
			)
			( pin "U5D1.DW38"
				( objectStatus "@baseboard_fab2_lib.baseboard_fab2(sch_1):page26_i172:ddr3_dqs_dp(13)" )
			)
			( pin "U5D1.DM35"
				( objectStatus "@baseboard_fab2_lib.baseboard_fab2(sch_1):page26_i172:ddr3_dqs_dp(14)" )
			)
			( pin "U5D1.DP29"
				( objectStatus "@baseboard_fab2_lib.baseboard_fab2(sch_1):page26_i172:ddr3_dqs_dp(15)" )
			)
			( pin "U5D1.DP23"
				( objectStatus "@baseboard_fab2_lib.baseboard_fab2(sch_1):page26_i172:ddr3_dqs_dp(16)" )
			)
			( pin "U5D1.CY67"
				( objectStatus "@baseboard_fab2_lib.baseboard_fab2(sch_1):page26_i172:ddr3_dqs_dp(17)" )
			)
			( pin "U5D1.DA68"
				( objectStatus "@baseboard_fab2_lib.baseboard_fab2(sch_1):page26_i172:ddr3_ecc(0)" )
			)
			( pin "U5D1.DE68"
				( objectStatus "@baseboard_fab2_lib.baseboard_fab2(sch_1):page26_i172:ddr3_ecc(1)" )
			)
			( pin "U5D1.DB65"
				( objectStatus "@baseboard_fab2_lib.baseboard_fab2(sch_1):page26_i172:ddr3_ecc(2)" )
			)
			( pin "U5D1.DD65"
				( objectStatus "@baseboard_fab2_lib.baseboard_fab2(sch_1):page26_i172:ddr3_ecc(3)" )
			)
			( pin "U5D1.DB69"
				( objectStatus "@baseboard_fab2_lib.baseboard_fab2(sch_1):page26_i172:ddr3_ecc(4)" )
			)
			( pin "U5D1.DD69"
				( objectStatus "@baseboard_fab2_lib.baseboard_fab2(sch_1):page26_i172:ddr3_ecc(5)" )
			)
			( pin "U5D1.DA66"
				( objectStatus "@baseboard_fab2_lib.baseboard_fab2(sch_1):page26_i172:ddr3_ecc(6)" )
			)
			( pin "U5D1.DE66"
				( objectStatus "@baseboard_fab2_lib.baseboard_fab2(sch_1):page26_i172:ddr3_ecc(7)" )
			)
			( pin "U5D1.EB53"
				( objectStatus "@baseboard_fab2_lib.baseboard_fab2(sch_1):page26_i172:ddr3_ma(0)" )
			)
			( pin "U5D1.ED57"
				( objectStatus "@baseboard_fab2_lib.baseboard_fab2(sch_1):page26_i172:ddr3_ma(1)" )
			)
			( pin "U5D1.EE58"
				( objectStatus "@baseboard_fab2_lib.baseboard_fab2(sch_1):page26_i172:ddr3_ma(2)" )
			)
			( pin "U5D1.EB57"
				( objectStatus "@baseboard_fab2_lib.baseboard_fab2(sch_1):page26_i172:ddr3_ma(3)" )
			)
			( pin "U5D1.ED59"
				( objectStatus "@baseboard_fab2_lib.baseboard_fab2(sch_1):page26_i172:ddr3_ma(4)" )
			)
			( pin "U5D1.EA58"
				( objectStatus "@baseboard_fab2_lib.baseboard_fab2(sch_1):page26_i172:ddr3_ma(5)" )
			)
			( pin "U5D1.EE60"
				( objectStatus "@baseboard_fab2_lib.baseboard_fab2(sch_1):page26_i172:ddr3_ma(6)" )
			)
			( pin "U5D1.EA60"
				( objectStatus "@baseboard_fab2_lib.baseboard_fab2(sch_1):page26_i172:ddr3_ma(7)" )
			)
			( pin "U5D1.EB59"
				( objectStatus "@baseboard_fab2_lib.baseboard_fab2(sch_1):page26_i172:ddr3_ma(8)" )
			)
			( pin "U5D1.EF61"
				( objectStatus "@baseboard_fab2_lib.baseboard_fab2(sch_1):page26_i172:ddr3_ma(9)" )
			)
			( pin "U5D1.DW54"
				( objectStatus "@baseboard_fab2_lib.baseboard_fab2(sch_1):page26_i172:ddr3_ma(10)" )
			)
			( pin "U5D1.EB61"
				( objectStatus "@baseboard_fab2_lib.baseboard_fab2(sch_1):page26_i172:ddr3_ma(11)" )
			)
			( pin "U5D1.DT63"
				( objectStatus "@baseboard_fab2_lib.baseboard_fab2(sch_1):page26_i172:ddr3_ma(12)" )
			)
			( pin "U5D1.DW48"
				( objectStatus "@baseboard_fab2_lib.baseboard_fab2(sch_1):page26_i172:ddr3_ma(13)" )
			)
			( pin "U5D1.ED51"
				( objectStatus "@baseboard_fab2_lib.baseboard_fab2(sch_1):page26_i172:ddr3_ma(14)" )
			)
			( pin "U5D1.DV49"
				( objectStatus "@baseboard_fab2_lib.baseboard_fab2(sch_1):page26_i172:ddr3_ma(15)" )
			)
			( pin "U5D1.EA52"
				( objectStatus "@baseboard_fab2_lib.baseboard_fab2(sch_1):page26_i172:ddr3_ma(16)" )
			)
			( pin "U5D1.EA46"
				( objectStatus "@baseboard_fab2_lib.baseboard_fab2(sch_1):page26_i172:ddr3_ma(17)" )
			)
			( pin "U5D1.EE50"
				( objectStatus "@baseboard_fab2_lib.baseboard_fab2(sch_1):page26_i172:ddr3_odt(0)" )
			)
			( pin "U5D1.EE48"
				( objectStatus "@baseboard_fab2_lib.baseboard_fab2(sch_1):page26_i172:ddr3_odt(1)" )
			)
			( pin "U5D1.EA50"
				( objectStatus "@baseboard_fab2_lib.baseboard_fab2(sch_1):page26_i172:ddr3_odt(2)" )
			)
			( pin "U5D1.EA48"
				( objectStatus "@baseboard_fab2_lib.baseboard_fab2(sch_1):page26_i172:ddr3_odt(3)" )
			)
			( pin "U5D1.ED53"
				( objectStatus "@baseboard_fab2_lib.baseboard_fab2(sch_1):page26_i172:ddr3_par" )
			)
			( pin "U5D1.DR62"
				( objectStatus "@baseboard_fab2_lib.baseboard_fab2(sch_1):page27_i172:ddr4_act_n" )
			)
			( pin "U5D1.DT61"
				( objectStatus "@baseboard_fab2_lib.baseboard_fab2(sch_1):page27_i172:ddr4_alert_n" )
			)
			( pin "U5D1.DM53"
				( objectStatus "@baseboard_fab2_lib.baseboard_fab2(sch_1):page27_i172:ddr4_ba(0)" )
			)
			( pin "U5D1.DV55"
				( objectStatus "@baseboard_fab2_lib.baseboard_fab2(sch_1):page27_i172:ddr4_ba(1)" )
			)
			( pin "U5D1.DJ62"
				( objectStatus "@baseboard_fab2_lib.baseboard_fab2(sch_1):page27_i172:ddr4_bg(0)" )
			)
			( pin "U5D1.DM61"
				( objectStatus "@baseboard_fab2_lib.baseboard_fab2(sch_1):page27_i172:ddr4_bg(1)" )
			)
			( pin "U5D1.DT47"
				( objectStatus "@baseboard_fab2_lib.baseboard_fab2(sch_1):page27_i172:ddr4_cid(2)" )
			)
			( pin "U5D1.DM63"
				( objectStatus "@baseboard_fab2_lib.baseboard_fab2(sch_1):page27_i172:ddr4_cke(0)" )
			)
			( pin "U5D1.DN64"
				( objectStatus "@baseboard_fab2_lib.baseboard_fab2(sch_1):page27_i172:ddr4_cke(1)" )
			)
			( pin "U5D1.DL64"
				( objectStatus "@baseboard_fab2_lib.baseboard_fab2(sch_1):page27_i172:ddr4_cke(2)" )
			)
			( pin "U5D1.DR64"
				( objectStatus "@baseboard_fab2_lib.baseboard_fab2(sch_1):page27_i172:ddr4_cke(3)" )
			)
			( pin "U5D1.DM55"
				( objectStatus "@baseboard_fab2_lib.baseboard_fab2(sch_1):page27_i172:ddr4_clk_dn(0)" )
			)
			( pin "U5D1.DR54"
				( objectStatus "@baseboard_fab2_lib.baseboard_fab2(sch_1):page27_i172:ddr4_clk_dn(1)" )
			)
			( pin "U5D1.DM57"
				( objectStatus "@baseboard_fab2_lib.baseboard_fab2(sch_1):page27_i172:ddr4_clk_dn(2)" )
			)
			( pin "U5D1.DT57"
				( objectStatus "@baseboard_fab2_lib.baseboard_fab2(sch_1):page27_i172:ddr4_clk_dn(3)" )
			)
			( pin "U5D1.DN54"
				( objectStatus "@baseboard_fab2_lib.baseboard_fab2(sch_1):page27_i172:ddr4_clk_dp(0)" )
			)
			( pin "U5D1.DT53"
				( objectStatus "@baseboard_fab2_lib.baseboard_fab2(sch_1):page27_i172:ddr4_clk_dp(1)" )
			)
			( pin "U5D1.DN56"
				( objectStatus "@baseboard_fab2_lib.baseboard_fab2(sch_1):page27_i172:ddr4_clk_dp(2)" )
			)
			( pin "U5D1.DR56"
				( objectStatus "@baseboard_fab2_lib.baseboard_fab2(sch_1):page27_i172:ddr4_clk_dp(3)" )
			)
			( pin "U5D1.DV51"
				( objectStatus "@baseboard_fab2_lib.baseboard_fab2(sch_1):page27_i172:ddr4_cs_n(0)" )
			)
			( pin "U5D1.DN50"
				( objectStatus "@baseboard_fab2_lib.baseboard_fab2(sch_1):page27_i172:ddr4_cs_n(1)" )
			)
			( pin "U5D1.DR46"
				( objectStatus "@baseboard_fab2_lib.baseboard_fab2(sch_1):page27_i172:ddr4_cs_n(2)" )
			)
			( pin "U5D1.DK47"
				( objectStatus "@baseboard_fab2_lib.baseboard_fab2(sch_1):page27_i172:ddr4_cs_n(3)" )
			)
			( pin "U5D1.DW50"
				( objectStatus "@baseboard_fab2_lib.baseboard_fab2(sch_1):page27_i172:ddr4_cs_n(4)" )
			)
			( pin "U5D1.DM49"
				( objectStatus "@baseboard_fab2_lib.baseboard_fab2(sch_1):page27_i172:ddr4_cs_n(5)" )
			)
			( pin "U5D1.DT45"
				( objectStatus "@baseboard_fab2_lib.baseboard_fab2(sch_1):page27_i172:ddr4_cs_n(6)" )
			)
			( pin "U5D1.DN46"
				( objectStatus "@baseboard_fab2_lib.baseboard_fab2(sch_1):page27_i172:ddr4_cs_n(7)" )
			)
			( pin "U5D1.CM79"
				( objectStatus "@baseboard_fab2_lib.baseboard_fab2(sch_1):page27_i172:ddr4_dq(0)" )
			)
			( pin "U5D1.CK81"
				( objectStatus "@baseboard_fab2_lib.baseboard_fab2(sch_1):page27_i172:ddr4_dq(1)" )
			)
			( pin "U5D1.CT81"
				( objectStatus "@baseboard_fab2_lib.baseboard_fab2(sch_1):page27_i172:ddr4_dq(2)" )
			)
			( pin "U5D1.CR82"
				( objectStatus "@baseboard_fab2_lib.baseboard_fab2(sch_1):page27_i172:ddr4_dq(3)" )
			)
			( pin "U5D1.CK79"
				( objectStatus "@baseboard_fab2_lib.baseboard_fab2(sch_1):page27_i172:ddr4_dq(4)" )
			)
			( pin "U5D1.CJ80"
				( objectStatus "@baseboard_fab2_lib.baseboard_fab2(sch_1):page27_i172:ddr4_dq(5)" )
			)
			( pin "U5D1.CR80"
				( objectStatus "@baseboard_fab2_lib.baseboard_fab2(sch_1):page27_i172:ddr4_dq(6)" )
			)
			( pin "U5D1.CN82"
				( objectStatus "@baseboard_fab2_lib.baseboard_fab2(sch_1):page27_i172:ddr4_dq(7)" )
			)
			( pin "U5D1.DB79"
				( objectStatus "@baseboard_fab2_lib.baseboard_fab2(sch_1):page27_i172:ddr4_dq(8)" )
			)
			( pin "U5D1.CY81"
				( objectStatus "@baseboard_fab2_lib.baseboard_fab2(sch_1):page27_i172:ddr4_dq(9)" )
			)
			( pin "U5D1.DE80"
				( objectStatus "@baseboard_fab2_lib.baseboard_fab2(sch_1):page27_i172:ddr4_dq(10)" )
			)
			( pin "U5D1.DF81"
				( objectStatus "@baseboard_fab2_lib.baseboard_fab2(sch_1):page27_i172:ddr4_dq(11)" )
			)
			( pin "U5D1.CY79"
				( objectStatus "@baseboard_fab2_lib.baseboard_fab2(sch_1):page27_i172:ddr4_dq(12)" )
			)
			( pin "U5D1.CW80"
				( objectStatus "@baseboard_fab2_lib.baseboard_fab2(sch_1):page27_i172:ddr4_dq(13)" )
			)
			( pin "U5D1.DC82"
				( objectStatus "@baseboard_fab2_lib.baseboard_fab2(sch_1):page27_i172:ddr4_dq(14)" )
			)
			( pin "U5D1.DE82"
				( objectStatus "@baseboard_fab2_lib.baseboard_fab2(sch_1):page27_i172:ddr4_dq(15)" )
			)
			( pin "U5D1.DW80"
				( objectStatus "@baseboard_fab2_lib.baseboard_fab2(sch_1):page27_i172:ddr4_dq(16)" )
			)
			( pin "U5D1.EC80"
				( objectStatus "@baseboard_fab2_lib.baseboard_fab2(sch_1):page27_i172:ddr4_dq(17)" )
			)
			( pin "U5D1.DY77"
				( objectStatus "@baseboard_fab2_lib.baseboard_fab2(sch_1):page27_i172:ddr4_dq(18)" )
			)
			( pin "U5D1.EB77"
				( objectStatus "@baseboard_fab2_lib.baseboard_fab2(sch_1):page27_i172:ddr4_dq(19)" )
			)
			( pin "U5D1.DY81"
				( objectStatus "@baseboard_fab2_lib.baseboard_fab2(sch_1):page27_i172:ddr4_dq(20)" )
			)
			( pin "U5D1.EB81"
				( objectStatus "@baseboard_fab2_lib.baseboard_fab2(sch_1):page27_i172:ddr4_dq(21)" )
			)
			( pin "U5D1.DW78"
				( objectStatus "@baseboard_fab2_lib.baseboard_fab2(sch_1):page27_i172:ddr4_dq(22)" )
			)
			( pin "U5D1.EC78"
				( objectStatus "@baseboard_fab2_lib.baseboard_fab2(sch_1):page27_i172:ddr4_dq(23)" )
			)
			( pin "U5D1.ED75"
				( objectStatus "@baseboard_fab2_lib.baseboard_fab2(sch_1):page27_i172:ddr4_dq(24)" )
			)
			( pin "U5D1.EE74"
				( objectStatus "@baseboard_fab2_lib.baseboard_fab2(sch_1):page27_i172:ddr4_dq(25)" )
			)
			( pin "U5D1.EB71"
				( objectStatus "@baseboard_fab2_lib.baseboard_fab2(sch_1):page27_i172:ddr4_dq(26)" )
			)
			( pin "U5D1.ED71"
				( objectStatus "@baseboard_fab2_lib.baseboard_fab2(sch_1):page27_i172:ddr4_dq(27)" )
			)
			( pin "U5D1.EA74"
				( objectStatus "@baseboard_fab2_lib.baseboard_fab2(sch_1):page27_i172:ddr4_dq(28)" )
			)
			( pin "U5D1.EB75"
				( objectStatus "@baseboard_fab2_lib.baseboard_fab2(sch_1):page27_i172:ddr4_dq(29)" )
			)
			( pin "U5D1.EA72"
				( objectStatus "@baseboard_fab2_lib.baseboard_fab2(sch_1):page27_i172:ddr4_dq(30)" )
			)
			( pin "U5D1.EE72"
				( objectStatus "@baseboard_fab2_lib.baseboard_fab2(sch_1):page27_i172:ddr4_dq(31)" )
			)
			( pin "U5D1.DU42"
				( objectStatus "@baseboard_fab2_lib.baseboard_fab2(sch_1):page27_i172:ddr4_dq(32)" )
			)
			( pin "U5D1.DW42"
				( objectStatus "@baseboard_fab2_lib.baseboard_fab2(sch_1):page27_i172:ddr4_dq(33)" )
			)
			( pin "U5D1.DP39"
				( objectStatus "@baseboard_fab2_lib.baseboard_fab2(sch_1):page27_i172:ddr4_dq(34)" )
			)
			( pin "U5D1.DT39"
				( objectStatus "@baseboard_fab2_lib.baseboard_fab2(sch_1):page27_i172:ddr4_dq(35)" )
			)
			( pin "U5D1.DL42"
				( objectStatus "@baseboard_fab2_lib.baseboard_fab2(sch_1):page27_i172:ddr4_dq(36)" )
			)
			( pin "U5D1.DN42"
				( objectStatus "@baseboard_fab2_lib.baseboard_fab2(sch_1):page27_i172:ddr4_dq(37)" )
			)
			( pin "U5D1.DN40"
				( objectStatus "@baseboard_fab2_lib.baseboard_fab2(sch_1):page27_i172:ddr4_dq(38)" )
			)
			( pin "U5D1.DU40"
				( objectStatus "@baseboard_fab2_lib.baseboard_fab2(sch_1):page27_i172:ddr4_dq(39)" )
			)
			( pin "U5D1.EC34"
				( objectStatus "@baseboard_fab2_lib.baseboard_fab2(sch_1):page27_i172:ddr4_dq(40)" )
			)
			( pin "U5D1.ED33"
				( objectStatus "@baseboard_fab2_lib.baseboard_fab2(sch_1):page27_i172:ddr4_dq(41)" )
			)
			( pin "U5D1.EA30"
				( objectStatus "@baseboard_fab2_lib.baseboard_fab2(sch_1):page27_i172:ddr4_dq(42)" )
			)
			( pin "U5D1.EC30"
				( objectStatus "@baseboard_fab2_lib.baseboard_fab2(sch_1):page27_i172:ddr4_dq(43)" )
			)
			( pin "U5D1.DY33"
				( objectStatus "@baseboard_fab2_lib.baseboard_fab2(sch_1):page27_i172:ddr4_dq(44)" )
			)
			( pin "U5D1.EA34"
				( objectStatus "@baseboard_fab2_lib.baseboard_fab2(sch_1):page27_i172:ddr4_dq(45)" )
			)
			( pin "U5D1.DY31"
				( objectStatus "@baseboard_fab2_lib.baseboard_fab2(sch_1):page27_i172:ddr4_dq(46)" )
			)
			( pin "U5D1.ED31"
				( objectStatus "@baseboard_fab2_lib.baseboard_fab2(sch_1):page27_i172:ddr4_dq(47)" )
			)
			( pin "U5D1.EC28"
				( objectStatus "@baseboard_fab2_lib.baseboard_fab2(sch_1):page27_i172:ddr4_dq(48)" )
			)
			( pin "U5D1.ED27"
				( objectStatus "@baseboard_fab2_lib.baseboard_fab2(sch_1):page27_i172:ddr4_dq(49)" )
			)
			( pin "U5D1.EA24"
				( objectStatus "@baseboard_fab2_lib.baseboard_fab2(sch_1):page27_i172:ddr4_dq(50)" )
			)
			( pin "U5D1.EC24"
				( objectStatus "@baseboard_fab2_lib.baseboard_fab2(sch_1):page27_i172:ddr4_dq(51)" )
			)
			( pin "U5D1.DY27"
				( objectStatus "@baseboard_fab2_lib.baseboard_fab2(sch_1):page27_i172:ddr4_dq(52)" )
			)
			( pin "U5D1.EA28"
				( objectStatus "@baseboard_fab2_lib.baseboard_fab2(sch_1):page27_i172:ddr4_dq(53)" )
			)
			( pin "U5D1.DY25"
				( objectStatus "@baseboard_fab2_lib.baseboard_fab2(sch_1):page27_i172:ddr4_dq(54)" )
			)
			( pin "U5D1.ED25"
				( objectStatus "@baseboard_fab2_lib.baseboard_fab2(sch_1):page27_i172:ddr4_dq(55)" )
			)
			( pin "U5D1.DF27"
				( objectStatus "@baseboard_fab2_lib.baseboard_fab2(sch_1):page27_i172:ddr4_dq(56)" )
			)
			( pin "U5D1.DK27"
				( objectStatus "@baseboard_fab2_lib.baseboard_fab2(sch_1):page27_i172:ddr4_dq(57)" )
			)
			( pin "U5D1.DD25"
				( objectStatus "@baseboard_fab2_lib.baseboard_fab2(sch_1):page27_i172:ddr4_dq(58)" )
			)
			( pin "U5D1.DJ24"
				( objectStatus "@baseboard_fab2_lib.baseboard_fab2(sch_1):page27_i172:ddr4_dq(59)" )
			)
			( pin "U5D1.DG28"
				( objectStatus "@baseboard_fab2_lib.baseboard_fab2(sch_1):page27_i172:ddr4_dq(60)" )
			)
			( pin "U5D1.DJ28"
				( objectStatus "@baseboard_fab2_lib.baseboard_fab2(sch_1):page27_i172:ddr4_dq(61)" )
			)
			( pin "U5D1.DF25"
				( objectStatus "@baseboard_fab2_lib.baseboard_fab2(sch_1):page27_i172:ddr4_dq(62)" )
			)
			( pin "U5D1.DK25"
				( objectStatus "@baseboard_fab2_lib.baseboard_fab2(sch_1):page27_i172:ddr4_dq(63)" )
			)
			( pin "U5D1.CL82"
				( objectStatus "@baseboard_fab2_lib.baseboard_fab2(sch_1):page27_i172:ddr4_dqs_dn(0)" )
			)
			( pin "U5D1.DA82"
				( objectStatus "@baseboard_fab2_lib.baseboard_fab2(sch_1):page27_i172:ddr4_dqs_dn(1)" )
			)
			( pin "U5D1.ED79"
				( objectStatus "@baseboard_fab2_lib.baseboard_fab2(sch_1):page27_i172:ddr4_dqs_dn(2)" )
			)
			( pin "U5D1.EF73"
				( objectStatus "@baseboard_fab2_lib.baseboard_fab2(sch_1):page27_i172:ddr4_dqs_dn(3)" )
			)
			( pin "U5D1.DV41"
				( objectStatus "@baseboard_fab2_lib.baseboard_fab2(sch_1):page27_i172:ddr4_dqs_dn(4)" )
			)
			( pin "U5D1.EE32"
				( objectStatus "@baseboard_fab2_lib.baseboard_fab2(sch_1):page27_i172:ddr4_dqs_dn(5)" )
			)
			( pin "U5D1.EE26"
				( objectStatus "@baseboard_fab2_lib.baseboard_fab2(sch_1):page27_i172:ddr4_dqs_dn(6)" )
			)
			( pin "U5D1.DL26"
				( objectStatus "@baseboard_fab2_lib.baseboard_fab2(sch_1):page27_i172:ddr4_dqs_dn(7)" )
			)
			( pin "U5D1.EB67"
				( objectStatus "@baseboard_fab2_lib.baseboard_fab2(sch_1):page27_i172:ddr4_dqs_dn(8)" )
			)
			( pin "U5D1.CN80"
				( objectStatus "@baseboard_fab2_lib.baseboard_fab2(sch_1):page27_i172:ddr4_dqs_dn(9)" )
			)
			( pin "U5D1.DC80"
				( objectStatus "@baseboard_fab2_lib.baseboard_fab2(sch_1):page27_i172:ddr4_dqs_dn(10)" )
			)
			( pin "U5D1.DY79"
				( objectStatus "@baseboard_fab2_lib.baseboard_fab2(sch_1):page27_i172:ddr4_dqs_dn(11)" )
			)
			( pin "U5D1.EB73"
				( objectStatus "@baseboard_fab2_lib.baseboard_fab2(sch_1):page27_i172:ddr4_dqs_dn(12)" )
			)
			( pin "U5D1.DP41"
				( objectStatus "@baseboard_fab2_lib.baseboard_fab2(sch_1):page27_i172:ddr4_dqs_dn(13)" )
			)
			( pin "U5D1.EA32"
				( objectStatus "@baseboard_fab2_lib.baseboard_fab2(sch_1):page27_i172:ddr4_dqs_dn(14)" )
			)
			( pin "U5D1.EA26"
				( objectStatus "@baseboard_fab2_lib.baseboard_fab2(sch_1):page27_i172:ddr4_dqs_dn(15)" )
			)
			( pin "U5D1.DG26"
				( objectStatus "@baseboard_fab2_lib.baseboard_fab2(sch_1):page27_i172:ddr4_dqs_dn(16)" )
			)
			( pin "U5D1.DV67"
				( objectStatus "@baseboard_fab2_lib.baseboard_fab2(sch_1):page27_i172:ddr4_dqs_dn(17)" )
			)
			( pin "U5D1.CM81"
				( objectStatus "@baseboard_fab2_lib.baseboard_fab2(sch_1):page27_i172:ddr4_dqs_dp(0)" )
			)
			( pin "U5D1.DB81"
				( objectStatus "@baseboard_fab2_lib.baseboard_fab2(sch_1):page27_i172:ddr4_dqs_dp(1)" )
			)
			( pin "U5D1.EB79"
				( objectStatus "@baseboard_fab2_lib.baseboard_fab2(sch_1):page27_i172:ddr4_dqs_dp(2)" )
			)
			( pin "U5D1.ED73"
				( objectStatus "@baseboard_fab2_lib.baseboard_fab2(sch_1):page27_i172:ddr4_dqs_dp(3)" )
			)
			( pin "U5D1.DT41"
				( objectStatus "@baseboard_fab2_lib.baseboard_fab2(sch_1):page27_i172:ddr4_dqs_dp(4)" )
			)
			( pin "U5D1.EC32"
				( objectStatus "@baseboard_fab2_lib.baseboard_fab2(sch_1):page27_i172:ddr4_dqs_dp(5)" )
			)
			( pin "U5D1.EC26"
				( objectStatus "@baseboard_fab2_lib.baseboard_fab2(sch_1):page27_i172:ddr4_dqs_dp(6)" )
			)
			( pin "U5D1.DJ26"
				( objectStatus "@baseboard_fab2_lib.baseboard_fab2(sch_1):page27_i172:ddr4_dqs_dp(7)" )
			)
			( pin "U5D1.DY67"
				( objectStatus "@baseboard_fab2_lib.baseboard_fab2(sch_1):page27_i172:ddr4_dqs_dp(8)" )
			)
			( pin "U5D1.CP79"
				( objectStatus "@baseboard_fab2_lib.baseboard_fab2(sch_1):page27_i172:ddr4_dqs_dp(9)" )
			)
			( pin "U5D1.DD79"
				( objectStatus "@baseboard_fab2_lib.baseboard_fab2(sch_1):page27_i172:ddr4_dqs_dp(10)" )
			)
			( pin "U5D1.DV79"
				( objectStatus "@baseboard_fab2_lib.baseboard_fab2(sch_1):page27_i172:ddr4_dqs_dp(11)" )
			)
			( pin "U5D1.DY73"
				( objectStatus "@baseboard_fab2_lib.baseboard_fab2(sch_1):page27_i172:ddr4_dqs_dp(12)" )
			)
			( pin "U5D1.DM41"
				( objectStatus "@baseboard_fab2_lib.baseboard_fab2(sch_1):page27_i172:ddr4_dqs_dp(13)" )
			)
			( pin "U5D1.DW32"
				( objectStatus "@baseboard_fab2_lib.baseboard_fab2(sch_1):page27_i172:ddr4_dqs_dp(14)" )
			)
			( pin "U5D1.DW26"
				( objectStatus "@baseboard_fab2_lib.baseboard_fab2(sch_1):page27_i172:ddr4_dqs_dp(15)" )
			)
			( pin "U5D1.DE26"
				( objectStatus "@baseboard_fab2_lib.baseboard_fab2(sch_1):page27_i172:ddr4_dqs_dp(16)" )
			)
			( pin "U5D1.DT67"
				( objectStatus "@baseboard_fab2_lib.baseboard_fab2(sch_1):page27_i172:ddr4_dqs_dp(17)" )
			)
			( pin "U5D1.DY69"
				( objectStatus "@baseboard_fab2_lib.baseboard_fab2(sch_1):page27_i172:ddr4_ecc(0)" )
			)
			( pin "U5D1.EA68"
				( objectStatus "@baseboard_fab2_lib.baseboard_fab2(sch_1):page27_i172:ddr4_ecc(1)" )
			)
			( pin "U5D1.DV65"
				( objectStatus "@baseboard_fab2_lib.baseboard_fab2(sch_1):page27_i172:ddr4_ecc(2)" )
			)
			( pin "U5D1.DY65"
				( objectStatus "@baseboard_fab2_lib.baseboard_fab2(sch_1):page27_i172:ddr4_ecc(3)" )
			)
			( pin "U5D1.DU68"
				( objectStatus "@baseboard_fab2_lib.baseboard_fab2(sch_1):page27_i172:ddr4_ecc(4)" )
			)
			( pin "U5D1.DV69"
				( objectStatus "@baseboard_fab2_lib.baseboard_fab2(sch_1):page27_i172:ddr4_ecc(5)" )
			)
			( pin "U5D1.DU66"
				( objectStatus "@baseboard_fab2_lib.baseboard_fab2(sch_1):page27_i172:ddr4_ecc(6)" )
			)
			( pin "U5D1.EA66"
				( objectStatus "@baseboard_fab2_lib.baseboard_fab2(sch_1):page27_i172:ddr4_ecc(7)" )
			)
			( pin "U5D1.DW52"
				( objectStatus "@baseboard_fab2_lib.baseboard_fab2(sch_1):page27_i172:ddr4_ma(0)" )
			)
			( pin "U5D1.DW58"
				( objectStatus "@baseboard_fab2_lib.baseboard_fab2(sch_1):page27_i172:ddr4_ma(1)" )
			)
			( pin "U5D1.DV57"
				( objectStatus "@baseboard_fab2_lib.baseboard_fab2(sch_1):page27_i172:ddr4_ma(2)" )
			)
			( pin "U5D1.DR58"
				( objectStatus "@baseboard_fab2_lib.baseboard_fab2(sch_1):page27_i172:ddr4_ma(3)" )
			)
			( pin "U5D1.DT59"
				( objectStatus "@baseboard_fab2_lib.baseboard_fab2(sch_1):page27_i172:ddr4_ma(4)" )
			)
			( pin "U5D1.DN58"
				( objectStatus "@baseboard_fab2_lib.baseboard_fab2(sch_1):page27_i172:ddr4_ma(5)" )
			)
			( pin "U5D1.DM59"
				( objectStatus "@baseboard_fab2_lib.baseboard_fab2(sch_1):page27_i172:ddr4_ma(6)" )
			)
			( pin "U5D1.DK61"
				( objectStatus "@baseboard_fab2_lib.baseboard_fab2(sch_1):page27_i172:ddr4_ma(7)" )
			)
			( pin "U5D1.DJ60"
				( objectStatus "@baseboard_fab2_lib.baseboard_fab2(sch_1):page27_i172:ddr4_ma(8)" )
			)
			( pin "U5D1.DV59"
				( objectStatus "@baseboard_fab2_lib.baseboard_fab2(sch_1):page27_i172:ddr4_ma(9)" )
			)
			( pin "U5D1.DT55"
				( objectStatus "@baseboard_fab2_lib.baseboard_fab2(sch_1):page27_i172:ddr4_ma(10)" )
			)
			( pin "U5D1.DR60"
				( objectStatus "@baseboard_fab2_lib.baseboard_fab2(sch_1):page27_i172:ddr4_ma(11)" )
			)
			( pin "U5D1.DN60"
				( objectStatus "@baseboard_fab2_lib.baseboard_fab2(sch_1):page27_i172:ddr4_ma(12)" )
			)
			( pin "U5D1.DT51"
				( objectStatus "@baseboard_fab2_lib.baseboard_fab2(sch_1):page27_i172:ddr4_ma(13)" )
			)
			( pin "U5D1.DM51"
				( objectStatus "@baseboard_fab2_lib.baseboard_fab2(sch_1):page27_i172:ddr4_ma(14)" )
			)
			( pin "U5D1.DR52"
				( objectStatus "@baseboard_fab2_lib.baseboard_fab2(sch_1):page27_i172:ddr4_ma(15)" )
			)
			( pin "U5D1.DN52"
				( objectStatus "@baseboard_fab2_lib.baseboard_fab2(sch_1):page27_i172:ddr4_ma(16)" )
			)
			( pin "U5D1.DR48"
				( objectStatus "@baseboard_fab2_lib.baseboard_fab2(sch_1):page27_i172:ddr4_ma(17)" )
			)
			( pin "U5D1.DR50"
				( objectStatus "@baseboard_fab2_lib.baseboard_fab2(sch_1):page27_i172:ddr4_odt(0)" )
			)
			( pin "U5D1.DN48"
				( objectStatus "@baseboard_fab2_lib.baseboard_fab2(sch_1):page27_i172:ddr4_odt(1)" )
			)
			( pin "U5D1.DT49"
				( objectStatus "@baseboard_fab2_lib.baseboard_fab2(sch_1):page27_i172:ddr4_odt(2)" )
			)
			( pin "U5D1.DM47"
				( objectStatus "@baseboard_fab2_lib.baseboard_fab2(sch_1):page27_i172:ddr4_odt(3)" )
			)
			( pin "U5D1.DV53"
				( objectStatus "@baseboard_fab2_lib.baseboard_fab2(sch_1):page27_i172:ddr4_par" )
			)
			( pin "U5D1.DC62"
				( objectStatus "@baseboard_fab2_lib.baseboard_fab2(sch_1):page28_i172:ddr5_act_n" )
			)
			( pin "U5D1.DD61"
				( objectStatus "@baseboard_fab2_lib.baseboard_fab2(sch_1):page28_i172:ddr5_alert_n" )
			)
			( pin "U5D1.DJ52"
				( objectStatus "@baseboard_fab2_lib.baseboard_fab2(sch_1):page28_i172:ddr5_ba(0)" )
			)
			( pin "U5D1.DC56"
				( objectStatus "@baseboard_fab2_lib.baseboard_fab2(sch_1):page28_i172:ddr5_ba(1)" )
			)
			( pin "U5D1.DA62"
				( objectStatus "@baseboard_fab2_lib.baseboard_fab2(sch_1):page28_i172:ddr5_bg(0)" )
			)
			( pin "U5D1.DF61"
				( objectStatus "@baseboard_fab2_lib.baseboard_fab2(sch_1):page28_i172:ddr5_bg(1)" )
			)
			( pin "U5D1.DF45"
				( objectStatus "@baseboard_fab2_lib.baseboard_fab2(sch_1):page28_i172:ddr5_cid(2)" )
			)
			( pin "U5D1.DG62"
				( objectStatus "@baseboard_fab2_lib.baseboard_fab2(sch_1):page28_i172:ddr5_cke(0)" )
			)
			( pin "U5D1.DD63"
				( objectStatus "@baseboard_fab2_lib.baseboard_fab2(sch_1):page28_i172:ddr5_cke(1)" )
			)
			( pin "U5D1.DK63"
				( objectStatus "@baseboard_fab2_lib.baseboard_fab2(sch_1):page28_i172:ddr5_cke(2)" )
			)
			( pin "U5D1.DF63"
				( objectStatus "@baseboard_fab2_lib.baseboard_fab2(sch_1):page28_i172:ddr5_cke(3)" )
			)
			( pin "U5D1.DK55"
				( objectStatus "@baseboard_fab2_lib.baseboard_fab2(sch_1):page28_i172:ddr5_clk_dn(0)" )
			)
			( pin "U5D1.DF55"
				( objectStatus "@baseboard_fab2_lib.baseboard_fab2(sch_1):page28_i172:ddr5_clk_dn(1)" )
			)
			( pin "U5D1.DK57"
				( objectStatus "@baseboard_fab2_lib.baseboard_fab2(sch_1):page28_i172:ddr5_clk_dn(2)" )
			)
			( pin "U5D1.DF57"
				( objectStatus "@baseboard_fab2_lib.baseboard_fab2(sch_1):page28_i172:ddr5_clk_dn(3)" )
			)
			( pin "U5D1.DJ54"
				( objectStatus "@baseboard_fab2_lib.baseboard_fab2(sch_1):page28_i172:ddr5_clk_dp(0)" )
			)
			( pin "U5D1.DG54"
				( objectStatus "@baseboard_fab2_lib.baseboard_fab2(sch_1):page28_i172:ddr5_clk_dp(1)" )
			)
			( pin "U5D1.DJ56"
				( objectStatus "@baseboard_fab2_lib.baseboard_fab2(sch_1):page28_i172:ddr5_clk_dp(2)" )
			)
			( pin "U5D1.DG56"
				( objectStatus "@baseboard_fab2_lib.baseboard_fab2(sch_1):page28_i172:ddr5_clk_dp(3)" )
			)
			( pin "U5D1.DK51"
				( objectStatus "@baseboard_fab2_lib.baseboard_fab2(sch_1):page28_i172:ddr5_cs_n(0)" )
			)
			( pin "U5D1.DF49"
				( objectStatus "@baseboard_fab2_lib.baseboard_fab2(sch_1):page28_i172:ddr5_cs_n(1)" )
			)
			( pin "U5D1.DJ46"
				( objectStatus "@baseboard_fab2_lib.baseboard_fab2(sch_1):page28_i172:ddr5_cs_n(2)" )
			)
			( pin "U5D1.DG46"
				( objectStatus "@baseboard_fab2_lib.baseboard_fab2(sch_1):page28_i172:ddr5_cs_n(3)" )
			)
			( pin "U5D1.DF51"
				( objectStatus "@baseboard_fab2_lib.baseboard_fab2(sch_1):page28_i172:ddr5_cs_n(4)" )
			)
			( pin "U5D1.DJ48"
				( objectStatus "@baseboard_fab2_lib.baseboard_fab2(sch_1):page28_i172:ddr5_cs_n(5)" )
			)
			( pin "U5D1.DM45"
				( objectStatus "@baseboard_fab2_lib.baseboard_fab2(sch_1):page28_i172:ddr5_cs_n(6)" )
			)
			( pin "U5D1.DK45"
				( objectStatus "@baseboard_fab2_lib.baseboard_fab2(sch_1):page28_i172:ddr5_cs_n(7)" )
			)
			( pin "U5D1.CR74"
				( objectStatus "@baseboard_fab2_lib.baseboard_fab2(sch_1):page28_i172:ddr5_dq(0)" )
			)
			( pin "U5D1.CN76"
				( objectStatus "@baseboard_fab2_lib.baseboard_fab2(sch_1):page28_i172:ddr5_dq(1)" )
			)
			( pin "U5D1.CW76"
				( objectStatus "@baseboard_fab2_lib.baseboard_fab2(sch_1):page28_i172:ddr5_dq(2)" )
			)
			( pin "U5D1.CV77"
				( objectStatus "@baseboard_fab2_lib.baseboard_fab2(sch_1):page28_i172:ddr5_dq(3)" )
			)
			( pin "U5D1.CN74"
				( objectStatus "@baseboard_fab2_lib.baseboard_fab2(sch_1):page28_i172:ddr5_dq(4)" )
			)
			( pin "U5D1.CM75"
				( objectStatus "@baseboard_fab2_lib.baseboard_fab2(sch_1):page28_i172:ddr5_dq(5)" )
			)
			( pin "U5D1.CV75"
				( objectStatus "@baseboard_fab2_lib.baseboard_fab2(sch_1):page28_i172:ddr5_dq(6)" )
			)
			( pin "U5D1.CT77"
				( objectStatus "@baseboard_fab2_lib.baseboard_fab2(sch_1):page28_i172:ddr5_dq(7)" )
			)
			( pin "U5D1.DE74"
				( objectStatus "@baseboard_fab2_lib.baseboard_fab2(sch_1):page28_i172:ddr5_dq(8)" )
			)
			( pin "U5D1.DC76"
				( objectStatus "@baseboard_fab2_lib.baseboard_fab2(sch_1):page28_i172:ddr5_dq(9)" )
			)
			( pin "U5D1.DH75"
				( objectStatus "@baseboard_fab2_lib.baseboard_fab2(sch_1):page28_i172:ddr5_dq(10)" )
			)
			( pin "U5D1.DJ76"
				( objectStatus "@baseboard_fab2_lib.baseboard_fab2(sch_1):page28_i172:ddr5_dq(11)" )
			)
			( pin "U5D1.DC74"
				( objectStatus "@baseboard_fab2_lib.baseboard_fab2(sch_1):page28_i172:ddr5_dq(12)" )
			)
			( pin "U5D1.DB75"
				( objectStatus "@baseboard_fab2_lib.baseboard_fab2(sch_1):page28_i172:ddr5_dq(13)" )
			)
			( pin "U5D1.DF77"
				( objectStatus "@baseboard_fab2_lib.baseboard_fab2(sch_1):page28_i172:ddr5_dq(14)" )
			)
			( pin "U5D1.DH77"
				( objectStatus "@baseboard_fab2_lib.baseboard_fab2(sch_1):page28_i172:ddr5_dq(15)" )
			)
			( pin "U5D1.DG70"
				( objectStatus "@baseboard_fab2_lib.baseboard_fab2(sch_1):page28_i172:ddr5_dq(16)" )
			)
			( pin "U5D1.DJ72"
				( objectStatus "@baseboard_fab2_lib.baseboard_fab2(sch_1):page28_i172:ddr5_dq(17)" )
			)
			( pin "U5D1.DM69"
				( objectStatus "@baseboard_fab2_lib.baseboard_fab2(sch_1):page28_i172:ddr5_dq(18)" )
			)
			( pin "U5D1.DN70"
				( objectStatus "@baseboard_fab2_lib.baseboard_fab2(sch_1):page28_i172:ddr5_dq(19)" )
			)
			( pin "U5D1.DF71"
				( objectStatus "@baseboard_fab2_lib.baseboard_fab2(sch_1):page28_i172:ddr5_dq(20)" )
			)
			( pin "U5D1.DG72"
				( objectStatus "@baseboard_fab2_lib.baseboard_fab2(sch_1):page28_i172:ddr5_dq(21)" )
			)
			( pin "U5D1.DK69"
				( objectStatus "@baseboard_fab2_lib.baseboard_fab2(sch_1):page28_i172:ddr5_dq(22)" )
			)
			( pin "U5D1.DM71"
				( objectStatus "@baseboard_fab2_lib.baseboard_fab2(sch_1):page28_i172:ddr5_dq(23)" )
			)
			( pin "U5D1.CN66"
				( objectStatus "@baseboard_fab2_lib.baseboard_fab2(sch_1):page28_i172:ddr5_dq(24)" )
			)
			( pin "U5D1.CU66"
				( objectStatus "@baseboard_fab2_lib.baseboard_fab2(sch_1):page28_i172:ddr5_dq(25)" )
			)
			( pin "U5D1.CP63"
				( objectStatus "@baseboard_fab2_lib.baseboard_fab2(sch_1):page28_i172:ddr5_dq(26)" )
			)
			( pin "U5D1.CT63"
				( objectStatus "@baseboard_fab2_lib.baseboard_fab2(sch_1):page28_i172:ddr5_dq(27)" )
			)
			( pin "U5D1.CP67"
				( objectStatus "@baseboard_fab2_lib.baseboard_fab2(sch_1):page28_i172:ddr5_dq(28)" )
			)
			( pin "U5D1.CT67"
				( objectStatus "@baseboard_fab2_lib.baseboard_fab2(sch_1):page28_i172:ddr5_dq(29)" )
			)
			( pin "U5D1.CN64"
				( objectStatus "@baseboard_fab2_lib.baseboard_fab2(sch_1):page28_i172:ddr5_dq(30)" )
			)
			( pin "U5D1.CU64"
				( objectStatus "@baseboard_fab2_lib.baseboard_fab2(sch_1):page28_i172:ddr5_dq(31)" )
			)
			( pin "U5D1.DD41"
				( objectStatus "@baseboard_fab2_lib.baseboard_fab2(sch_1):page28_i172:ddr5_dq(32)" )
			)
			( pin "U5D1.DG42"
				( objectStatus "@baseboard_fab2_lib.baseboard_fab2(sch_1):page28_i172:ddr5_dq(33)" )
			)
			( pin "U5D1.DE38"
				( objectStatus "@baseboard_fab2_lib.baseboard_fab2(sch_1):page28_i172:ddr5_dq(34)" )
			)
			( pin "U5D1.DG38"
				( objectStatus "@baseboard_fab2_lib.baseboard_fab2(sch_1):page28_i172:ddr5_dq(35)" )
			)
			( pin "U5D1.DA42"
				( objectStatus "@baseboard_fab2_lib.baseboard_fab2(sch_1):page28_i172:ddr5_dq(36)" )
			)
			( pin "U5D1.DE42"
				( objectStatus "@baseboard_fab2_lib.baseboard_fab2(sch_1):page28_i172:ddr5_dq(37)" )
			)
			( pin "U5D1.DD39"
				( objectStatus "@baseboard_fab2_lib.baseboard_fab2(sch_1):page28_i172:ddr5_dq(38)" )
			)
			( pin "U5D1.DH39"
				( objectStatus "@baseboard_fab2_lib.baseboard_fab2(sch_1):page28_i172:ddr5_dq(39)" )
			)
			( pin "U5D1.DF33"
				( objectStatus "@baseboard_fab2_lib.baseboard_fab2(sch_1):page28_i172:ddr5_dq(40)" )
			)
			( pin "U5D1.DK33"
				( objectStatus "@baseboard_fab2_lib.baseboard_fab2(sch_1):page28_i172:ddr5_dq(41)" )
			)
			( pin "U5D1.DG30"
				( objectStatus "@baseboard_fab2_lib.baseboard_fab2(sch_1):page28_i172:ddr5_dq(42)" )
			)
			( pin "U5D1.DJ30"
				( objectStatus "@baseboard_fab2_lib.baseboard_fab2(sch_1):page28_i172:ddr5_dq(43)" )
			)
			( pin "U5D1.DG34"
				( objectStatus "@baseboard_fab2_lib.baseboard_fab2(sch_1):page28_i172:ddr5_dq(44)" )
			)
			( pin "U5D1.DJ34"
				( objectStatus "@baseboard_fab2_lib.baseboard_fab2(sch_1):page28_i172:ddr5_dq(45)" )
			)
			( pin "U5D1.DF31"
				( objectStatus "@baseboard_fab2_lib.baseboard_fab2(sch_1):page28_i172:ddr5_dq(46)" )
			)
			( pin "U5D1.DK31"
				( objectStatus "@baseboard_fab2_lib.baseboard_fab2(sch_1):page28_i172:ddr5_dq(47)" )
			)
			( pin "U5D1.CW36"
				( objectStatus "@baseboard_fab2_lib.baseboard_fab2(sch_1):page28_i172:ddr5_dq(48)" )
			)
			( pin "U5D1.DC36"
				( objectStatus "@baseboard_fab2_lib.baseboard_fab2(sch_1):page28_i172:ddr5_dq(49)" )
			)
			( pin "U5D1.CY33"
				( objectStatus "@baseboard_fab2_lib.baseboard_fab2(sch_1):page28_i172:ddr5_dq(50)" )
			)
			( pin "U5D1.DB33"
				( objectStatus "@baseboard_fab2_lib.baseboard_fab2(sch_1):page28_i172:ddr5_dq(51)" )
			)
			( pin "U5D1.CY37"
				( objectStatus "@baseboard_fab2_lib.baseboard_fab2(sch_1):page28_i172:ddr5_dq(52)" )
			)
			( pin "U5D1.DB37"
				( objectStatus "@baseboard_fab2_lib.baseboard_fab2(sch_1):page28_i172:ddr5_dq(53)" )
			)
			( pin "U5D1.CW34"
				( objectStatus "@baseboard_fab2_lib.baseboard_fab2(sch_1):page28_i172:ddr5_dq(54)" )
			)
			( pin "U5D1.DC34"
				( objectStatus "@baseboard_fab2_lib.baseboard_fab2(sch_1):page28_i172:ddr5_dq(55)" )
			)
			( pin "U5D1.CW30"
				( objectStatus "@baseboard_fab2_lib.baseboard_fab2(sch_1):page28_i172:ddr5_dq(56)" )
			)
			( pin "U5D1.DC30"
				( objectStatus "@baseboard_fab2_lib.baseboard_fab2(sch_1):page28_i172:ddr5_dq(57)" )
			)
			( pin "U5D1.CY27"
				( objectStatus "@baseboard_fab2_lib.baseboard_fab2(sch_1):page28_i172:ddr5_dq(58)" )
			)
			( pin "U5D1.DB27"
				( objectStatus "@baseboard_fab2_lib.baseboard_fab2(sch_1):page28_i172:ddr5_dq(59)" )
			)
			( pin "U5D1.CY31"
				( objectStatus "@baseboard_fab2_lib.baseboard_fab2(sch_1):page28_i172:ddr5_dq(60)" )
			)
			( pin "U5D1.DB31"
				( objectStatus "@baseboard_fab2_lib.baseboard_fab2(sch_1):page28_i172:ddr5_dq(61)" )
			)
			( pin "U5D1.CW28"
				( objectStatus "@baseboard_fab2_lib.baseboard_fab2(sch_1):page28_i172:ddr5_dq(62)" )
			)
			( pin "U5D1.DC28"
				( objectStatus "@baseboard_fab2_lib.baseboard_fab2(sch_1):page28_i172:ddr5_dq(63)" )
			)
			( pin "U5D1.CP77"
				( objectStatus "@baseboard_fab2_lib.baseboard_fab2(sch_1):page28_i172:ddr5_dqs_dn(0)" )
			)
			( pin "U5D1.DD77"
				( objectStatus "@baseboard_fab2_lib.baseboard_fab2(sch_1):page28_i172:ddr5_dqs_dn(1)" )
			)
			( pin "U5D1.DL72"
				( objectStatus "@baseboard_fab2_lib.baseboard_fab2(sch_1):page28_i172:ddr5_dqs_dn(2)" )
			)
			( pin "U5D1.CV65"
				( objectStatus "@baseboard_fab2_lib.baseboard_fab2(sch_1):page28_i172:ddr5_dqs_dn(3)" )
			)
			( pin "U5D1.DG40"
				( objectStatus "@baseboard_fab2_lib.baseboard_fab2(sch_1):page28_i172:ddr5_dqs_dn(4)" )
			)
			( pin "U5D1.DL32"
				( objectStatus "@baseboard_fab2_lib.baseboard_fab2(sch_1):page28_i172:ddr5_dqs_dn(5)" )
			)
			( pin "U5D1.DD35"
				( objectStatus "@baseboard_fab2_lib.baseboard_fab2(sch_1):page28_i172:ddr5_dqs_dn(6)" )
			)
			( pin "U5D1.DD29"
				( objectStatus "@baseboard_fab2_lib.baseboard_fab2(sch_1):page28_i172:ddr5_dqs_dn(7)" )
			)
			( pin "U5D1.CN70"
				( objectStatus "@baseboard_fab2_lib.baseboard_fab2(sch_1):page28_i172:ddr5_dqs_dn(8)" )
			)
			( pin "U5D1.CT75"
				( objectStatus "@baseboard_fab2_lib.baseboard_fab2(sch_1):page28_i172:ddr5_dqs_dn(9)" )
			)
			( pin "U5D1.DF75"
				( objectStatus "@baseboard_fab2_lib.baseboard_fab2(sch_1):page28_i172:ddr5_dqs_dn(10)" )
			)
			( pin "U5D1.DJ70"
				( objectStatus "@baseboard_fab2_lib.baseboard_fab2(sch_1):page28_i172:ddr5_dqs_dn(11)" )
			)
			( pin "U5D1.CP65"
				( objectStatus "@baseboard_fab2_lib.baseboard_fab2(sch_1):page28_i172:ddr5_dqs_dn(12)" )
			)
			( pin "U5D1.DE40"
				( objectStatus "@baseboard_fab2_lib.baseboard_fab2(sch_1):page28_i172:ddr5_dqs_dn(13)" )
			)
			( pin "U5D1.DG32"
				( objectStatus "@baseboard_fab2_lib.baseboard_fab2(sch_1):page28_i172:ddr5_dqs_dn(14)" )
			)
			( pin "U5D1.CY35"
				( objectStatus "@baseboard_fab2_lib.baseboard_fab2(sch_1):page28_i172:ddr5_dqs_dn(15)" )
			)
			( pin "U5D1.CY29"
				( objectStatus "@baseboard_fab2_lib.baseboard_fab2(sch_1):page28_i172:ddr5_dqs_dn(16)" )
			)
			( pin "U5D1.CJ70"
				( objectStatus "@baseboard_fab2_lib.baseboard_fab2(sch_1):page28_i172:ddr5_dqs_dn(17)" )
			)
			( pin "U5D1.CR76"
				( objectStatus "@baseboard_fab2_lib.baseboard_fab2(sch_1):page28_i172:ddr5_dqs_dp(0)" )
			)
			( pin "U5D1.DE76"
				( objectStatus "@baseboard_fab2_lib.baseboard_fab2(sch_1):page28_i172:ddr5_dqs_dp(1)" )
			)
			( pin "U5D1.DK71"
				( objectStatus "@baseboard_fab2_lib.baseboard_fab2(sch_1):page28_i172:ddr5_dqs_dp(2)" )
			)
			( pin "U5D1.CT65"
				( objectStatus "@baseboard_fab2_lib.baseboard_fab2(sch_1):page28_i172:ddr5_dqs_dp(3)" )
			)
			( pin "U5D1.DJ40"
				( objectStatus "@baseboard_fab2_lib.baseboard_fab2(sch_1):page28_i172:ddr5_dqs_dp(4)" )
			)
			( pin "U5D1.DJ32"
				( objectStatus "@baseboard_fab2_lib.baseboard_fab2(sch_1):page28_i172:ddr5_dqs_dp(5)" )
			)
			( pin "U5D1.DB35"
				( objectStatus "@baseboard_fab2_lib.baseboard_fab2(sch_1):page28_i172:ddr5_dqs_dp(6)" )
			)
			( pin "U5D1.DB29"
				( objectStatus "@baseboard_fab2_lib.baseboard_fab2(sch_1):page28_i172:ddr5_dqs_dp(7)" )
			)
			( pin "U5D1.CL70"
				( objectStatus "@baseboard_fab2_lib.baseboard_fab2(sch_1):page28_i172:ddr5_dqs_dp(8)" )
			)
			( pin "U5D1.CU74"
				( objectStatus "@baseboard_fab2_lib.baseboard_fab2(sch_1):page28_i172:ddr5_dqs_dp(9)" )
			)
			( pin "U5D1.DG74"
				( objectStatus "@baseboard_fab2_lib.baseboard_fab2(sch_1):page28_i172:ddr5_dqs_dp(10)" )
			)
			( pin "U5D1.DH69"
				( objectStatus "@baseboard_fab2_lib.baseboard_fab2(sch_1):page28_i172:ddr5_dqs_dp(11)" )
			)
			( pin "U5D1.CM65"
				( objectStatus "@baseboard_fab2_lib.baseboard_fab2(sch_1):page28_i172:ddr5_dqs_dp(12)" )
			)
			( pin "U5D1.DC40"
				( objectStatus "@baseboard_fab2_lib.baseboard_fab2(sch_1):page28_i172:ddr5_dqs_dp(13)" )
			)
			( pin "U5D1.DE32"
				( objectStatus "@baseboard_fab2_lib.baseboard_fab2(sch_1):page28_i172:ddr5_dqs_dp(14)" )
			)
			( pin "U5D1.CV35"
				( objectStatus "@baseboard_fab2_lib.baseboard_fab2(sch_1):page28_i172:ddr5_dqs_dp(15)" )
			)
			( pin "U5D1.CV29"
				( objectStatus "@baseboard_fab2_lib.baseboard_fab2(sch_1):page28_i172:ddr5_dqs_dp(16)" )
			)
			( pin "U5D1.CG70"
				( objectStatus "@baseboard_fab2_lib.baseboard_fab2(sch_1):page28_i172:ddr5_dqs_dp(17)" )
			)
			( pin "U5D1.CH71"
				( objectStatus "@baseboard_fab2_lib.baseboard_fab2(sch_1):page28_i172:ddr5_ecc(0)" )
			)
			( pin "U5D1.CM71"
				( objectStatus "@baseboard_fab2_lib.baseboard_fab2(sch_1):page28_i172:ddr5_ecc(1)" )
			)
			( pin "U5D1.CJ68"
				( objectStatus "@baseboard_fab2_lib.baseboard_fab2(sch_1):page28_i172:ddr5_ecc(2)" )
			)
			( pin "U5D1.CL68"
				( objectStatus "@baseboard_fab2_lib.baseboard_fab2(sch_1):page28_i172:ddr5_ecc(3)" )
			)
			( pin "U5D1.CJ72"
				( objectStatus "@baseboard_fab2_lib.baseboard_fab2(sch_1):page28_i172:ddr5_ecc(4)" )
			)
			( pin "U5D1.CL72"
				( objectStatus "@baseboard_fab2_lib.baseboard_fab2(sch_1):page28_i172:ddr5_ecc(5)" )
			)
			( pin "U5D1.CH69"
				( objectStatus "@baseboard_fab2_lib.baseboard_fab2(sch_1):page28_i172:ddr5_ecc(6)" )
			)
			( pin "U5D1.CM69"
				( objectStatus "@baseboard_fab2_lib.baseboard_fab2(sch_1):page28_i172:ddr5_ecc(7)" )
			)
			( pin "U5D1.DF53"
				( objectStatus "@baseboard_fab2_lib.baseboard_fab2(sch_1):page28_i172:ddr5_ma(0)" )
			)
			( pin "U5D1.DC58"
				( objectStatus "@baseboard_fab2_lib.baseboard_fab2(sch_1):page28_i172:ddr5_ma(1)" )
			)
			( pin "U5D1.DD57"
				( objectStatus "@baseboard_fab2_lib.baseboard_fab2(sch_1):page28_i172:ddr5_ma(2)" )
			)
			( pin "U5D1.DG58"
				( objectStatus "@baseboard_fab2_lib.baseboard_fab2(sch_1):page28_i172:ddr5_ma(3)" )
			)
			( pin "U5D1.DJ58"
				( objectStatus "@baseboard_fab2_lib.baseboard_fab2(sch_1):page28_i172:ddr5_ma(4)" )
			)
			( pin "U5D1.DF59"
				( objectStatus "@baseboard_fab2_lib.baseboard_fab2(sch_1):page28_i172:ddr5_ma(5)" )
			)
			( pin "U5D1.DK59"
				( objectStatus "@baseboard_fab2_lib.baseboard_fab2(sch_1):page28_i172:ddr5_ma(6)" )
			)
			( pin "U5D1.DC60"
				( objectStatus "@baseboard_fab2_lib.baseboard_fab2(sch_1):page28_i172:ddr5_ma(7)" )
			)
			( pin "U5D1.DD59"
				( objectStatus "@baseboard_fab2_lib.baseboard_fab2(sch_1):page28_i172:ddr5_ma(8)" )
			)
			( pin "U5D1.DA58"
				( objectStatus "@baseboard_fab2_lib.baseboard_fab2(sch_1):page28_i172:ddr5_ma(9)" )
			)
			( pin "U5D1.DD55"
				( objectStatus "@baseboard_fab2_lib.baseboard_fab2(sch_1):page28_i172:ddr5_ma(10)" )
			)
			( pin "U5D1.DA60"
				( objectStatus "@baseboard_fab2_lib.baseboard_fab2(sch_1):page28_i172:ddr5_ma(11)" )
			)
			( pin "U5D1.DG60"
				( objectStatus "@baseboard_fab2_lib.baseboard_fab2(sch_1):page28_i172:ddr5_ma(12)" )
			)
			( pin "U5D1.DD53"
				( objectStatus "@baseboard_fab2_lib.baseboard_fab2(sch_1):page28_i172:ddr5_ma(13)" )
			)
			( pin "U5D1.DJ50"
				( objectStatus "@baseboard_fab2_lib.baseboard_fab2(sch_1):page28_i172:ddr5_ma(14)" )
			)
			( pin "U5D1.DC54"
				( objectStatus "@baseboard_fab2_lib.baseboard_fab2(sch_1):page28_i172:ddr5_ma(15)" )
			)
			( pin "U5D1.DG52"
				( objectStatus "@baseboard_fab2_lib.baseboard_fab2(sch_1):page28_i172:ddr5_ma(16)" )
			)
			( pin "U5D1.DE46"
				( objectStatus "@baseboard_fab2_lib.baseboard_fab2(sch_1):page28_i172:ddr5_ma(17)" )
			)
			( pin "U5D1.DG50"
				( objectStatus "@baseboard_fab2_lib.baseboard_fab2(sch_1):page28_i172:ddr5_odt(0)" )
			)
			( pin "U5D1.DG48"
				( objectStatus "@baseboard_fab2_lib.baseboard_fab2(sch_1):page28_i172:ddr5_odt(1)" )
			)
			( pin "U5D1.DK49"
				( objectStatus "@baseboard_fab2_lib.baseboard_fab2(sch_1):page28_i172:ddr5_odt(2)" )
			)
			( pin "U5D1.DF47"
				( objectStatus "@baseboard_fab2_lib.baseboard_fab2(sch_1):page28_i172:ddr5_odt(3)" )
			)
			( pin "U5D1.DK53"
				( objectStatus "@baseboard_fab2_lib.baseboard_fab2(sch_1):page28_i172:ddr5_par" )
			)
			( pin "U5D1.BN22"
				( objectStatus "@baseboard_fab2_lib.baseboard_fab2(sch_1):page29_i61:cd_hfi0_i2cclk" )
			)
			( pin "U5D1.BP23"
				( objectStatus "@baseboard_fab2_lib.baseboard_fab2(sch_1):page29_i61:cd_hfi0_i2cdat" )
			)
			( pin "U5D1.BP19"
				( objectStatus "@baseboard_fab2_lib.baseboard_fab2(sch_1):page29_i61:cd_hfi0_int_n" )
			)
			( pin "U5D1.BK21"
				( objectStatus "@baseboard_fab2_lib.baseboard_fab2(sch_1):page29_i61:cd_hfi0_led_n" )
			)
			( pin "U5D1.BR20"
				( objectStatus "@baseboard_fab2_lib.baseboard_fab2(sch_1):page29_i61:cd_hfi0_modprst_n" )
			)
			( pin "U5D1.BN24"
				( objectStatus "@baseboard_fab2_lib.baseboard_fab2(sch_1):page29_i61:cd_hfi0_reset_n" )
			)
			( pin "U5D1.BJ22"
				( objectStatus "@baseboard_fab2_lib.baseboard_fab2(sch_1):page29_i61:cd_hfi1_i2cclk" )
			)
			( pin "U5D1.BH23"
				( objectStatus "@baseboard_fab2_lib.baseboard_fab2(sch_1):page29_i61:cd_hfi1_i2cdat" )
			)
			( pin "U5D1.BM21"
				( objectStatus "@baseboard_fab2_lib.baseboard_fab2(sch_1):page29_i61:cd_hfi1_int_n" )
			)
			( pin "U5D1.BM23"
				( objectStatus "@baseboard_fab2_lib.baseboard_fab2(sch_1):page29_i61:cd_hfi1_led_n" )
			)
			( pin "U5D1.BT19"
				( objectStatus "@baseboard_fab2_lib.baseboard_fab2(sch_1):page29_i61:cd_hfi1_modprst_n" )
			)
			( pin "U5D1.BK23"
				( objectStatus "@baseboard_fab2_lib.baseboard_fab2(sch_1):page29_i61:cd_hfi1_reset_n" )
			)
			( pin "U5D1.BE16"
				( objectStatus "@baseboard_fab2_lib.baseboard_fab2(sch_1):page29_i61:cd_hfi_refclk_dn" )
			)
			( pin "U5D1.BG16"
				( objectStatus "@baseboard_fab2_lib.baseboard_fab2(sch_1):page29_i61:cd_hfi_refclk_dp" )
			)
			( pin "U5D1.BU24"
				( objectStatus "@baseboard_fab2_lib.baseboard_fab2(sch_1):page29_i61:cd_pe_refclk_dn" )
			)
			( pin "U5D1.BW24"
				( objectStatus "@baseboard_fab2_lib.baseboard_fab2(sch_1):page29_i61:cd_pe_refclk_dp" )
			)
			( pin "U5D1.CF25"
				( objectStatus "@baseboard_fab2_lib.baseboard_fab2(sch_1):page29_i61:cd_por_n" )
			)
			( pin "U5D1.CB23"
				( objectStatus "@baseboard_fab2_lib.baseboard_fab2(sch_1):page29_i61:cd_tclk" )
			)
			( pin "U5D1.BY21"
				( objectStatus "@baseboard_fab2_lib.baseboard_fab2(sch_1):page29_i61:cd_tdi" )
			)
			( pin "U5D1.CC22"
				( objectStatus "@baseboard_fab2_lib.baseboard_fab2(sch_1):page29_i61:cd_tdo" )
			)
			( pin "U5D1.CE24"
				( objectStatus "@baseboard_fab2_lib.baseboard_fab2(sch_1):page29_i61:cd_tms" )
			)
			( pin "U5D1.CD23"
				( objectStatus "@baseboard_fab2_lib.baseboard_fab2(sch_1):page29_i61:cd_trst_n" )
			)
			( pin "U5D1.CK9"
				( objectStatus "@baseboard_fab2_lib.baseboard_fab2(sch_1):page29_i61:dmi_rx_dn(0)" )
			)
			( pin "U5D1.CM11"
				( objectStatus "@baseboard_fab2_lib.baseboard_fab2(sch_1):page29_i61:dmi_rx_dn(1)" )
			)
			( pin "U5D1.CR12"
				( objectStatus "@baseboard_fab2_lib.baseboard_fab2(sch_1):page29_i61:dmi_rx_dn(2)" )
			)
			( pin "U5D1.CT11"
				( objectStatus "@baseboard_fab2_lib.baseboard_fab2(sch_1):page29_i61:dmi_rx_dn(3)" )
			)
			( pin "U5D1.CL10"
				( objectStatus "@baseboard_fab2_lib.baseboard_fab2(sch_1):page29_i61:dmi_rx_dp(0)" )
			)
			( pin "U5D1.CN10"
				( objectStatus "@baseboard_fab2_lib.baseboard_fab2(sch_1):page29_i61:dmi_rx_dp(1)" )
			)
			( pin "U5D1.CP11"
				( objectStatus "@baseboard_fab2_lib.baseboard_fab2(sch_1):page29_i61:dmi_rx_dp(2)" )
			)
			( pin "U5D1.CV11"
				( objectStatus "@baseboard_fab2_lib.baseboard_fab2(sch_1):page29_i61:dmi_rx_dp(3)" )
			)
			( pin "U5D1.CG4"
				( objectStatus "@baseboard_fab2_lib.baseboard_fab2(sch_1):page29_i61:dmi_tx_dn(0)" )
			)
			( pin "U5D1.CJ4"
				( objectStatus "@baseboard_fab2_lib.baseboard_fab2(sch_1):page29_i61:dmi_tx_dn(1)" )
			)
			( pin "U5D1.CN4"
				( objectStatus "@baseboard_fab2_lib.baseboard_fab2(sch_1):page29_i61:dmi_tx_dn(2)" )
			)
			( pin "U5D1.CP5"
				( objectStatus "@baseboard_fab2_lib.baseboard_fab2(sch_1):page29_i61:dmi_tx_dn(3)" )
			)
			( pin "U5D1.CH5"
				( objectStatus "@baseboard_fab2_lib.baseboard_fab2(sch_1):page29_i61:dmi_tx_dp(0)" )
			)
			( pin "U5D1.CL4"
				( objectStatus "@baseboard_fab2_lib.baseboard_fab2(sch_1):page29_i61:dmi_tx_dp(1)" )
			)
			( pin "U5D1.CM3"
				( objectStatus "@baseboard_fab2_lib.baseboard_fab2(sch_1):page29_i61:dmi_tx_dp(2)" )
			)
			( pin "U5D1.CR4"
				( objectStatus "@baseboard_fab2_lib.baseboard_fab2(sch_1):page29_i61:dmi_tx_dp(3)" )
			)
			( pin "U5D1.BA76"
				( objectStatus "@baseboard_fab2_lib.baseboard_fab2(sch_1):page29_i61:rsvd(172)" )
			)
			( pin "U5D1.BA66"
				( objectStatus "@baseboard_fab2_lib.baseboard_fab2(sch_1):page29_i61:rsvd(173)" )
			)
			( pin "U5D1.BA64"
				( objectStatus "@baseboard_fab2_lib.baseboard_fab2(sch_1):page29_i61:rsvd(174)" )
			)
			( pin "U5D1.BA22"
				( objectStatus "@baseboard_fab2_lib.baseboard_fab2(sch_1):page29_i61:rsvd(175)" )
			)
			( pin "U5D1.BA18"
				( objectStatus "@baseboard_fab2_lib.baseboard_fab2(sch_1):page29_i61:rsvd(176)" )
			)
			( pin "U5D1.BA16"
				( objectStatus "@baseboard_fab2_lib.baseboard_fab2(sch_1):page29_i61:rsvd(177)" )
			)
			( pin "U5D1.BA14"
				( objectStatus "@baseboard_fab2_lib.baseboard_fab2(sch_1):page29_i61:rsvd(178)" )
			)
			( pin "U5D1.AY77"
				( objectStatus "@baseboard_fab2_lib.baseboard_fab2(sch_1):page29_i61:rsvd(179)" )
			)
			( pin "U5D1.AY75"
				( objectStatus "@baseboard_fab2_lib.baseboard_fab2(sch_1):page29_i61:rsvd(180)" )
			)
			( pin "U5D1.AY67"
				( objectStatus "@baseboard_fab2_lib.baseboard_fab2(sch_1):page29_i61:rsvd(181)" )
			)
			( pin "U5D1.AY65"
				( objectStatus "@baseboard_fab2_lib.baseboard_fab2(sch_1):page29_i61:rsvd(182)" )
			)
			( pin "U5D1.AW76"
				( objectStatus "@baseboard_fab2_lib.baseboard_fab2(sch_1):page29_i61:rsvd(183)" )
			)
			( pin "U5D1.AW64"
				( objectStatus "@baseboard_fab2_lib.baseboard_fab2(sch_1):page29_i61:rsvd(184)" )
			)
			( pin "U5D1.AV77"
				( objectStatus "@baseboard_fab2_lib.baseboard_fab2(sch_1):page29_i61:rsvd(186)" )
			)
			( pin "U5D1.AT25"
				( objectStatus "@baseboard_fab2_lib.baseboard_fab2(sch_1):page29_i61:rsvd(187)" )
			)
			( pin "U5D1.AT23"
				( objectStatus "@baseboard_fab2_lib.baseboard_fab2(sch_1):page29_i61:rsvd(188)" )
			)
			( pin "U5D1.AT13"
				( objectStatus "@baseboard_fab2_lib.baseboard_fab2(sch_1):page29_i61:rsvd(189)" )
			)
			( pin "U5D1.AR62"
				( objectStatus "@baseboard_fab2_lib.baseboard_fab2(sch_1):page29_i61:rsvd(190)" )
			)
			( pin "U5D1.AR26"
				( objectStatus "@baseboard_fab2_lib.baseboard_fab2(sch_1):page29_i61:rsvd(191)" )
			)
			( pin "U5D1.AR22"
				( objectStatus "@baseboard_fab2_lib.baseboard_fab2(sch_1):page29_i61:rsvd(192)" )
			)
			( pin "U5D1.AR20"
				( objectStatus "@baseboard_fab2_lib.baseboard_fab2(sch_1):page29_i61:rsvd(193)" )
			)
			( pin "U5D1.CW8"
				( objectStatus "@baseboard_fab2_lib.baseboard_fab2(sch_1):page30_i84:pe1_rx_dn(0)" )
			)
			( pin "U5D1.DA8"
				( objectStatus "@baseboard_fab2_lib.baseboard_fab2(sch_1):page30_i84:pe1_rx_dn(1)" )
			)
			( pin "U5D1.DC8"
				( objectStatus "@baseboard_fab2_lib.baseboard_fab2(sch_1):page30_i84:pe1_rx_dn(2)" )
			)
			( pin "U5D1.DC10"
				( objectStatus "@baseboard_fab2_lib.baseboard_fab2(sch_1):page30_i84:pe1_rx_dn(3)" )
			)
			( pin "U5D1.DE10"
				( objectStatus "@baseboard_fab2_lib.baseboard_fab2(sch_1):page30_i84:pe1_rx_dn(4)" )
			)
			( pin "U5D1.DH9"
				( objectStatus "@baseboard_fab2_lib.baseboard_fab2(sch_1):page30_i84:pe1_rx_dn(5)" )
			)
			( pin "U5D1.DK9"
				( objectStatus "@baseboard_fab2_lib.baseboard_fab2(sch_1):page30_i84:pe1_rx_dn(6)" )
			)
			( pin "U5D1.DM9"
				( objectStatus "@baseboard_fab2_lib.baseboard_fab2(sch_1):page30_i84:pe1_rx_dn(7)" )
			)
			( pin "U5D1.DM11"
				( objectStatus "@baseboard_fab2_lib.baseboard_fab2(sch_1):page30_i84:pe1_rx_dn(8)" )
			)
			( pin "U5D1.DP11"
				( objectStatus "@baseboard_fab2_lib.baseboard_fab2(sch_1):page30_i84:pe1_rx_dn(9)" )
			)
			( pin "U5D1.DT11"
				( objectStatus "@baseboard_fab2_lib.baseboard_fab2(sch_1):page30_i84:pe1_rx_dn(10)" )
			)
			( pin "U5D1.DT13"
				( objectStatus "@baseboard_fab2_lib.baseboard_fab2(sch_1):page30_i84:pe1_rx_dn(11)" )
			)
			( pin "U5D1.DV13"
				( objectStatus "@baseboard_fab2_lib.baseboard_fab2(sch_1):page30_i84:pe1_rx_dn(12)" )
			)
			( pin "U5D1.DW14"
				( objectStatus "@baseboard_fab2_lib.baseboard_fab2(sch_1):page30_i84:pe1_rx_dn(13)" )
			)
			( pin "U5D1.DY15"
				( objectStatus "@baseboard_fab2_lib.baseboard_fab2(sch_1):page30_i84:pe1_rx_dn(14)" )
			)
			( pin "U5D1.DU16"
				( objectStatus "@baseboard_fab2_lib.baseboard_fab2(sch_1):page30_i84:pe1_rx_dn(15)" )
			)
			( pin "U5D1.CU8"
				( objectStatus "@baseboard_fab2_lib.baseboard_fab2(sch_1):page30_i84:pe1_rx_dp(0)" )
			)
			( pin "U5D1.CY7"
				( objectStatus "@baseboard_fab2_lib.baseboard_fab2(sch_1):page30_i84:pe1_rx_dp(1)" )
			)
			( pin "U5D1.DB9"
				( objectStatus "@baseboard_fab2_lib.baseboard_fab2(sch_1):page30_i84:pe1_rx_dp(2)" )
			)
			( pin "U5D1.DA10"
				( objectStatus "@baseboard_fab2_lib.baseboard_fab2(sch_1):page30_i84:pe1_rx_dp(3)" )
			)
			( pin "U5D1.DD9"
				( objectStatus "@baseboard_fab2_lib.baseboard_fab2(sch_1):page30_i84:pe1_rx_dp(4)" )
			)
			( pin "U5D1.DF9"
				( objectStatus "@baseboard_fab2_lib.baseboard_fab2(sch_1):page30_i84:pe1_rx_dp(5)" )
			)
			( pin "U5D1.DJ8"
				( objectStatus "@baseboard_fab2_lib.baseboard_fab2(sch_1):page30_i84:pe1_rx_dp(6)" )
			)
			( pin "U5D1.DL10"
				( objectStatus "@baseboard_fab2_lib.baseboard_fab2(sch_1):page30_i84:pe1_rx_dp(7)" )
			)
			( pin "U5D1.DK11"
				( objectStatus "@baseboard_fab2_lib.baseboard_fab2(sch_1):page30_i84:pe1_rx_dp(8)" )
			)
			( pin "U5D1.DN10"
				( objectStatus "@baseboard_fab2_lib.baseboard_fab2(sch_1):page30_i84:pe1_rx_dp(9)" )
			)
			( pin "U5D1.DR12"
				( objectStatus "@baseboard_fab2_lib.baseboard_fab2(sch_1):page30_i84:pe1_rx_dp(10)" )
			)
			( pin "U5D1.DP13"
				( objectStatus "@baseboard_fab2_lib.baseboard_fab2(sch_1):page30_i84:pe1_rx_dp(11)" )
			)
			( pin "U5D1.DU12"
				( objectStatus "@baseboard_fab2_lib.baseboard_fab2(sch_1):page30_i84:pe1_rx_dp(12)" )
			)
			( pin "U5D1.DY13"
				( objectStatus "@baseboard_fab2_lib.baseboard_fab2(sch_1):page30_i84:pe1_rx_dp(13)" )
			)
			( pin "U5D1.DV15"
				( objectStatus "@baseboard_fab2_lib.baseboard_fab2(sch_1):page30_i84:pe1_rx_dp(14)" )
			)
			( pin "U5D1.DT15"
				( objectStatus "@baseboard_fab2_lib.baseboard_fab2(sch_1):page30_i84:pe1_rx_dp(15)" )
			)
			( pin "U5D1.DA2"
				( objectStatus "@baseboard_fab2_lib.baseboard_fab2(sch_1):page30_i84:pe1_tx_dn(0)" )
			)
			( pin "U5D1.DC2"
				( objectStatus "@baseboard_fab2_lib.baseboard_fab2(sch_1):page30_i84:pe1_tx_dn(1)" )
			)
			( pin "U5D1.DE2"
				( objectStatus "@baseboard_fab2_lib.baseboard_fab2(sch_1):page30_i84:pe1_tx_dn(2)" )
			)
			( pin "U5D1.DE4"
				( objectStatus "@baseboard_fab2_lib.baseboard_fab2(sch_1):page30_i84:pe1_tx_dn(3)" )
			)
			( pin "U5D1.DG4"
				( objectStatus "@baseboard_fab2_lib.baseboard_fab2(sch_1):page30_i84:pe1_tx_dn(4)" )
			)
			( pin "U5D1.DK3"
				( objectStatus "@baseboard_fab2_lib.baseboard_fab2(sch_1):page30_i84:pe1_tx_dn(5)" )
			)
			( pin "U5D1.DM3"
				( objectStatus "@baseboard_fab2_lib.baseboard_fab2(sch_1):page30_i84:pe1_tx_dn(6)" )
			)
			( pin "U5D1.DN4"
				( objectStatus "@baseboard_fab2_lib.baseboard_fab2(sch_1):page30_i84:pe1_tx_dn(7)" )
			)
			( pin "U5D1.DT5"
				( objectStatus "@baseboard_fab2_lib.baseboard_fab2(sch_1):page30_i84:pe1_tx_dn(8)" )
			)
			( pin "U5D1.DV3"
				( objectStatus "@baseboard_fab2_lib.baseboard_fab2(sch_1):page30_i84:pe1_tx_dn(9)" )
			)
			( pin "U5D1.DW4"
				( objectStatus "@baseboard_fab2_lib.baseboard_fab2(sch_1):page30_i84:pe1_tx_dn(10)" )
			)
			( pin "U5D1.DU6"
				( objectStatus "@baseboard_fab2_lib.baseboard_fab2(sch_1):page30_i84:pe1_tx_dn(11)" )
			)
			( pin "U5D1.DV7"
				( objectStatus "@baseboard_fab2_lib.baseboard_fab2(sch_1):page30_i84:pe1_tx_dn(12)" )
			)
			( pin "U5D1.DY7"
				( objectStatus "@baseboard_fab2_lib.baseboard_fab2(sch_1):page30_i84:pe1_tx_dn(13)" )
			)
			( pin "U5D1.EA8"
				( objectStatus "@baseboard_fab2_lib.baseboard_fab2(sch_1):page30_i84:pe1_tx_dn(14)" )
			)
			( pin "U5D1.ED9"
				( objectStatus "@baseboard_fab2_lib.baseboard_fab2(sch_1):page30_i84:pe1_tx_dn(15)" )
			)
			( pin "U5D1.CW2"
				( objectStatus "@baseboard_fab2_lib.baseboard_fab2(sch_1):page30_i84:pe1_tx_dp(0)" )
			)
			( pin "U5D1.DB1"
				( objectStatus "@baseboard_fab2_lib.baseboard_fab2(sch_1):page30_i84:pe1_tx_dp(1)" )
			)
			( pin "U5D1.DD3"
				( objectStatus "@baseboard_fab2_lib.baseboard_fab2(sch_1):page30_i84:pe1_tx_dp(2)" )
			)
			( pin "U5D1.DC4"
				( objectStatus "@baseboard_fab2_lib.baseboard_fab2(sch_1):page30_i84:pe1_tx_dp(3)" )
			)
			( pin "U5D1.DF3"
				( objectStatus "@baseboard_fab2_lib.baseboard_fab2(sch_1):page30_i84:pe1_tx_dp(4)" )
			)
			( pin "U5D1.DH3"
				( objectStatus "@baseboard_fab2_lib.baseboard_fab2(sch_1):page30_i84:pe1_tx_dp(5)" )
			)
			( pin "U5D1.DL2"
				( objectStatus "@baseboard_fab2_lib.baseboard_fab2(sch_1):page30_i84:pe1_tx_dp(6)" )
			)
			( pin "U5D1.DP3"
				( objectStatus "@baseboard_fab2_lib.baseboard_fab2(sch_1):page30_i84:pe1_tx_dp(7)" )
			)
			( pin "U5D1.DR4"
				( objectStatus "@baseboard_fab2_lib.baseboard_fab2(sch_1):page30_i84:pe1_tx_dp(8)" )
			)
			( pin "U5D1.DU2"
				( objectStatus "@baseboard_fab2_lib.baseboard_fab2(sch_1):page30_i84:pe1_tx_dp(9)" )
			)
			( pin "U5D1.DU4"
				( objectStatus "@baseboard_fab2_lib.baseboard_fab2(sch_1):page30_i84:pe1_tx_dp(10)" )
			)
			( pin "U5D1.DV5"
				( objectStatus "@baseboard_fab2_lib.baseboard_fab2(sch_1):page30_i84:pe1_tx_dp(11)" )
			)
			( pin "U5D1.DT7"
				( objectStatus "@baseboard_fab2_lib.baseboard_fab2(sch_1):page30_i84:pe1_tx_dp(12)" )
			)
			( pin "U5D1.DW6"
				( objectStatus "@baseboard_fab2_lib.baseboard_fab2(sch_1):page30_i84:pe1_tx_dp(13)" )
			)
			( pin "U5D1.EB7"
				( objectStatus "@baseboard_fab2_lib.baseboard_fab2(sch_1):page30_i84:pe1_tx_dp(14)" )
			)
			( pin "U5D1.EC8"
				( objectStatus "@baseboard_fab2_lib.baseboard_fab2(sch_1):page30_i84:pe1_tx_dp(15)" )
			)
			( pin "U5D1.CT9"
				( objectStatus "@baseboard_fab2_lib.baseboard_fab2(sch_1):page31_i106:pe2_rx_dn(0)" )
			)
			( pin "U5D1.CP9"
				( objectStatus "@baseboard_fab2_lib.baseboard_fab2(sch_1):page31_i106:pe2_rx_dn(1)" )
			)
			( pin "U5D1.CP7"
				( objectStatus "@baseboard_fab2_lib.baseboard_fab2(sch_1):page31_i106:pe2_rx_dn(2)" )
			)
			( pin "U5D1.CM7"
				( objectStatus "@baseboard_fab2_lib.baseboard_fab2(sch_1):page31_i106:pe2_rx_dn(3)" )
			)
			( pin "U5D1.CK7"
				( objectStatus "@baseboard_fab2_lib.baseboard_fab2(sch_1):page31_i106:pe2_rx_dn(4)" )
			)
			( pin "U5D1.CG8"
				( objectStatus "@baseboard_fab2_lib.baseboard_fab2(sch_1):page31_i106:pe2_rx_dn(5)" )
			)
			( pin "U5D1.CE6"
				( objectStatus "@baseboard_fab2_lib.baseboard_fab2(sch_1):page31_i106:pe2_rx_dn(6)" )
			)
			( pin "U5D1.CE8"
				( objectStatus "@baseboard_fab2_lib.baseboard_fab2(sch_1):page31_i106:pe2_rx_dn(7)" )
			)
			( pin "U5D1.BY9"
				( objectStatus "@baseboard_fab2_lib.baseboard_fab2(sch_1):page31_i106:pe2_rx_dn(8)" )
			)
			( pin "U5D1.BY7"
				( objectStatus "@baseboard_fab2_lib.baseboard_fab2(sch_1):page31_i106:pe2_rx_dn(9)" )
			)
			( pin "U5D1.BV7"
				( objectStatus "@baseboard_fab2_lib.baseboard_fab2(sch_1):page31_i106:pe2_rx_dn(10)" )
			)
			( pin "U5D1.BT7"
				( objectStatus "@baseboard_fab2_lib.baseboard_fab2(sch_1):page31_i106:pe2_rx_dn(11)" )
			)
			( pin "U5D1.BR8"
				( objectStatus "@baseboard_fab2_lib.baseboard_fab2(sch_1):page31_i106:pe2_rx_dn(12)" )
			)
			( pin "U5D1.BN8"
				( objectStatus "@baseboard_fab2_lib.baseboard_fab2(sch_1):page31_i106:pe2_rx_dn(13)" )
			)
			( pin "U5D1.BL8"
				( objectStatus "@baseboard_fab2_lib.baseboard_fab2(sch_1):page31_i106:pe2_rx_dn(14)" )
			)
			( pin "U5D1.BK9"
				( objectStatus "@baseboard_fab2_lib.baseboard_fab2(sch_1):page31_i106:pe2_rx_dn(15)" )
			)
			( pin "U5D1.CR8"
				( objectStatus "@baseboard_fab2_lib.baseboard_fab2(sch_1):page31_i106:pe2_rx_dp(0)" )
			)
			( pin "U5D1.CM9"
				( objectStatus "@baseboard_fab2_lib.baseboard_fab2(sch_1):page31_i106:pe2_rx_dp(1)" )
			)
			( pin "U5D1.CN8"
				( objectStatus "@baseboard_fab2_lib.baseboard_fab2(sch_1):page31_i106:pe2_rx_dp(2)" )
			)
			( pin "U5D1.CL6"
				( objectStatus "@baseboard_fab2_lib.baseboard_fab2(sch_1):page31_i106:pe2_rx_dp(3)" )
			)
			( pin "U5D1.CH7"
				( objectStatus "@baseboard_fab2_lib.baseboard_fab2(sch_1):page31_i106:pe2_rx_dp(4)" )
			)
			( pin "U5D1.CF7"
				( objectStatus "@baseboard_fab2_lib.baseboard_fab2(sch_1):page31_i106:pe2_rx_dp(5)" )
			)
			( pin "U5D1.CD7"
				( objectStatus "@baseboard_fab2_lib.baseboard_fab2(sch_1):page31_i106:pe2_rx_dp(6)" )
			)
			( pin "U5D1.CC8"
				( objectStatus "@baseboard_fab2_lib.baseboard_fab2(sch_1):page31_i106:pe2_rx_dp(7)" )
			)
			( pin "U5D1.BV9"
				( objectStatus "@baseboard_fab2_lib.baseboard_fab2(sch_1):page31_i106:pe2_rx_dp(8)" )
			)
			( pin "U5D1.BW8"
				( objectStatus "@baseboard_fab2_lib.baseboard_fab2(sch_1):page31_i106:pe2_rx_dp(9)" )
			)
			( pin "U5D1.BU6"
				( objectStatus "@baseboard_fab2_lib.baseboard_fab2(sch_1):page31_i106:pe2_rx_dp(10)" )
			)
			( pin "U5D1.BP7"
				( objectStatus "@baseboard_fab2_lib.baseboard_fab2(sch_1):page31_i106:pe2_rx_dp(11)" )
			)
			( pin "U5D1.BP9"
				( objectStatus "@baseboard_fab2_lib.baseboard_fab2(sch_1):page31_i106:pe2_rx_dp(12)" )
			)
			( pin "U5D1.BM7"
				( objectStatus "@baseboard_fab2_lib.baseboard_fab2(sch_1):page31_i106:pe2_rx_dp(13)" )
			)
			( pin "U5D1.BJ8"
				( objectStatus "@baseboard_fab2_lib.baseboard_fab2(sch_1):page31_i106:pe2_rx_dp(14)" )
			)
			( pin "U5D1.BJ10"
				( objectStatus "@baseboard_fab2_lib.baseboard_fab2(sch_1):page31_i106:pe2_rx_dp(15)" )
			)
			( pin "U5D1.CY3"
				( objectStatus "@baseboard_fab2_lib.baseboard_fab2(sch_1):page31_i106:pe2_tx_dn(0)" )
			)
			( pin "U5D1.CV3"
				( objectStatus "@baseboard_fab2_lib.baseboard_fab2(sch_1):page31_i106:pe2_tx_dn(1)" )
			)
			( pin "U5D1.CT1"
				( objectStatus "@baseboard_fab2_lib.baseboard_fab2(sch_1):page31_i106:pe2_tx_dn(2)" )
			)
			( pin "U5D1.CT3"
				( objectStatus "@baseboard_fab2_lib.baseboard_fab2(sch_1):page31_i106:pe2_tx_dn(3)" )
			)
			( pin "U5D1.CM1"
				( objectStatus "@baseboard_fab2_lib.baseboard_fab2(sch_1):page31_i106:pe2_tx_dn(4)" )
			)
			( pin "U5D1.CL2"
				( objectStatus "@baseboard_fab2_lib.baseboard_fab2(sch_1):page31_i106:pe2_tx_dn(5)" )
			)
			( pin "U5D1.CG2"
				( objectStatus "@baseboard_fab2_lib.baseboard_fab2(sch_1):page31_i106:pe2_tx_dn(6)" )
			)
			( pin "U5D1.CF3"
				( objectStatus "@baseboard_fab2_lib.baseboard_fab2(sch_1):page31_i106:pe2_tx_dn(7)" )
			)
			( pin "U5D1.CC2"
				( objectStatus "@baseboard_fab2_lib.baseboard_fab2(sch_1):page31_i106:pe2_tx_dn(8)" )
			)
			( pin "U5D1.CB3"
				( objectStatus "@baseboard_fab2_lib.baseboard_fab2(sch_1):page31_i106:pe2_tx_dn(9)" )
			)
			( pin "U5D1.CA4"
				( objectStatus "@baseboard_fab2_lib.baseboard_fab2(sch_1):page31_i106:pe2_tx_dn(10)" )
			)
			( pin "U5D1.BW4"
				( objectStatus "@baseboard_fab2_lib.baseboard_fab2(sch_1):page31_i106:pe2_tx_dn(11)" )
			)
			( pin "U5D1.BU4"
				( objectStatus "@baseboard_fab2_lib.baseboard_fab2(sch_1):page31_i106:pe2_tx_dn(12)" )
			)
			( pin "U5D1.BP5"
				( objectStatus "@baseboard_fab2_lib.baseboard_fab2(sch_1):page31_i106:pe2_tx_dn(13)" )
			)
			( pin "U5D1.BL4"
				( objectStatus "@baseboard_fab2_lib.baseboard_fab2(sch_1):page31_i106:pe2_tx_dn(14)" )
			)
			( pin "U5D1.BM5"
				( objectStatus "@baseboard_fab2_lib.baseboard_fab2(sch_1):page31_i106:pe2_tx_dn(15)" )
			)
			( pin "U5D1.CW4"
				( objectStatus "@baseboard_fab2_lib.baseboard_fab2(sch_1):page31_i106:pe2_tx_dp(0)" )
			)
			( pin "U5D1.CU2"
				( objectStatus "@baseboard_fab2_lib.baseboard_fab2(sch_1):page31_i106:pe2_tx_dp(1)" )
			)
			( pin "U5D1.CR2"
				( objectStatus "@baseboard_fab2_lib.baseboard_fab2(sch_1):page31_i106:pe2_tx_dp(2)" )
			)
			( pin "U5D1.CP3"
				( objectStatus "@baseboard_fab2_lib.baseboard_fab2(sch_1):page31_i106:pe2_tx_dp(3)" )
			)
			( pin "U5D1.CK1"
				( objectStatus "@baseboard_fab2_lib.baseboard_fab2(sch_1):page31_i106:pe2_tx_dp(4)" )
			)
			( pin "U5D1.CK3"
				( objectStatus "@baseboard_fab2_lib.baseboard_fab2(sch_1):page31_i106:pe2_tx_dp(5)" )
			)
			( pin "U5D1.CE2"
				( objectStatus "@baseboard_fab2_lib.baseboard_fab2(sch_1):page31_i106:pe2_tx_dp(6)" )
			)
			( pin "U5D1.CE4"
				( objectStatus "@baseboard_fab2_lib.baseboard_fab2(sch_1):page31_i106:pe2_tx_dp(7)" )
			)
			( pin "U5D1.CD3"
				( objectStatus "@baseboard_fab2_lib.baseboard_fab2(sch_1):page31_i106:pe2_tx_dp(8)" )
			)
			( pin "U5D1.BY3"
				( objectStatus "@baseboard_fab2_lib.baseboard_fab2(sch_1):page31_i106:pe2_tx_dp(9)" )
			)
			( pin "U5D1.BY5"
				( objectStatus "@baseboard_fab2_lib.baseboard_fab2(sch_1):page31_i106:pe2_tx_dp(10)" )
			)
			( pin "U5D1.BV3"
				( objectStatus "@baseboard_fab2_lib.baseboard_fab2(sch_1):page31_i106:pe2_tx_dp(11)" )
			)
			( pin "U5D1.BR4"
				( objectStatus "@baseboard_fab2_lib.baseboard_fab2(sch_1):page31_i106:pe2_tx_dp(12)" )
			)
			( pin "U5D1.BN4"
				( objectStatus "@baseboard_fab2_lib.baseboard_fab2(sch_1):page31_i106:pe2_tx_dp(13)" )
			)
			( pin "U5D1.BM3"
				( objectStatus "@baseboard_fab2_lib.baseboard_fab2(sch_1):page31_i106:pe2_tx_dp(14)" )
			)
			( pin "U5D1.BK5"
				( objectStatus "@baseboard_fab2_lib.baseboard_fab2(sch_1):page31_i106:pe2_tx_dp(15)" )
			)
			( pin "U5D1.EA18"
				( objectStatus "@baseboard_fab2_lib.baseboard_fab2(sch_1):page32_i89:pe3_rx_dn(0)" )
			)
			( pin "U5D1.DW18"
				( objectStatus "@baseboard_fab2_lib.baseboard_fab2(sch_1):page32_i89:pe3_rx_dn(1)" )
			)
			( pin "U5D1.DW16"
				( objectStatus "@baseboard_fab2_lib.baseboard_fab2(sch_1):page32_i89:pe3_rx_dn(2)" )
			)
			( pin "U5D1.DT19"
				( objectStatus "@baseboard_fab2_lib.baseboard_fab2(sch_1):page32_i89:pe3_rx_dn(3)" )
			)
			( pin "U5D1.DR16"
				( objectStatus "@baseboard_fab2_lib.baseboard_fab2(sch_1):page32_i89:pe3_rx_dn(4)" )
			)
			( pin "U5D1.DR14"
				( objectStatus "@baseboard_fab2_lib.baseboard_fab2(sch_1):page32_i89:pe3_rx_dn(5)" )
			)
			( pin "U5D1.DN14"
				( objectStatus "@baseboard_fab2_lib.baseboard_fab2(sch_1):page32_i89:pe3_rx_dn(6)" )
			)
			( pin "U5D1.DL14"
				( objectStatus "@baseboard_fab2_lib.baseboard_fab2(sch_1):page32_i89:pe3_rx_dn(7)" )
			)
			( pin "U5D1.DL12"
				( objectStatus "@baseboard_fab2_lib.baseboard_fab2(sch_1):page32_i89:pe3_rx_dn(8)" )
			)
			( pin "U5D1.DJ12"
				( objectStatus "@baseboard_fab2_lib.baseboard_fab2(sch_1):page32_i89:pe3_rx_dn(9)" )
			)
			( pin "U5D1.DG12"
				( objectStatus "@baseboard_fab2_lib.baseboard_fab2(sch_1):page32_i89:pe3_rx_dn(10)" )
			)
			( pin "U5D1.DG10"
				( objectStatus "@baseboard_fab2_lib.baseboard_fab2(sch_1):page32_i89:pe3_rx_dn(11)" )
			)
			( pin "U5D1.DD13"
				( objectStatus "@baseboard_fab2_lib.baseboard_fab2(sch_1):page32_i89:pe3_rx_dn(12)" )
			)
			( pin "U5D1.DB11"
				( objectStatus "@baseboard_fab2_lib.baseboard_fab2(sch_1):page32_i89:pe3_rx_dn(13)" )
			)
			( pin "U5D1.CY11"
				( objectStatus "@baseboard_fab2_lib.baseboard_fab2(sch_1):page32_i89:pe3_rx_dn(14)" )
			)
			( pin "U5D1.CV9"
				( objectStatus "@baseboard_fab2_lib.baseboard_fab2(sch_1):page32_i89:pe3_rx_dn(15)" )
			)
			( pin "U5D1.DY17"
				( objectStatus "@baseboard_fab2_lib.baseboard_fab2(sch_1):page32_i89:pe3_rx_dp(0)" )
			)
			( pin "U5D1.DU18"
				( objectStatus "@baseboard_fab2_lib.baseboard_fab2(sch_1):page32_i89:pe3_rx_dp(1)" )
			)
			( pin "U5D1.DV17"
				( objectStatus "@baseboard_fab2_lib.baseboard_fab2(sch_1):page32_i89:pe3_rx_dp(2)" )
			)
			( pin "U5D1.DR18"
				( objectStatus "@baseboard_fab2_lib.baseboard_fab2(sch_1):page32_i89:pe3_rx_dp(3)" )
			)
			( pin "U5D1.DN16"
				( objectStatus "@baseboard_fab2_lib.baseboard_fab2(sch_1):page32_i89:pe3_rx_dp(4)" )
			)
			( pin "U5D1.DP15"
				( objectStatus "@baseboard_fab2_lib.baseboard_fab2(sch_1):page32_i89:pe3_rx_dp(5)" )
			)
			( pin "U5D1.DM13"
				( objectStatus "@baseboard_fab2_lib.baseboard_fab2(sch_1):page32_i89:pe3_rx_dp(6)" )
			)
			( pin "U5D1.DJ14"
				( objectStatus "@baseboard_fab2_lib.baseboard_fab2(sch_1):page32_i89:pe3_rx_dp(7)" )
			)
			( pin "U5D1.DK13"
				( objectStatus "@baseboard_fab2_lib.baseboard_fab2(sch_1):page32_i89:pe3_rx_dp(8)" )
			)
			( pin "U5D1.DH11"
				( objectStatus "@baseboard_fab2_lib.baseboard_fab2(sch_1):page32_i89:pe3_rx_dp(9)" )
			)
			( pin "U5D1.DE12"
				( objectStatus "@baseboard_fab2_lib.baseboard_fab2(sch_1):page32_i89:pe3_rx_dp(10)" )
			)
			( pin "U5D1.DF11"
				( objectStatus "@baseboard_fab2_lib.baseboard_fab2(sch_1):page32_i89:pe3_rx_dp(11)" )
			)
			( pin "U5D1.DC12"
				( objectStatus "@baseboard_fab2_lib.baseboard_fab2(sch_1):page32_i89:pe3_rx_dp(12)" )
			)
			( pin "U5D1.DA12"
				( objectStatus "@baseboard_fab2_lib.baseboard_fab2(sch_1):page32_i89:pe3_rx_dp(13)" )
			)
			( pin "U5D1.CW10"
				( objectStatus "@baseboard_fab2_lib.baseboard_fab2(sch_1):page32_i89:pe3_rx_dp(14)" )
			)
			( pin "U5D1.CU10"
				( objectStatus "@baseboard_fab2_lib.baseboard_fab2(sch_1):page32_i89:pe3_rx_dp(15)" )
			)
			( pin "U5D1.EE14"
				( objectStatus "@baseboard_fab2_lib.baseboard_fab2(sch_1):page32_i89:pe3_tx_dn(0)" )
			)
			( pin "U5D1.EE12"
				( objectStatus "@baseboard_fab2_lib.baseboard_fab2(sch_1):page32_i89:pe3_tx_dn(1)" )
			)
			( pin "U5D1.EC12"
				( objectStatus "@baseboard_fab2_lib.baseboard_fab2(sch_1):page32_i89:pe3_tx_dn(2)" )
			)
			( pin "U5D1.DY11"
				( objectStatus "@baseboard_fab2_lib.baseboard_fab2(sch_1):page32_i89:pe3_tx_dn(3)" )
			)
			( pin "U5D1.EB9"
				( objectStatus "@baseboard_fab2_lib.baseboard_fab2(sch_1):page32_i89:pe3_tx_dn(4)" )
			)
			( pin "U5D1.DW10"
				( objectStatus "@baseboard_fab2_lib.baseboard_fab2(sch_1):page32_i89:pe3_tx_dn(5)" )
			)
			( pin "U5D1.DU8"
				( objectStatus "@baseboard_fab2_lib.baseboard_fab2(sch_1):page32_i89:pe3_tx_dn(6)" )
			)
			( pin "U5D1.DR8"
				( objectStatus "@baseboard_fab2_lib.baseboard_fab2(sch_1):page32_i89:pe3_tx_dn(7)" )
			)
			( pin "U5D1.DM7"
				( objectStatus "@baseboard_fab2_lib.baseboard_fab2(sch_1):page32_i89:pe3_tx_dn(8)" )
			)
			( pin "U5D1.DP5"
				( objectStatus "@baseboard_fab2_lib.baseboard_fab2(sch_1):page32_i89:pe3_tx_dn(9)" )
			)
			( pin "U5D1.DL6"
				( objectStatus "@baseboard_fab2_lib.baseboard_fab2(sch_1):page32_i89:pe3_tx_dn(10)" )
			)
			( pin "U5D1.DJ4"
				( objectStatus "@baseboard_fab2_lib.baseboard_fab2(sch_1):page32_i89:pe3_tx_dn(11)" )
			)
			( pin "U5D1.DJ6"
				( objectStatus "@baseboard_fab2_lib.baseboard_fab2(sch_1):page32_i89:pe3_tx_dn(12)" )
			)
			( pin "U5D1.DD5"
				( objectStatus "@baseboard_fab2_lib.baseboard_fab2(sch_1):page32_i89:pe3_tx_dn(13)" )
			)
			( pin "U5D1.DB5"
				( objectStatus "@baseboard_fab2_lib.baseboard_fab2(sch_1):page32_i89:pe3_tx_dn(14)" )
			)
			( pin "U5D1.CY5"
				( objectStatus "@baseboard_fab2_lib.baseboard_fab2(sch_1):page32_i89:pe3_tx_dn(15)" )
			)
			( pin "U5D1.EC14"
				( objectStatus "@baseboard_fab2_lib.baseboard_fab2(sch_1):page32_i89:pe3_tx_dp(0)" )
			)
			( pin "U5D1.ED13"
				( objectStatus "@baseboard_fab2_lib.baseboard_fab2(sch_1):page32_i89:pe3_tx_dp(1)" )
			)
			( pin "U5D1.EB11"
				( objectStatus "@baseboard_fab2_lib.baseboard_fab2(sch_1):page32_i89:pe3_tx_dp(2)" )
			)
			( pin "U5D1.EA10"
				( objectStatus "@baseboard_fab2_lib.baseboard_fab2(sch_1):page32_i89:pe3_tx_dp(3)" )
			)
			( pin "U5D1.DY9"
				( objectStatus "@baseboard_fab2_lib.baseboard_fab2(sch_1):page32_i89:pe3_tx_dp(4)" )
			)
			( pin "U5D1.DV9"
				( objectStatus "@baseboard_fab2_lib.baseboard_fab2(sch_1):page32_i89:pe3_tx_dp(5)" )
			)
			( pin "U5D1.DT9"
				( objectStatus "@baseboard_fab2_lib.baseboard_fab2(sch_1):page32_i89:pe3_tx_dp(6)" )
			)
			( pin "U5D1.DP7"
				( objectStatus "@baseboard_fab2_lib.baseboard_fab2(sch_1):page32_i89:pe3_tx_dp(7)" )
			)
			( pin "U5D1.DN6"
				( objectStatus "@baseboard_fab2_lib.baseboard_fab2(sch_1):page32_i89:pe3_tx_dp(8)" )
			)
			( pin "U5D1.DM5"
				( objectStatus "@baseboard_fab2_lib.baseboard_fab2(sch_1):page32_i89:pe3_tx_dp(9)" )
			)
			( pin "U5D1.DK5"
				( objectStatus "@baseboard_fab2_lib.baseboard_fab2(sch_1):page32_i89:pe3_tx_dp(10)" )
			)
			( pin "U5D1.DH5"
				( objectStatus "@baseboard_fab2_lib.baseboard_fab2(sch_1):page32_i89:pe3_tx_dp(11)" )
			)
			( pin "U5D1.DG6"
				( objectStatus "@baseboard_fab2_lib.baseboard_fab2(sch_1):page32_i89:pe3_tx_dp(12)" )
			)
			( pin "U5D1.DC6"
				( objectStatus "@baseboard_fab2_lib.baseboard_fab2(sch_1):page32_i89:pe3_tx_dp(13)" )
			)
			( pin "U5D1.DA4"
				( objectStatus "@baseboard_fab2_lib.baseboard_fab2(sch_1):page32_i89:pe3_tx_dp(14)" )
			)
			( pin "U5D1.CV5"
				( objectStatus "@baseboard_fab2_lib.baseboard_fab2(sch_1):page32_i89:pe3_tx_dp(15)" )
			)
			( pin "U5D1.AC10"
				( objectStatus "@baseboard_fab2_lib.baseboard_fab2(sch_1):page33_i86:upi0_rx_dn(0)" )
			)
			( pin "U5D1.AA8"
				( objectStatus "@baseboard_fab2_lib.baseboard_fab2(sch_1):page33_i86:upi0_rx_dn(1)" )
			)
			( pin "U5D1.AB7"
				( objectStatus "@baseboard_fab2_lib.baseboard_fab2(sch_1):page33_i86:upi0_rx_dn(2)" )
			)
			( pin "U5D1.AD5"
				( objectStatus "@baseboard_fab2_lib.baseboard_fab2(sch_1):page33_i86:upi0_rx_dn(3)" )
			)
			( pin "U5D1.AE6"
				( objectStatus "@baseboard_fab2_lib.baseboard_fab2(sch_1):page33_i86:upi0_rx_dn(4)" )
			)
			( pin "U5D1.AG8"
				( objectStatus "@baseboard_fab2_lib.baseboard_fab2(sch_1):page33_i86:upi0_rx_dn(5)" )
			)
			( pin "U5D1.AJ6"
				( objectStatus "@baseboard_fab2_lib.baseboard_fab2(sch_1):page33_i86:upi0_rx_dn(6)" )
			)
			( pin "U5D1.AL6"
				( objectStatus "@baseboard_fab2_lib.baseboard_fab2(sch_1):page33_i86:upi0_rx_dn(7)" )
			)
			( pin "U5D1.AK7"
				( objectStatus "@baseboard_fab2_lib.baseboard_fab2(sch_1):page33_i86:upi0_rx_dn(8)" )
			)
			( pin "U5D1.AM9"
				( objectStatus "@baseboard_fab2_lib.baseboard_fab2(sch_1):page33_i86:upi0_rx_dn(9)" )
			)
			( pin "U5D1.AP7"
				( objectStatus "@baseboard_fab2_lib.baseboard_fab2(sch_1):page33_i86:upi0_rx_dn(10)" )
			)
			( pin "U5D1.AR8"
				( objectStatus "@baseboard_fab2_lib.baseboard_fab2(sch_1):page33_i86:upi0_rx_dn(11)" )
			)
			( pin "U5D1.AU10"
				( objectStatus "@baseboard_fab2_lib.baseboard_fab2(sch_1):page33_i86:upi0_rx_dn(12)" )
			)
			( pin "U5D1.BA8"
				( objectStatus "@baseboard_fab2_lib.baseboard_fab2(sch_1):page33_i86:upi0_rx_dn(13)" )
			)
			( pin "U5D1.BC6"
				( objectStatus "@baseboard_fab2_lib.baseboard_fab2(sch_1):page33_i86:upi0_rx_dn(14)" )
			)
			( pin "U5D1.BD7"
				( objectStatus "@baseboard_fab2_lib.baseboard_fab2(sch_1):page33_i86:upi0_rx_dn(15)" )
			)
			( pin "U5D1.AW8"
				( objectStatus "@baseboard_fab2_lib.baseboard_fab2(sch_1):page33_i86:upi0_rx_dn(16)" )
			)
			( pin "U5D1.AY9"
				( objectStatus "@baseboard_fab2_lib.baseboard_fab2(sch_1):page33_i86:upi0_rx_dn(17)" )
			)
			( pin "U5D1.BD9"
				( objectStatus "@baseboard_fab2_lib.baseboard_fab2(sch_1):page33_i86:upi0_rx_dn(18)" )
			)
			( pin "U5D1.BB11"
				( objectStatus "@baseboard_fab2_lib.baseboard_fab2(sch_1):page33_i86:upi0_rx_dn(19)" )
			)
			( pin "U5D1.AB9"
				( objectStatus "@baseboard_fab2_lib.baseboard_fab2(sch_1):page33_i86:upi0_rx_dp(0)" )
			)
			( pin "U5D1.AC8"
				( objectStatus "@baseboard_fab2_lib.baseboard_fab2(sch_1):page33_i86:upi0_rx_dp(1)" )
			)
			( pin "U5D1.AA6"
				( objectStatus "@baseboard_fab2_lib.baseboard_fab2(sch_1):page33_i86:upi0_rx_dp(2)" )
			)
			( pin "U5D1.AC6"
				( objectStatus "@baseboard_fab2_lib.baseboard_fab2(sch_1):page33_i86:upi0_rx_dp(3)" )
			)
			( pin "U5D1.AG6"
				( objectStatus "@baseboard_fab2_lib.baseboard_fab2(sch_1):page33_i86:upi0_rx_dp(4)" )
			)
			( pin "U5D1.AF7"
				( objectStatus "@baseboard_fab2_lib.baseboard_fab2(sch_1):page33_i86:upi0_rx_dp(5)" )
			)
			( pin "U5D1.AH7"
				( objectStatus "@baseboard_fab2_lib.baseboard_fab2(sch_1):page33_i86:upi0_rx_dp(6)" )
			)
			( pin "U5D1.AK5"
				( objectStatus "@baseboard_fab2_lib.baseboard_fab2(sch_1):page33_i86:upi0_rx_dp(7)" )
			)
			( pin "U5D1.AM7"
				( objectStatus "@baseboard_fab2_lib.baseboard_fab2(sch_1):page33_i86:upi0_rx_dp(8)" )
			)
			( pin "U5D1.AL8"
				( objectStatus "@baseboard_fab2_lib.baseboard_fab2(sch_1):page33_i86:upi0_rx_dp(9)" )
			)
			( pin "U5D1.AN8"
				( objectStatus "@baseboard_fab2_lib.baseboard_fab2(sch_1):page33_i86:upi0_rx_dp(10)" )
			)
			( pin "U5D1.AU8"
				( objectStatus "@baseboard_fab2_lib.baseboard_fab2(sch_1):page33_i86:upi0_rx_dp(11)" )
			)
			( pin "U5D1.AT9"
				( objectStatus "@baseboard_fab2_lib.baseboard_fab2(sch_1):page33_i86:upi0_rx_dp(12)" )
			)
			( pin "U5D1.AY7"
				( objectStatus "@baseboard_fab2_lib.baseboard_fab2(sch_1):page33_i86:upi0_rx_dp(13)" )
			)
			( pin "U5D1.BB7"
				( objectStatus "@baseboard_fab2_lib.baseboard_fab2(sch_1):page33_i86:upi0_rx_dp(14)" )
			)
			( pin "U5D1.BF7"
				( objectStatus "@baseboard_fab2_lib.baseboard_fab2(sch_1):page33_i86:upi0_rx_dp(15)" )
			)
			( pin "U5D1.AV9"
				( objectStatus "@baseboard_fab2_lib.baseboard_fab2(sch_1):page33_i86:upi0_rx_dp(16)" )
			)
			( pin "U5D1.BB9"
				( objectStatus "@baseboard_fab2_lib.baseboard_fab2(sch_1):page33_i86:upi0_rx_dp(17)" )
			)
			( pin "U5D1.BC10"
				( objectStatus "@baseboard_fab2_lib.baseboard_fab2(sch_1):page33_i86:upi0_rx_dp(18)" )
			)
			( pin "U5D1.BA10"
				( objectStatus "@baseboard_fab2_lib.baseboard_fab2(sch_1):page33_i86:upi0_rx_dp(19)" )
			)
			( pin "U5D1.N2"
				( objectStatus "@baseboard_fab2_lib.baseboard_fab2(sch_1):page33_i86:upi0_tx_dn(0)" )
			)
			( pin "U5D1.P1"
				( objectStatus "@baseboard_fab2_lib.baseboard_fab2(sch_1):page33_i86:upi0_tx_dn(1)" )
			)
			( pin "U5D1.V3"
				( objectStatus "@baseboard_fab2_lib.baseboard_fab2(sch_1):page33_i86:upi0_tx_dn(2)" )
			)
			( pin "U5D1.Y1"
				( objectStatus "@baseboard_fab2_lib.baseboard_fab2(sch_1):page33_i86:upi0_tx_dn(3)" )
			)
			( pin "U5D1.AB3"
				( objectStatus "@baseboard_fab2_lib.baseboard_fab2(sch_1):page33_i86:upi0_tx_dn(4)" )
			)
			( pin "U5D1.AC2"
				( objectStatus "@baseboard_fab2_lib.baseboard_fab2(sch_1):page33_i86:upi0_tx_dn(5)" )
			)
			( pin "U5D1.AG4"
				( objectStatus "@baseboard_fab2_lib.baseboard_fab2(sch_1):page33_i86:upi0_tx_dn(6)" )
			)
			( pin "U5D1.AE2"
				( objectStatus "@baseboard_fab2_lib.baseboard_fab2(sch_1):page33_i86:upi0_tx_dn(7)" )
			)
			( pin "U5D1.AH3"
				( objectStatus "@baseboard_fab2_lib.baseboard_fab2(sch_1):page33_i86:upi0_tx_dn(8)" )
			)
			( pin "U5D1.AL2"
				( objectStatus "@baseboard_fab2_lib.baseboard_fab2(sch_1):page33_i86:upi0_tx_dn(9)" )
			)
			( pin "U5D1.AM3"
				( objectStatus "@baseboard_fab2_lib.baseboard_fab2(sch_1):page33_i86:upi0_tx_dn(10)" )
			)
			( pin "U5D1.AN4"
				( objectStatus "@baseboard_fab2_lib.baseboard_fab2(sch_1):page33_i86:upi0_tx_dn(11)" )
			)
			( pin "U5D1.AT1"
				( objectStatus "@baseboard_fab2_lib.baseboard_fab2(sch_1):page33_i86:upi0_tx_dn(12)" )
			)
			( pin "U5D1.AT3"
				( objectStatus "@baseboard_fab2_lib.baseboard_fab2(sch_1):page33_i86:upi0_tx_dn(13)" )
			)
			( pin "U5D1.AU4"
				( objectStatus "@baseboard_fab2_lib.baseboard_fab2(sch_1):page33_i86:upi0_tx_dn(14)" )
			)
			( pin "U5D1.AV5"
				( objectStatus "@baseboard_fab2_lib.baseboard_fab2(sch_1):page33_i86:upi0_tx_dn(15)" )
			)
			( pin "U5D1.BA4"
				( objectStatus "@baseboard_fab2_lib.baseboard_fab2(sch_1):page33_i86:upi0_tx_dn(16)" )
			)
			( pin "U5D1.BB3"
				( objectStatus "@baseboard_fab2_lib.baseboard_fab2(sch_1):page33_i86:upi0_tx_dn(17)" )
			)
			( pin "U5D1.BF3"
				( objectStatus "@baseboard_fab2_lib.baseboard_fab2(sch_1):page33_i86:upi0_tx_dn(18)" )
			)
			( pin "U5D1.BG4"
				( objectStatus "@baseboard_fab2_lib.baseboard_fab2(sch_1):page33_i86:upi0_tx_dn(19)" )
			)
			( pin "U5D1.M1"
				( objectStatus "@baseboard_fab2_lib.baseboard_fab2(sch_1):page33_i86:upi0_tx_dp(0)" )
			)
			( pin "U5D1.T1"
				( objectStatus "@baseboard_fab2_lib.baseboard_fab2(sch_1):page33_i86:upi0_tx_dp(1)" )
			)
			( pin "U5D1.Y3"
				( objectStatus "@baseboard_fab2_lib.baseboard_fab2(sch_1):page33_i86:upi0_tx_dp(2)" )
			)
			( pin "U5D1.W2"
				( objectStatus "@baseboard_fab2_lib.baseboard_fab2(sch_1):page33_i86:upi0_tx_dp(3)" )
			)
			( pin "U5D1.AA2"
				( objectStatus "@baseboard_fab2_lib.baseboard_fab2(sch_1):page33_i86:upi0_tx_dp(4)" )
			)
			( pin "U5D1.AD1"
				( objectStatus "@baseboard_fab2_lib.baseboard_fab2(sch_1):page33_i86:upi0_tx_dp(5)" )
			)
			( pin "U5D1.AF3"
				( objectStatus "@baseboard_fab2_lib.baseboard_fab2(sch_1):page33_i86:upi0_tx_dp(6)" )
			)
			( pin "U5D1.AG2"
				( objectStatus "@baseboard_fab2_lib.baseboard_fab2(sch_1):page33_i86:upi0_tx_dp(7)" )
			)
			( pin "U5D1.AJ2"
				( objectStatus "@baseboard_fab2_lib.baseboard_fab2(sch_1):page33_i86:upi0_tx_dp(8)" )
			)
			( pin "U5D1.AK1"
				( objectStatus "@baseboard_fab2_lib.baseboard_fab2(sch_1):page33_i86:upi0_tx_dp(9)" )
			)
			( pin "U5D1.AK3"
				( objectStatus "@baseboard_fab2_lib.baseboard_fab2(sch_1):page33_i86:upi0_tx_dp(10)" )
			)
			( pin "U5D1.AP3"
				( objectStatus "@baseboard_fab2_lib.baseboard_fab2(sch_1):page33_i86:upi0_tx_dp(11)" )
			)
			( pin "U5D1.AP1"
				( objectStatus "@baseboard_fab2_lib.baseboard_fab2(sch_1):page33_i86:upi0_tx_dp(12)" )
			)
			( pin "U5D1.AR2"
				( objectStatus "@baseboard_fab2_lib.baseboard_fab2(sch_1):page33_i86:upi0_tx_dp(13)" )
			)
			( pin "U5D1.AR4"
				( objectStatus "@baseboard_fab2_lib.baseboard_fab2(sch_1):page33_i86:upi0_tx_dp(14)" )
			)
			( pin "U5D1.AW4"
				( objectStatus "@baseboard_fab2_lib.baseboard_fab2(sch_1):page33_i86:upi0_tx_dp(15)" )
			)
			( pin "U5D1.AY3"
				( objectStatus "@baseboard_fab2_lib.baseboard_fab2(sch_1):page33_i86:upi0_tx_dp(16)" )
			)
			( pin "U5D1.BC2"
				( objectStatus "@baseboard_fab2_lib.baseboard_fab2(sch_1):page33_i86:upi0_tx_dp(17)" )
			)
			( pin "U5D1.BD3"
				( objectStatus "@baseboard_fab2_lib.baseboard_fab2(sch_1):page33_i86:upi0_tx_dp(18)" )
			)
			( pin "U5D1.BH3"
				( objectStatus "@baseboard_fab2_lib.baseboard_fab2(sch_1):page33_i86:upi0_tx_dp(19)" )
			)
			( pin "U5D1.T5"
				( objectStatus "@baseboard_fab2_lib.baseboard_fab2(sch_1):page34_i86:upi1_rx_dn(0)" )
			)
			( pin "U5D1.P7"
				( objectStatus "@baseboard_fab2_lib.baseboard_fab2(sch_1):page34_i86:upi1_rx_dn(1)" )
			)
			( pin "U5D1.V7"
				( objectStatus "@baseboard_fab2_lib.baseboard_fab2(sch_1):page34_i86:upi1_rx_dn(2)" )
			)
			( pin "U5D1.T9"
				( objectStatus "@baseboard_fab2_lib.baseboard_fab2(sch_1):page34_i86:upi1_rx_dn(3)" )
			)
			( pin "U5D1.P9"
				( objectStatus "@baseboard_fab2_lib.baseboard_fab2(sch_1):page34_i86:upi1_rx_dn(4)" )
			)
			( pin "U5D1.R10"
				( objectStatus "@baseboard_fab2_lib.baseboard_fab2(sch_1):page34_i86:upi1_rx_dn(5)" )
			)
			( pin "U5D1.U12"
				( objectStatus "@baseboard_fab2_lib.baseboard_fab2(sch_1):page34_i86:upi1_rx_dn(6)" )
			)
			( pin "U5D1.L12"
				( objectStatus "@baseboard_fab2_lib.baseboard_fab2(sch_1):page34_i86:upi1_rx_dn(7)" )
			)
			( pin "U5D1.N14"
				( objectStatus "@baseboard_fab2_lib.baseboard_fab2(sch_1):page34_i86:upi1_rx_dn(8)" )
			)
			( pin "U5D1.R12"
				( objectStatus "@baseboard_fab2_lib.baseboard_fab2(sch_1):page34_i86:upi1_rx_dn(9)" )
			)
			( pin "U5D1.R16"
				( objectStatus "@baseboard_fab2_lib.baseboard_fab2(sch_1):page34_i86:upi1_rx_dn(10)" )
			)
			( pin "U5D1.P17"
				( objectStatus "@baseboard_fab2_lib.baseboard_fab2(sch_1):page34_i86:upi1_rx_dn(11)" )
			)
			( pin "U5D1.U16"
				( objectStatus "@baseboard_fab2_lib.baseboard_fab2(sch_1):page34_i86:upi1_rx_dn(12)" )
			)
			( pin "U5D1.W18"
				( objectStatus "@baseboard_fab2_lib.baseboard_fab2(sch_1):page34_i86:upi1_rx_dn(13)" )
			)
			( pin "U5D1.R20"
				( objectStatus "@baseboard_fab2_lib.baseboard_fab2(sch_1):page34_i86:upi1_rx_dn(14)" )
			)
			( pin "U5D1.U18"
				( objectStatus "@baseboard_fab2_lib.baseboard_fab2(sch_1):page34_i86:upi1_rx_dn(15)" )
			)
			( pin "U5D1.P21"
				( objectStatus "@baseboard_fab2_lib.baseboard_fab2(sch_1):page34_i86:upi1_rx_dn(16)" )
			)
			( pin "U5D1.V19"
				( objectStatus "@baseboard_fab2_lib.baseboard_fab2(sch_1):page34_i86:upi1_rx_dn(17)" )
			)
			( pin "U5D1.Y21"
				( objectStatus "@baseboard_fab2_lib.baseboard_fab2(sch_1):page34_i86:upi1_rx_dn(18)" )
			)
			( pin "U5D1.AB19"
				( objectStatus "@baseboard_fab2_lib.baseboard_fab2(sch_1):page34_i86:upi1_rx_dn(19)" )
			)
			( pin "U5D1.R6"
				( objectStatus "@baseboard_fab2_lib.baseboard_fab2(sch_1):page34_i86:upi1_rx_dp(0)" )
			)
			( pin "U5D1.T7"
				( objectStatus "@baseboard_fab2_lib.baseboard_fab2(sch_1):page34_i86:upi1_rx_dp(1)" )
			)
			( pin "U5D1.U8"
				( objectStatus "@baseboard_fab2_lib.baseboard_fab2(sch_1):page34_i86:upi1_rx_dp(2)" )
			)
			( pin "U5D1.R8"
				( objectStatus "@baseboard_fab2_lib.baseboard_fab2(sch_1):page34_i86:upi1_rx_dp(3)" )
			)
			( pin "U5D1.N10"
				( objectStatus "@baseboard_fab2_lib.baseboard_fab2(sch_1):page34_i86:upi1_rx_dp(4)" )
			)
			( pin "U5D1.U10"
				( objectStatus "@baseboard_fab2_lib.baseboard_fab2(sch_1):page34_i86:upi1_rx_dp(5)" )
			)
			( pin "U5D1.T11"
				( objectStatus "@baseboard_fab2_lib.baseboard_fab2(sch_1):page34_i86:upi1_rx_dp(6)" )
			)
			( pin "U5D1.N12"
				( objectStatus "@baseboard_fab2_lib.baseboard_fab2(sch_1):page34_i86:upi1_rx_dp(7)" )
			)
			( pin "U5D1.M13"
				( objectStatus "@baseboard_fab2_lib.baseboard_fab2(sch_1):page34_i86:upi1_rx_dp(8)" )
			)
			( pin "U5D1.P13"
				( objectStatus "@baseboard_fab2_lib.baseboard_fab2(sch_1):page34_i86:upi1_rx_dp(9)" )
			)
			( pin "U5D1.T15"
				( objectStatus "@baseboard_fab2_lib.baseboard_fab2(sch_1):page34_i86:upi1_rx_dp(10)" )
			)
			( pin "U5D1.N16"
				( objectStatus "@baseboard_fab2_lib.baseboard_fab2(sch_1):page34_i86:upi1_rx_dp(11)" )
			)
			( pin "U5D1.W16"
				( objectStatus "@baseboard_fab2_lib.baseboard_fab2(sch_1):page34_i86:upi1_rx_dp(12)" )
			)
			( pin "U5D1.V17"
				( objectStatus "@baseboard_fab2_lib.baseboard_fab2(sch_1):page34_i86:upi1_rx_dp(13)" )
			)
			( pin "U5D1.P19"
				( objectStatus "@baseboard_fab2_lib.baseboard_fab2(sch_1):page34_i86:upi1_rx_dp(14)" )
			)
			( pin "U5D1.T19"
				( objectStatus "@baseboard_fab2_lib.baseboard_fab2(sch_1):page34_i86:upi1_rx_dp(15)" )
			)
			( pin "U5D1.T21"
				( objectStatus "@baseboard_fab2_lib.baseboard_fab2(sch_1):page34_i86:upi1_rx_dp(16)" )
			)
			( pin "U5D1.Y19"
				( objectStatus "@baseboard_fab2_lib.baseboard_fab2(sch_1):page34_i86:upi1_rx_dp(17)" )
			)
			( pin "U5D1.W20"
				( objectStatus "@baseboard_fab2_lib.baseboard_fab2(sch_1):page34_i86:upi1_rx_dp(18)" )
			)
			( pin "U5D1.AA20"
				( objectStatus "@baseboard_fab2_lib.baseboard_fab2(sch_1):page34_i86:upi1_rx_dp(19)" )
			)
			( pin "U5D1.M3"
				( objectStatus "@baseboard_fab2_lib.baseboard_fab2(sch_1):page34_i86:upi1_tx_dn(0)" )
			)
			( pin "U5D1.L4"
				( objectStatus "@baseboard_fab2_lib.baseboard_fab2(sch_1):page34_i86:upi1_tx_dn(1)" )
			)
			( pin "U5D1.K5"
				( objectStatus "@baseboard_fab2_lib.baseboard_fab2(sch_1):page34_i86:upi1_tx_dn(2)" )
			)
			( pin "U5D1.J6"
				( objectStatus "@baseboard_fab2_lib.baseboard_fab2(sch_1):page34_i86:upi1_tx_dn(3)" )
			)
			( pin "U5D1.G6"
				( objectStatus "@baseboard_fab2_lib.baseboard_fab2(sch_1):page34_i86:upi1_tx_dn(4)" )
			)
			( pin "U5D1.H7"
				( objectStatus "@baseboard_fab2_lib.baseboard_fab2(sch_1):page34_i86:upi1_tx_dn(5)" )
			)
			( pin "U5D1.K9"
				( objectStatus "@baseboard_fab2_lib.baseboard_fab2(sch_1):page34_i86:upi1_tx_dn(6)" )
			)
			( pin "U5D1.D9"
				( objectStatus "@baseboard_fab2_lib.baseboard_fab2(sch_1):page34_i86:upi1_tx_dn(7)" )
			)
			( pin "U5D1.F11"
				( objectStatus "@baseboard_fab2_lib.baseboard_fab2(sch_1):page34_i86:upi1_tx_dn(8)" )
			)
			( pin "U5D1.G10"
				( objectStatus "@baseboard_fab2_lib.baseboard_fab2(sch_1):page34_i86:upi1_tx_dn(9)" )
			)
			( pin "U5D1.E12"
				( objectStatus "@baseboard_fab2_lib.baseboard_fab2(sch_1):page34_i86:upi1_tx_dn(10)" )
			)
			( pin "U5D1.G14"
				( objectStatus "@baseboard_fab2_lib.baseboard_fab2(sch_1):page34_i86:upi1_tx_dn(11)" )
			)
			( pin "U5D1.D15"
				( objectStatus "@baseboard_fab2_lib.baseboard_fab2(sch_1):page34_i86:upi1_tx_dn(12)" )
			)
			( pin "U5D1.F15"
				( objectStatus "@baseboard_fab2_lib.baseboard_fab2(sch_1):page34_i86:upi1_tx_dn(13)" )
			)
			( pin "U5D1.H17"
				( objectStatus "@baseboard_fab2_lib.baseboard_fab2(sch_1):page34_i86:upi1_tx_dn(14)" )
			)
			( pin "U5D1.K19"
				( objectStatus "@baseboard_fab2_lib.baseboard_fab2(sch_1):page34_i86:upi1_tx_dn(15)" )
			)
			( pin "U5D1.G18"
				( objectStatus "@baseboard_fab2_lib.baseboard_fab2(sch_1):page34_i86:upi1_tx_dn(16)" )
			)
			( pin "U5D1.J20"
				( objectStatus "@baseboard_fab2_lib.baseboard_fab2(sch_1):page34_i86:upi1_tx_dn(17)" )
			)
			( pin "U5D1.F21"
				( objectStatus "@baseboard_fab2_lib.baseboard_fab2(sch_1):page34_i86:upi1_tx_dn(18)" )
			)
			( pin "U5D1.H21"
				( objectStatus "@baseboard_fab2_lib.baseboard_fab2(sch_1):page34_i86:upi1_tx_dn(19)" )
			)
			( pin "U5D1.P3"
				( objectStatus "@baseboard_fab2_lib.baseboard_fab2(sch_1):page34_i86:upi1_tx_dp(0)" )
			)
			( pin "U5D1.K3"
				( objectStatus "@baseboard_fab2_lib.baseboard_fab2(sch_1):page34_i86:upi1_tx_dp(1)" )
			)
			( pin "U5D1.M5"
				( objectStatus "@baseboard_fab2_lib.baseboard_fab2(sch_1):page34_i86:upi1_tx_dp(2)" )
			)
			( pin "U5D1.H5"
				( objectStatus "@baseboard_fab2_lib.baseboard_fab2(sch_1):page34_i86:upi1_tx_dp(3)" )
			)
			( pin "U5D1.F7"
				( objectStatus "@baseboard_fab2_lib.baseboard_fab2(sch_1):page34_i86:upi1_tx_dp(4)" )
			)
			( pin "U5D1.K7"
				( objectStatus "@baseboard_fab2_lib.baseboard_fab2(sch_1):page34_i86:upi1_tx_dp(5)" )
			)
			( pin "U5D1.J8"
				( objectStatus "@baseboard_fab2_lib.baseboard_fab2(sch_1):page34_i86:upi1_tx_dp(6)" )
			)
			( pin "U5D1.F9"
				( objectStatus "@baseboard_fab2_lib.baseboard_fab2(sch_1):page34_i86:upi1_tx_dp(7)" )
			)
			( pin "U5D1.E10"
				( objectStatus "@baseboard_fab2_lib.baseboard_fab2(sch_1):page34_i86:upi1_tx_dp(8)" )
			)
			( pin "U5D1.H9"
				( objectStatus "@baseboard_fab2_lib.baseboard_fab2(sch_1):page34_i86:upi1_tx_dp(9)" )
			)
			( pin "U5D1.G12"
				( objectStatus "@baseboard_fab2_lib.baseboard_fab2(sch_1):page34_i86:upi1_tx_dp(10)" )
			)
			( pin "U5D1.F13"
				( objectStatus "@baseboard_fab2_lib.baseboard_fab2(sch_1):page34_i86:upi1_tx_dp(11)" )
			)
			( pin "U5D1.E14"
				( objectStatus "@baseboard_fab2_lib.baseboard_fab2(sch_1):page34_i86:upi1_tx_dp(12)" )
			)
			( pin "U5D1.H15"
				( objectStatus "@baseboard_fab2_lib.baseboard_fab2(sch_1):page34_i86:upi1_tx_dp(13)" )
			)
			( pin "U5D1.G16"
				( objectStatus "@baseboard_fab2_lib.baseboard_fab2(sch_1):page34_i86:upi1_tx_dp(14)" )
			)
			( pin "U5D1.L18"
				( objectStatus "@baseboard_fab2_lib.baseboard_fab2(sch_1):page34_i86:upi1_tx_dp(15)" )
			)
			( pin "U5D1.J18"
				( objectStatus "@baseboard_fab2_lib.baseboard_fab2(sch_1):page34_i86:upi1_tx_dp(16)" )
			)
			( pin "U5D1.H19"
				( objectStatus "@baseboard_fab2_lib.baseboard_fab2(sch_1):page34_i86:upi1_tx_dp(17)" )
			)
			( pin "U5D1.G20"
				( objectStatus "@baseboard_fab2_lib.baseboard_fab2(sch_1):page34_i86:upi1_tx_dp(18)" )
			)
			( pin "U5D1.K21"
				( objectStatus "@baseboard_fab2_lib.baseboard_fab2(sch_1):page34_i86:upi1_tx_dp(19)" )
			)
			( pin "U5D1.DF23"
				( objectStatus "@baseboard_fab2_lib.baseboard_fab2(sch_1):page35_i3:upi2_rx_dn(0)" )
			)
			( pin "U5D1.DE22"
				( objectStatus "@baseboard_fab2_lib.baseboard_fab2(sch_1):page35_i3:upi2_rx_dn(1)" )
			)
			( pin "U5D1.DC22"
				( objectStatus "@baseboard_fab2_lib.baseboard_fab2(sch_1):page35_i3:upi2_rx_dn(2)" )
			)
			( pin "U5D1.DB21"
				( objectStatus "@baseboard_fab2_lib.baseboard_fab2(sch_1):page35_i3:upi2_rx_dn(3)" )
			)
			( pin "U5D1.DD19"
				( objectStatus "@baseboard_fab2_lib.baseboard_fab2(sch_1):page35_i3:upi2_rx_dn(4)" )
			)
			( pin "U5D1.DA20"
				( objectStatus "@baseboard_fab2_lib.baseboard_fab2(sch_1):page35_i3:upi2_rx_dn(5)" )
			)
			( pin "U5D1.CW20"
				( objectStatus "@baseboard_fab2_lib.baseboard_fab2(sch_1):page35_i3:upi2_rx_dn(6)" )
			)
			( pin "U5D1.CV19"
				( objectStatus "@baseboard_fab2_lib.baseboard_fab2(sch_1):page35_i3:upi2_rx_dn(7)" )
			)
			( pin "U5D1.CT21"
				( objectStatus "@baseboard_fab2_lib.baseboard_fab2(sch_1):page35_i3:upi2_rx_dn(8)" )
			)
			( pin "U5D1.CR18"
				( objectStatus "@baseboard_fab2_lib.baseboard_fab2(sch_1):page35_i3:upi2_rx_dn(9)" )
			)
			( pin "U5D1.CN20"
				( objectStatus "@baseboard_fab2_lib.baseboard_fab2(sch_1):page35_i3:upi2_rx_dn(10)" )
			)
			( pin "U5D1.CP21"
				( objectStatus "@baseboard_fab2_lib.baseboard_fab2(sch_1):page35_i3:upi2_rx_dn(11)" )
			)
			( pin "U5D1.CL16"
				( objectStatus "@baseboard_fab2_lib.baseboard_fab2(sch_1):page35_i3:upi2_rx_dn(12)" )
			)
			( pin "U5D1.CJ18"
				( objectStatus "@baseboard_fab2_lib.baseboard_fab2(sch_1):page35_i3:upi2_rx_dn(13)" )
			)
			( pin "U5D1.CH17"
				( objectStatus "@baseboard_fab2_lib.baseboard_fab2(sch_1):page35_i3:upi2_rx_dn(14)" )
			)
			( pin "U5D1.CE16"
				( objectStatus "@baseboard_fab2_lib.baseboard_fab2(sch_1):page35_i3:upi2_rx_dn(15)" )
			)
			( pin "U5D1.CD15"
				( objectStatus "@baseboard_fab2_lib.baseboard_fab2(sch_1):page35_i3:upi2_rx_dn(16)" )
			)
			( pin "U5D1.CF17"
				( objectStatus "@baseboard_fab2_lib.baseboard_fab2(sch_1):page35_i3:upi2_rx_dn(17)" )
			)
			( pin "U5D1.CB15"
				( objectStatus "@baseboard_fab2_lib.baseboard_fab2(sch_1):page35_i3:upi2_rx_dn(18)" )
			)
			( pin "U5D1.BY17"
				( objectStatus "@baseboard_fab2_lib.baseboard_fab2(sch_1):page35_i3:upi2_rx_dn(19)" )
			)
			( pin "U5D1.DG22"
				( objectStatus "@baseboard_fab2_lib.baseboard_fab2(sch_1):page35_i3:upi2_rx_dp(0)" )
			)
			( pin "U5D1.DD21"
				( objectStatus "@baseboard_fab2_lib.baseboard_fab2(sch_1):page35_i3:upi2_rx_dp(1)" )
			)
			( pin "U5D1.DA22"
				( objectStatus "@baseboard_fab2_lib.baseboard_fab2(sch_1):page35_i3:upi2_rx_dp(2)" )
			)
			( pin "U5D1.DC20"
				( objectStatus "@baseboard_fab2_lib.baseboard_fab2(sch_1):page35_i3:upi2_rx_dp(3)" )
			)
			( pin "U5D1.DB19"
				( objectStatus "@baseboard_fab2_lib.baseboard_fab2(sch_1):page35_i3:upi2_rx_dp(4)" )
			)
			( pin "U5D1.CY19"
				( objectStatus "@baseboard_fab2_lib.baseboard_fab2(sch_1):page35_i3:upi2_rx_dp(5)" )
			)
			( pin "U5D1.CU20"
				( objectStatus "@baseboard_fab2_lib.baseboard_fab2(sch_1):page35_i3:upi2_rx_dp(6)" )
			)
			( pin "U5D1.CW18"
				( objectStatus "@baseboard_fab2_lib.baseboard_fab2(sch_1):page35_i3:upi2_rx_dp(7)" )
			)
			( pin "U5D1.CR20"
				( objectStatus "@baseboard_fab2_lib.baseboard_fab2(sch_1):page35_i3:upi2_rx_dp(8)" )
			)
			( pin "U5D1.CN18"
				( objectStatus "@baseboard_fab2_lib.baseboard_fab2(sch_1):page35_i3:upi2_rx_dp(9)" )
			)
			( pin "U5D1.CP19"
				( objectStatus "@baseboard_fab2_lib.baseboard_fab2(sch_1):page35_i3:upi2_rx_dp(10)" )
			)
			( pin "U5D1.CM21"
				( objectStatus "@baseboard_fab2_lib.baseboard_fab2(sch_1):page35_i3:upi2_rx_dp(11)" )
			)
			( pin "U5D1.CJ16"
				( objectStatus "@baseboard_fab2_lib.baseboard_fab2(sch_1):page35_i3:upi2_rx_dp(12)" )
			)
			( pin "U5D1.CK17"
				( objectStatus "@baseboard_fab2_lib.baseboard_fab2(sch_1):page35_i3:upi2_rx_dp(13)" )
			)
			( pin "U5D1.CG16"
				( objectStatus "@baseboard_fab2_lib.baseboard_fab2(sch_1):page35_i3:upi2_rx_dp(14)" )
			)
			( pin "U5D1.CF15"
				( objectStatus "@baseboard_fab2_lib.baseboard_fab2(sch_1):page35_i3:upi2_rx_dp(15)" )
			)
			( pin "U5D1.CC14"
				( objectStatus "@baseboard_fab2_lib.baseboard_fab2(sch_1):page35_i3:upi2_rx_dp(16)" )
			)
			( pin "U5D1.CD17"
				( objectStatus "@baseboard_fab2_lib.baseboard_fab2(sch_1):page35_i3:upi2_rx_dp(17)" )
			)
			( pin "U5D1.BY15"
				( objectStatus "@baseboard_fab2_lib.baseboard_fab2(sch_1):page35_i3:upi2_rx_dp(18)" )
			)
			( pin "U5D1.CA16"
				( objectStatus "@baseboard_fab2_lib.baseboard_fab2(sch_1):page35_i3:upi2_rx_dp(19)" )
			)
			( pin "U5D1.DT21"
				( objectStatus "@baseboard_fab2_lib.baseboard_fab2(sch_1):page35_i3:upi2_tx_dn(0)" )
			)
			( pin "U5D1.DM21"
				( objectStatus "@baseboard_fab2_lib.baseboard_fab2(sch_1):page35_i3:upi2_tx_dn(1)" )
			)
			( pin "U5D1.DL20"
				( objectStatus "@baseboard_fab2_lib.baseboard_fab2(sch_1):page35_i3:upi2_tx_dn(2)" )
			)
			( pin "U5D1.DG20"
				( objectStatus "@baseboard_fab2_lib.baseboard_fab2(sch_1):page35_i3:upi2_tx_dn(3)" )
			)
			( pin "U5D1.DH19"
				( objectStatus "@baseboard_fab2_lib.baseboard_fab2(sch_1):page35_i3:upi2_tx_dn(4)" )
			)
			( pin "U5D1.DK17"
				( objectStatus "@baseboard_fab2_lib.baseboard_fab2(sch_1):page35_i3:upi2_tx_dn(5)" )
			)
			( pin "U5D1.DG18"
				( objectStatus "@baseboard_fab2_lib.baseboard_fab2(sch_1):page35_i3:upi2_tx_dn(6)" )
			)
			( pin "U5D1.DD17"
				( objectStatus "@baseboard_fab2_lib.baseboard_fab2(sch_1):page35_i3:upi2_tx_dn(7)" )
			)
			( pin "U5D1.DF15"
				( objectStatus "@baseboard_fab2_lib.baseboard_fab2(sch_1):page35_i3:upi2_tx_dn(8)" )
			)
			( pin "U5D1.DC16"
				( objectStatus "@baseboard_fab2_lib.baseboard_fab2(sch_1):page35_i3:upi2_tx_dn(9)" )
			)
			( pin "U5D1.DA16"
				( objectStatus "@baseboard_fab2_lib.baseboard_fab2(sch_1):page35_i3:upi2_tx_dn(10)" )
			)
			( pin "U5D1.CW14"
				( objectStatus "@baseboard_fab2_lib.baseboard_fab2(sch_1):page35_i3:upi2_tx_dn(11)" )
			)
			( pin "U5D1.CU14"
				( objectStatus "@baseboard_fab2_lib.baseboard_fab2(sch_1):page35_i3:upi2_tx_dn(12)" )
			)
			( pin "U5D1.CM13"
				( objectStatus "@baseboard_fab2_lib.baseboard_fab2(sch_1):page35_i3:upi2_tx_dn(13)" )
			)
			( pin "U5D1.CJ14"
				( objectStatus "@baseboard_fab2_lib.baseboard_fab2(sch_1):page35_i3:upi2_tx_dn(14)" )
			)
			( pin "U5D1.CF13"
				( objectStatus "@baseboard_fab2_lib.baseboard_fab2(sch_1):page35_i3:upi2_tx_dn(15)" )
			)
			( pin "U5D1.CH11"
				( objectStatus "@baseboard_fab2_lib.baseboard_fab2(sch_1):page35_i3:upi2_tx_dn(16)" )
			)
			( pin "U5D1.CE12"
				( objectStatus "@baseboard_fab2_lib.baseboard_fab2(sch_1):page35_i3:upi2_tx_dn(17)" )
			)
			( pin "U5D1.CC10"
				( objectStatus "@baseboard_fab2_lib.baseboard_fab2(sch_1):page35_i3:upi2_tx_dn(18)" )
			)
			( pin "U5D1.CC12"
				( objectStatus "@baseboard_fab2_lib.baseboard_fab2(sch_1):page35_i3:upi2_tx_dn(19)" )
			)
			( pin "U5D1.DP21"
				( objectStatus "@baseboard_fab2_lib.baseboard_fab2(sch_1):page35_i3:upi2_tx_dp(0)" )
			)
			( pin "U5D1.DN20"
				( objectStatus "@baseboard_fab2_lib.baseboard_fab2(sch_1):page35_i3:upi2_tx_dp(1)" )
			)
			( pin "U5D1.DK19"
				( objectStatus "@baseboard_fab2_lib.baseboard_fab2(sch_1):page35_i3:upi2_tx_dp(2)" )
			)
			( pin "U5D1.DJ20"
				( objectStatus "@baseboard_fab2_lib.baseboard_fab2(sch_1):page35_i3:upi2_tx_dp(3)" )
			)
			( pin "U5D1.DJ18"
				( objectStatus "@baseboard_fab2_lib.baseboard_fab2(sch_1):page35_i3:upi2_tx_dp(4)" )
			)
			( pin "U5D1.DH17"
				( objectStatus "@baseboard_fab2_lib.baseboard_fab2(sch_1):page35_i3:upi2_tx_dp(5)" )
			)
			( pin "U5D1.DF17"
				( objectStatus "@baseboard_fab2_lib.baseboard_fab2(sch_1):page35_i3:upi2_tx_dp(6)" )
			)
			( pin "U5D1.DE16"
				( objectStatus "@baseboard_fab2_lib.baseboard_fab2(sch_1):page35_i3:upi2_tx_dp(7)" )
			)
			( pin "U5D1.DD15"
				( objectStatus "@baseboard_fab2_lib.baseboard_fab2(sch_1):page35_i3:upi2_tx_dp(8)" )
			)
			( pin "U5D1.DB15"
				( objectStatus "@baseboard_fab2_lib.baseboard_fab2(sch_1):page35_i3:upi2_tx_dp(9)" )
			)
			( pin "U5D1.CW16"
				( objectStatus "@baseboard_fab2_lib.baseboard_fab2(sch_1):page35_i3:upi2_tx_dp(10)" )
			)
			( pin "U5D1.CV13"
				( objectStatus "@baseboard_fab2_lib.baseboard_fab2(sch_1):page35_i3:upi2_tx_dp(11)" )
			)
			( pin "U5D1.CR14"
				( objectStatus "@baseboard_fab2_lib.baseboard_fab2(sch_1):page35_i3:upi2_tx_dp(12)" )
			)
			( pin "U5D1.CK13"
				( objectStatus "@baseboard_fab2_lib.baseboard_fab2(sch_1):page35_i3:upi2_tx_dp(13)" )
			)
			( pin "U5D1.CH13"
				( objectStatus "@baseboard_fab2_lib.baseboard_fab2(sch_1):page35_i3:upi2_tx_dp(14)" )
			)
			( pin "U5D1.CG12"
				( objectStatus "@baseboard_fab2_lib.baseboard_fab2(sch_1):page35_i3:upi2_tx_dp(15)" )
			)
			( pin "U5D1.CF11"
				( objectStatus "@baseboard_fab2_lib.baseboard_fab2(sch_1):page35_i3:upi2_tx_dp(16)" )
			)
			( pin "U5D1.CD11"
				( objectStatus "@baseboard_fab2_lib.baseboard_fab2(sch_1):page35_i3:upi2_tx_dp(17)" )
			)
			( pin "U5D1.CB11"
				( objectStatus "@baseboard_fab2_lib.baseboard_fab2(sch_1):page35_i3:upi2_tx_dp(18)" )
			)
			( pin "U5D1.CA12"
				( objectStatus "@baseboard_fab2_lib.baseboard_fab2(sch_1):page35_i3:upi2_tx_dp(19)" )
			)
			( pin "U5D1.CH23"
				( objectStatus "@baseboard_fab2_lib.baseboard_fab2(sch_1):page36_i15:rsvd(92)" )
			)
			( pin "U5D1.CH21"
				( objectStatus "@baseboard_fab2_lib.baseboard_fab2(sch_1):page36_i15:rsvd(93)" )
			)
			( pin "U5D1.CG82"
				( objectStatus "@baseboard_fab2_lib.baseboard_fab2(sch_1):page36_i15:rsvd(94)" )
			)
			( pin "U5D1.CG78"
				( objectStatus "@baseboard_fab2_lib.baseboard_fab2(sch_1):page36_i15:rsvd(95)" )
			)
			( pin "U5D1.CG26"
				( objectStatus "@baseboard_fab2_lib.baseboard_fab2(sch_1):page36_i15:rsvd(96)" )
			)
			( pin "U5D1.CG24"
				( objectStatus "@baseboard_fab2_lib.baseboard_fab2(sch_1):page36_i15:rsvd(97)" )
			)
			( pin "U5D1.CG20"
				( objectStatus "@baseboard_fab2_lib.baseboard_fab2(sch_1):page36_i15:rsvd(98)" )
			)
			( pin "U5D1.CG10"
				( objectStatus "@baseboard_fab2_lib.baseboard_fab2(sch_1):page36_i15:rsvd(99)" )
			)
			( pin "U5D1.CF81"
				( objectStatus "@baseboard_fab2_lib.baseboard_fab2(sch_1):page36_i15:rsvd(100)" )
			)
			( pin "U5D1.CF79"
				( objectStatus "@baseboard_fab2_lib.baseboard_fab2(sch_1):page36_i15:rsvd(101)" )
			)
			( pin "U5D1.CF23"
				( objectStatus "@baseboard_fab2_lib.baseboard_fab2(sch_1):page36_i15:rsvd(102)" )
			)
			( pin "U5D1.CF21"
				( objectStatus "@baseboard_fab2_lib.baseboard_fab2(sch_1):page36_i15:rsvd(103)" )
			)
			( pin "U5D1.CF19"
				( objectStatus "@baseboard_fab2_lib.baseboard_fab2(sch_1):page36_i15:rsvd(104)" )
			)
			( pin "U5D1.CE80"
				( objectStatus "@baseboard_fab2_lib.baseboard_fab2(sch_1):page36_i15:rsvd(105)" )
			)
			( pin "U5D1.CE78"
				( objectStatus "@baseboard_fab2_lib.baseboard_fab2(sch_1):page36_i15:rsvd(106)" )
			)
			( pin "U5D1.CE22"
				( objectStatus "@baseboard_fab2_lib.baseboard_fab2(sch_1):page36_i15:rsvd(107)" )
			)
			( pin "U5D1.CD25"
				( objectStatus "@baseboard_fab2_lib.baseboard_fab2(sch_1):page36_i15:rsvd(108)" )
			)
			( pin "U5D1.CD21"
				( objectStatus "@baseboard_fab2_lib.baseboard_fab2(sch_1):page36_i15:rsvd(109)" )
			)
			( pin "U5D1.CD19"
				( objectStatus "@baseboard_fab2_lib.baseboard_fab2(sch_1):page36_i15:rsvd(110)" )
			)
			( pin "U5D1.CC6"
				( objectStatus "@baseboard_fab2_lib.baseboard_fab2(sch_1):page36_i15:rsvd(111)" )
			)
			( pin "U5D1.CC20"
				( objectStatus "@baseboard_fab2_lib.baseboard_fab2(sch_1):page36_i15:rsvd(112)" )
			)
			( pin "U5D1.CB5"
				( objectStatus "@baseboard_fab2_lib.baseboard_fab2(sch_1):page36_i15:rsvd(113)" )
			)
			( pin "U5D1.CB25"
				( objectStatus "@baseboard_fab2_lib.baseboard_fab2(sch_1):page36_i15:rsvd(114)" )
			)
			( pin "U5D1.CB21"
				( objectStatus "@baseboard_fab2_lib.baseboard_fab2(sch_1):page36_i15:rsvd(115)" )
			)
			( pin "U5D1.CB19"
				( objectStatus "@baseboard_fab2_lib.baseboard_fab2(sch_1):page36_i15:rsvd(116)" )
			)
			( pin "U5D1.CA24"
				( objectStatus "@baseboard_fab2_lib.baseboard_fab2(sch_1):page36_i15:rsvd(117)" )
			)
			( pin "U5D1.CA22"
				( objectStatus "@baseboard_fab2_lib.baseboard_fab2(sch_1):page36_i15:rsvd(118)" )
			)
			( pin "U5D1.BY25"
				( objectStatus "@baseboard_fab2_lib.baseboard_fab2(sch_1):page36_i15:rsvd(119)" )
			)
			( pin "U5D1.BY19"
				( objectStatus "@baseboard_fab2_lib.baseboard_fab2(sch_1):page36_i15:rsvd(120)" )
			)
			( pin "U5D1.BW22"
				( objectStatus "@baseboard_fab2_lib.baseboard_fab2(sch_1):page36_i15:rsvd(121)" )
			)
			( pin "U5D1.BW20"
				( objectStatus "@baseboard_fab2_lib.baseboard_fab2(sch_1):page36_i15:rsvd(122)" )
			)
			( pin "U5D1.BW10"
				( objectStatus "@baseboard_fab2_lib.baseboard_fab2(sch_1):page36_i15:rsvd(123)" )
			)
			( pin "U5D1.BV23"
				( objectStatus "@baseboard_fab2_lib.baseboard_fab2(sch_1):page36_i15:rsvd(124)" )
			)
			( pin "U5D1.BV21"
				( objectStatus "@baseboard_fab2_lib.baseboard_fab2(sch_1):page36_i15:rsvd(125)" )
			)
			( pin "U5D1.BV19"
				( objectStatus "@baseboard_fab2_lib.baseboard_fab2(sch_1):page36_i15:rsvd(126)" )
			)
			( pin "U5D1.BU22"
				( objectStatus "@baseboard_fab2_lib.baseboard_fab2(sch_1):page36_i15:rsvd(127)" )
			)
			( pin "U5D1.BU20"
				( objectStatus "@baseboard_fab2_lib.baseboard_fab2(sch_1):page36_i15:rsvd(128)" )
			)
			( pin "U5D1.BU18"
				( objectStatus "@baseboard_fab2_lib.baseboard_fab2(sch_1):page36_i15:rsvd(129)" )
			)
			( pin "U5D1.BR24"
				( objectStatus "@baseboard_fab2_lib.baseboard_fab2(sch_1):page36_i15:rsvd(130)" )
			)
			( pin "U5D1.BR22"
				( objectStatus "@baseboard_fab2_lib.baseboard_fab2(sch_1):page36_i15:rsvd(131)" )
			)
			( pin "U5D1.BP21"
				( objectStatus "@baseboard_fab2_lib.baseboard_fab2(sch_1):page36_i15:rsvd(132)" )
			)
			( pin "U5D1.BP17"
				( objectStatus "@baseboard_fab2_lib.baseboard_fab2(sch_1):page36_i15:rsvd(133)" )
			)
			( pin "U5D1.BN18"
				( objectStatus "@baseboard_fab2_lib.baseboard_fab2(sch_1):page36_i15:rsvd(134)" )
			)
			( pin "U5D1.BM19"
				( objectStatus "@baseboard_fab2_lib.baseboard_fab2(sch_1):page36_i15:rsvd(135)" )
			)
			( pin "U5D1.BM17"
				( objectStatus "@baseboard_fab2_lib.baseboard_fab2(sch_1):page36_i15:rsvd(136)" )
			)
			( pin "U5D1.BL20"
				( objectStatus "@baseboard_fab2_lib.baseboard_fab2(sch_1):page36_i15:rsvd(137)" )
			)
			( pin "U5D1.BL18"
				( objectStatus "@baseboard_fab2_lib.baseboard_fab2(sch_1):page36_i15:rsvd(138)" )
			)
			( pin "U5D1.BK17"
				( objectStatus "@baseboard_fab2_lib.baseboard_fab2(sch_1):page36_i15:rsvd(139)" )
			)
			( pin "U5D1.BJ20"
				( objectStatus "@baseboard_fab2_lib.baseboard_fab2(sch_1):page36_i15:rsvd(140)" )
			)
			( pin "U5D1.BJ18"
				( objectStatus "@baseboard_fab2_lib.baseboard_fab2(sch_1):page36_i15:rsvd(141)" )
			)
			( pin "U5D1.BJ16"
				( objectStatus "@baseboard_fab2_lib.baseboard_fab2(sch_1):page36_i15:rsvd(142)" )
			)
			( pin "U5D1.BH19"
				( objectStatus "@baseboard_fab2_lib.baseboard_fab2(sch_1):page36_i15:rsvd(143)" )
			)
			( pin "U5D1.BG20"
				( objectStatus "@baseboard_fab2_lib.baseboard_fab2(sch_1):page36_i15:rsvd(144)" )
			)
			( pin "U5D1.BG18"
				( objectStatus "@baseboard_fab2_lib.baseboard_fab2(sch_1):page36_i15:rsvd(145)" )
			)
			( pin "U5D1.BF21"
				( objectStatus "@baseboard_fab2_lib.baseboard_fab2(sch_1):page36_i15:rsvd(146)" )
			)
			( pin "U5D1.BE22"
				( objectStatus "@baseboard_fab2_lib.baseboard_fab2(sch_1):page36_i15:rsvd(147)" )
			)
			( pin "U5D1.BE20"
				( objectStatus "@baseboard_fab2_lib.baseboard_fab2(sch_1):page36_i15:rsvd(148)" )
			)
			( pin "U5D1.BE18"
				( objectStatus "@baseboard_fab2_lib.baseboard_fab2(sch_1):page36_i15:rsvd(149)" )
			)
			( pin "U5D1.BD69"
				( objectStatus "@baseboard_fab2_lib.baseboard_fab2(sch_1):page36_i15:rsvd(150)" )
			)
			( pin "U5D1.BD67"
				( objectStatus "@baseboard_fab2_lib.baseboard_fab2(sch_1):page36_i15:rsvd(151)" )
			)
			( pin "U5D1.BD65"
				( objectStatus "@baseboard_fab2_lib.baseboard_fab2(sch_1):page36_i15:rsvd(152)" )
			)
			( pin "U5D1.BD25"
				( objectStatus "@baseboard_fab2_lib.baseboard_fab2(sch_1):page36_i15:rsvd(153)" )
			)
			( pin "U5D1.BD19"
				( objectStatus "@baseboard_fab2_lib.baseboard_fab2(sch_1):page36_i15:rsvd(154)" )
			)
			( pin "U5D1.BD17"
				( objectStatus "@baseboard_fab2_lib.baseboard_fab2(sch_1):page36_i15:rsvd(155)" )
			)
			( pin "U5D1.BC68"
				( objectStatus "@baseboard_fab2_lib.baseboard_fab2(sch_1):page36_i15:rsvd(156)" )
			)
			( pin "U5D1.BC66"
				( objectStatus "@baseboard_fab2_lib.baseboard_fab2(sch_1):page36_i15:rsvd(157)" )
			)
			( pin "U5D1.BC64"
				( objectStatus "@baseboard_fab2_lib.baseboard_fab2(sch_1):page36_i15:rsvd(158)" )
			)
			( pin "U5D1.BC22"
				( objectStatus "@baseboard_fab2_lib.baseboard_fab2(sch_1):page36_i15:rsvd(159)" )
			)
			( pin "U5D1.BC20"
				( objectStatus "@baseboard_fab2_lib.baseboard_fab2(sch_1):page36_i15:rsvd(160)" )
			)
			( pin "U5D1.BC18"
				( objectStatus "@baseboard_fab2_lib.baseboard_fab2(sch_1):page36_i15:rsvd(161)" )
			)
			( pin "U5D1.BC14"
				( objectStatus "@baseboard_fab2_lib.baseboard_fab2(sch_1):page36_i15:rsvd(162)" )
			)
			( pin "U5D1.BB67"
				( objectStatus "@baseboard_fab2_lib.baseboard_fab2(sch_1):page36_i15:rsvd(163)" )
			)
			( pin "U5D1.BB65"
				( objectStatus "@baseboard_fab2_lib.baseboard_fab2(sch_1):page36_i15:rsvd(164)" )
			)
			( pin "U5D1.BB25"
				( objectStatus "@baseboard_fab2_lib.baseboard_fab2(sch_1):page36_i15:rsvd(165)" )
			)
			( pin "U5D1.BB21"
				( objectStatus "@baseboard_fab2_lib.baseboard_fab2(sch_1):page36_i15:rsvd(166)" )
			)
			( pin "U5D1.BB17"
				( objectStatus "@baseboard_fab2_lib.baseboard_fab2(sch_1):page36_i15:rsvd(167)" )
			)
			( pin "U5D1.BB15"
				( objectStatus "@baseboard_fab2_lib.baseboard_fab2(sch_1):page36_i15:rsvd(168)" )
			)
			( pin "U5D1.BB13"
				( objectStatus "@baseboard_fab2_lib.baseboard_fab2(sch_1):page36_i15:rsvd(169)" )
			)
			( pin "U5D1.BA82"
				( objectStatus "@baseboard_fab2_lib.baseboard_fab2(sch_1):page36_i15:rsvd(170)" )
			)
			( pin "U5D1.BA78"
				( objectStatus "@baseboard_fab2_lib.baseboard_fab2(sch_1):page36_i15:rsvd(171)" )
			)
			( pin "U5D1.AY83"
				( objectStatus "@baseboard_fab2_lib.baseboard_fab2(sch_1):page36_i15:rsvd(255)" )
			)
			( pin "U5D1.CL24"
				( objectStatus "@baseboard_fab2_lib.baseboard_fab2(sch_1):page36_i16:rsvd(81)" )
			)
			( pin "U5D1.CK77"
				( objectStatus "@baseboard_fab2_lib.baseboard_fab2(sch_1):page36_i16:rsvd(82)" )
			)
			( pin "U5D1.CK25"
				( objectStatus "@baseboard_fab2_lib.baseboard_fab2(sch_1):page36_i16:rsvd(83)" )
			)
			( pin "U5D1.CK23"
				( objectStatus "@baseboard_fab2_lib.baseboard_fab2(sch_1):page36_i16:rsvd(84)" )
			)
			( pin "U5D1.CK19"
				( objectStatus "@baseboard_fab2_lib.baseboard_fab2(sch_1):page36_i16:rsvd(85)" )
			)
			( pin "U5D1.CJ26"
				( objectStatus "@baseboard_fab2_lib.baseboard_fab2(sch_1):page36_i16:rsvd(86)" )
			)
			( pin "U5D1.CJ24"
				( objectStatus "@baseboard_fab2_lib.baseboard_fab2(sch_1):page36_i16:rsvd(87)" )
			)
			( pin "U5D1.CJ22"
				( objectStatus "@baseboard_fab2_lib.baseboard_fab2(sch_1):page36_i16:rsvd(88)" )
			)
			( pin "U5D1.CJ20"
				( objectStatus "@baseboard_fab2_lib.baseboard_fab2(sch_1):page36_i16:rsvd(89)" )
			)
			( pin "U5D1.CH77"
				( objectStatus "@baseboard_fab2_lib.baseboard_fab2(sch_1):page36_i16:rsvd(90)" )
			)
			( pin "U5D1.CH25"
				( objectStatus "@baseboard_fab2_lib.baseboard_fab2(sch_1):page36_i16:rsvd(91)" )
			)
			( pin "U5D1.AR16"
				( objectStatus "@baseboard_fab2_lib.baseboard_fab2(sch_1):page36_i16:test_6" )
			)
			( pin "U5D1.AU18"
				( objectStatus "@baseboard_fab2_lib.baseboard_fab2(sch_1):page36_i16:test_7" )
			)
			( pin "U5D1.AW16"
				( objectStatus "@baseboard_fab2_lib.baseboard_fab2(sch_1):page36_i16:test_8" )
			)
			( pin "U5D1.AW20"
				( objectStatus "@baseboard_fab2_lib.baseboard_fab2(sch_1):page36_i16:test_9" )
			)
			( pin "U5D1.AW22"
				( objectStatus "@baseboard_fab2_lib.baseboard_fab2(sch_1):page36_i16:test_10" )
			)
			( pin "R5D5.1"
				( objectStatus "@baseboard_fab2_lib.baseboard_fab2(sch_1):page37_i303:a" )
			)
			( pin "R5D5.2"
				( objectStatus "@baseboard_fab2_lib.baseboard_fab2(sch_1):page37_i303:b" )
			)
			( pin "R5P1.1"
				( objectStatus "@baseboard_fab2_lib.baseboard_fab2(sch_1):page37_i309:a" )
			)
			( pin "R5P1.2"
				( objectStatus "@baseboard_fab2_lib.baseboard_fab2(sch_1):page37_i309:b" )
			)
			( pin "U5D1.BN78"
				( objectStatus "@baseboard_fab2_lib.baseboard_fab2(sch_1):page37_i310:vccin(130)" )
			)
			( pin "U5D1.BN76"
				( objectStatus "@baseboard_fab2_lib.baseboard_fab2(sch_1):page37_i310:vccin(131)" )
			)
			( pin "U5D1.BN74"
				( objectStatus "@baseboard_fab2_lib.baseboard_fab2(sch_1):page37_i310:vccin(132)" )
			)
			( pin "U5D1.BN72"
				( objectStatus "@baseboard_fab2_lib.baseboard_fab2(sch_1):page37_i310:vccin(133)" )
			)
			( pin "U5D1.BN70"
				( objectStatus "@baseboard_fab2_lib.baseboard_fab2(sch_1):page37_i310:vccin(134)" )
			)
			( pin "U5D1.BN68"
				( objectStatus "@baseboard_fab2_lib.baseboard_fab2(sch_1):page37_i310:vccin(135)" )
			)
			( pin "U5D1.BN66"
				( objectStatus "@baseboard_fab2_lib.baseboard_fab2(sch_1):page37_i310:vccin(136)" )
			)
			( pin "U5D1.BN64"
				( objectStatus "@baseboard_fab2_lib.baseboard_fab2(sch_1):page37_i310:vccin(137)" )
			)
			( pin "U5D1.BN62"
				( objectStatus "@baseboard_fab2_lib.baseboard_fab2(sch_1):page37_i310:vccin(138)" )
			)
			( pin "U5D1.BN60"
				( objectStatus "@baseboard_fab2_lib.baseboard_fab2(sch_1):page37_i310:vccin(139)" )
			)
			( pin "U5D1.BM83"
				( objectStatus "@baseboard_fab2_lib.baseboard_fab2(sch_1):page37_i310:vccin(140)" )
			)
			( pin "U5D1.BM81"
				( objectStatus "@baseboard_fab2_lib.baseboard_fab2(sch_1):page37_i310:vccin(141)" )
			)
			( pin "U5D1.BM79"
				( objectStatus "@baseboard_fab2_lib.baseboard_fab2(sch_1):page37_i310:vccin(142)" )
			)
			( pin "U5D1.BM77"
				( objectStatus "@baseboard_fab2_lib.baseboard_fab2(sch_1):page37_i310:vccin(143)" )
			)
			( pin "U5D1.BM75"
				( objectStatus "@baseboard_fab2_lib.baseboard_fab2(sch_1):page37_i310:vccin(144)" )
			)
			( pin "U5D1.BM73"
				( objectStatus "@baseboard_fab2_lib.baseboard_fab2(sch_1):page37_i310:vccin(145)" )
			)
			( pin "U5D1.BM71"
				( objectStatus "@baseboard_fab2_lib.baseboard_fab2(sch_1):page37_i310:vccin(146)" )
			)
			( pin "U5D1.BM69"
				( objectStatus "@baseboard_fab2_lib.baseboard_fab2(sch_1):page37_i310:vccin(147)" )
			)
			( pin "U5D1.BM67"
				( objectStatus "@baseboard_fab2_lib.baseboard_fab2(sch_1):page37_i310:vccin(148)" )
			)
			( pin "U5D1.BM65"
				( objectStatus "@baseboard_fab2_lib.baseboard_fab2(sch_1):page37_i310:vccin(149)" )
			)
			( pin "U5D1.BM63"
				( objectStatus "@baseboard_fab2_lib.baseboard_fab2(sch_1):page37_i310:vccin(150)" )
			)
			( pin "U5D1.BM61"
				( objectStatus "@baseboard_fab2_lib.baseboard_fab2(sch_1):page37_i310:vccin(151)" )
			)
			( pin "U5D1.BL84"
				( objectStatus "@baseboard_fab2_lib.baseboard_fab2(sch_1):page37_i310:vccin(152)" )
			)
			( pin "U5D1.BL62"
				( objectStatus "@baseboard_fab2_lib.baseboard_fab2(sch_1):page37_i310:vccin(153)" )
			)
			( pin "U5D1.BL60"
				( objectStatus "@baseboard_fab2_lib.baseboard_fab2(sch_1):page37_i310:vccin(154)" )
			)
			( pin "U5D1.BK83"
				( objectStatus "@baseboard_fab2_lib.baseboard_fab2(sch_1):page37_i310:vccin(155)" )
			)
			( pin "U5D1.BK81"
				( objectStatus "@baseboard_fab2_lib.baseboard_fab2(sch_1):page37_i310:vccin(156)" )
			)
			( pin "U5D1.BK79"
				( objectStatus "@baseboard_fab2_lib.baseboard_fab2(sch_1):page37_i310:vccin(157)" )
			)
			( pin "U5D1.BK77"
				( objectStatus "@baseboard_fab2_lib.baseboard_fab2(sch_1):page37_i310:vccin(158)" )
			)
			( pin "U5D1.BK75"
				( objectStatus "@baseboard_fab2_lib.baseboard_fab2(sch_1):page37_i310:vccin(159)" )
			)
			( pin "U5D1.BK73"
				( objectStatus "@baseboard_fab2_lib.baseboard_fab2(sch_1):page37_i310:vccin(160)" )
			)
			( pin "U5D1.BK71"
				( objectStatus "@baseboard_fab2_lib.baseboard_fab2(sch_1):page37_i310:vccin(161)" )
			)
			( pin "U5D1.BK69"
				( objectStatus "@baseboard_fab2_lib.baseboard_fab2(sch_1):page37_i310:vccin(162)" )
			)
			( pin "U5D1.BK67"
				( objectStatus "@baseboard_fab2_lib.baseboard_fab2(sch_1):page37_i310:vccin(163)" )
			)
			( pin "U5D1.BK65"
				( objectStatus "@baseboard_fab2_lib.baseboard_fab2(sch_1):page37_i310:vccin(164)" )
			)
			( pin "U5D1.BK63"
				( objectStatus "@baseboard_fab2_lib.baseboard_fab2(sch_1):page37_i310:vccin(165)" )
			)
			( pin "U5D1.BK61"
				( objectStatus "@baseboard_fab2_lib.baseboard_fab2(sch_1):page37_i310:vccin(166)" )
			)
			( pin "U5D1.BJ84"
				( objectStatus "@baseboard_fab2_lib.baseboard_fab2(sch_1):page37_i310:vccin(167)" )
			)
			( pin "U5D1.BJ82"
				( objectStatus "@baseboard_fab2_lib.baseboard_fab2(sch_1):page37_i310:vccin(168)" )
			)
			( pin "U5D1.BJ80"
				( objectStatus "@baseboard_fab2_lib.baseboard_fab2(sch_1):page37_i310:vccin(169)" )
			)
			( pin "U5D1.BJ78"
				( objectStatus "@baseboard_fab2_lib.baseboard_fab2(sch_1):page37_i310:vccin(170)" )
			)
			( pin "U5D1.BJ76"
				( objectStatus "@baseboard_fab2_lib.baseboard_fab2(sch_1):page37_i310:vccin(171)" )
			)
			( pin "U5D1.BJ74"
				( objectStatus "@baseboard_fab2_lib.baseboard_fab2(sch_1):page37_i310:vccin(172)" )
			)
			( pin "U5D1.BJ72"
				( objectStatus "@baseboard_fab2_lib.baseboard_fab2(sch_1):page37_i310:vccin(173)" )
			)
			( pin "U5D1.BJ70"
				( objectStatus "@baseboard_fab2_lib.baseboard_fab2(sch_1):page37_i310:vccin(174)" )
			)
			( pin "U5D1.BJ68"
				( objectStatus "@baseboard_fab2_lib.baseboard_fab2(sch_1):page37_i310:vccin(175)" )
			)
			( pin "U5D1.BJ66"
				( objectStatus "@baseboard_fab2_lib.baseboard_fab2(sch_1):page37_i310:vccin(176)" )
			)
			( pin "U5D1.BJ64"
				( objectStatus "@baseboard_fab2_lib.baseboard_fab2(sch_1):page37_i310:vccin(177)" )
			)
			( pin "U5D1.BJ62"
				( objectStatus "@baseboard_fab2_lib.baseboard_fab2(sch_1):page37_i310:vccin(178)" )
			)
			( pin "U5D1.BJ60"
				( objectStatus "@baseboard_fab2_lib.baseboard_fab2(sch_1):page37_i310:vccin(179)" )
			)
			( pin "U5D1.BH83"
				( objectStatus "@baseboard_fab2_lib.baseboard_fab2(sch_1):page37_i310:vccin(180)" )
			)
			( pin "U5D1.BH81"
				( objectStatus "@baseboard_fab2_lib.baseboard_fab2(sch_1):page37_i310:vccin(181)" )
			)
			( pin "U5D1.BH79"
				( objectStatus "@baseboard_fab2_lib.baseboard_fab2(sch_1):page37_i310:vccin(182)" )
			)
			( pin "U5D1.BH77"
				( objectStatus "@baseboard_fab2_lib.baseboard_fab2(sch_1):page37_i310:vccin(183)" )
			)
			( pin "U5D1.BH75"
				( objectStatus "@baseboard_fab2_lib.baseboard_fab2(sch_1):page37_i310:vccin(184)" )
			)
			( pin "U5D1.BH73"
				( objectStatus "@baseboard_fab2_lib.baseboard_fab2(sch_1):page37_i310:vccin(185)" )
			)
			( pin "U5D1.BH71"
				( objectStatus "@baseboard_fab2_lib.baseboard_fab2(sch_1):page37_i310:vccin(186)" )
			)
			( pin "U5D1.BH69"
				( objectStatus "@baseboard_fab2_lib.baseboard_fab2(sch_1):page37_i310:vccin(187)" )
			)
			( pin "U5D1.BH67"
				( objectStatus "@baseboard_fab2_lib.baseboard_fab2(sch_1):page37_i310:vccin(188)" )
			)
			( pin "U5D1.BH65"
				( objectStatus "@baseboard_fab2_lib.baseboard_fab2(sch_1):page37_i310:vccin(189)" )
			)
			( pin "U5D1.BH63"
				( objectStatus "@baseboard_fab2_lib.baseboard_fab2(sch_1):page37_i310:vccin(190)" )
			)
			( pin "U5D1.BH61"
				( objectStatus "@baseboard_fab2_lib.baseboard_fab2(sch_1):page37_i310:vccin(191)" )
			)
			( pin "U5D1.BG84"
				( objectStatus "@baseboard_fab2_lib.baseboard_fab2(sch_1):page37_i310:vccin(192)" )
			)
			( pin "U5D1.BG70"
				( objectStatus "@baseboard_fab2_lib.baseboard_fab2(sch_1):page37_i310:vccin(193)" )
			)
			( pin "U5D1.BG68"
				( objectStatus "@baseboard_fab2_lib.baseboard_fab2(sch_1):page37_i310:vccin(194)" )
			)
			( pin "U5D1.BG66"
				( objectStatus "@baseboard_fab2_lib.baseboard_fab2(sch_1):page37_i310:vccin(195)" )
			)
			( pin "U5D1.BG64"
				( objectStatus "@baseboard_fab2_lib.baseboard_fab2(sch_1):page37_i310:vccin(196)" )
			)
			( pin "U5D1.BG62"
				( objectStatus "@baseboard_fab2_lib.baseboard_fab2(sch_1):page37_i310:vccin(197)" )
			)
			( pin "U5D1.BG60"
				( objectStatus "@baseboard_fab2_lib.baseboard_fab2(sch_1):page37_i310:vccin(198)" )
			)
			( pin "U5D1.BF85"
				( objectStatus "@baseboard_fab2_lib.baseboard_fab2(sch_1):page37_i310:vccin(199)" )
			)
			( pin "U5D1.BF83"
				( objectStatus "@baseboard_fab2_lib.baseboard_fab2(sch_1):page37_i310:vccin(200)" )
			)
			( pin "U5D1.BF81"
				( objectStatus "@baseboard_fab2_lib.baseboard_fab2(sch_1):page37_i310:vccin(201)" )
			)
			( pin "U5D1.BF79"
				( objectStatus "@baseboard_fab2_lib.baseboard_fab2(sch_1):page37_i310:vccin(202)" )
			)
			( pin "U5D1.BF77"
				( objectStatus "@baseboard_fab2_lib.baseboard_fab2(sch_1):page37_i310:vccin(203)" )
			)
			( pin "U5D1.BF75"
				( objectStatus "@baseboard_fab2_lib.baseboard_fab2(sch_1):page37_i310:vccin(204)" )
			)
			( pin "U5D1.BF73"
				( objectStatus "@baseboard_fab2_lib.baseboard_fab2(sch_1):page37_i310:vccin(205)" )
			)
			( pin "U5D1.BF61"
				( objectStatus "@baseboard_fab2_lib.baseboard_fab2(sch_1):page37_i310:vccin(206)" )
			)
			( pin "U5D1.BE84"
				( objectStatus "@baseboard_fab2_lib.baseboard_fab2(sch_1):page37_i310:vccin(207)" )
			)
			( pin "U5D1.BE82"
				( objectStatus "@baseboard_fab2_lib.baseboard_fab2(sch_1):page37_i310:vccin(208)" )
			)
			( pin "U5D1.BE80"
				( objectStatus "@baseboard_fab2_lib.baseboard_fab2(sch_1):page37_i310:vccin(209)" )
			)
			( pin "U5D1.BE78"
				( objectStatus "@baseboard_fab2_lib.baseboard_fab2(sch_1):page37_i310:vccin(210)" )
			)
			( pin "U5D1.BE76"
				( objectStatus "@baseboard_fab2_lib.baseboard_fab2(sch_1):page37_i310:vccin(211)" )
			)
			( pin "U5D1.BE74"
				( objectStatus "@baseboard_fab2_lib.baseboard_fab2(sch_1):page37_i310:vccin(212)" )
			)
			( pin "U5D1.BE72"
				( objectStatus "@baseboard_fab2_lib.baseboard_fab2(sch_1):page37_i310:vccin(213)" )
			)
			( pin "U5D1.BE62"
				( objectStatus "@baseboard_fab2_lib.baseboard_fab2(sch_1):page37_i310:vccin(214)" )
			)
			( pin "U5D1.BE60"
				( objectStatus "@baseboard_fab2_lib.baseboard_fab2(sch_1):page37_i310:vccin(215)" )
			)
			( pin "U5D1.BD85"
				( objectStatus "@baseboard_fab2_lib.baseboard_fab2(sch_1):page37_i310:vccin(216)" )
			)
			( pin "U5D1.BD83"
				( objectStatus "@baseboard_fab2_lib.baseboard_fab2(sch_1):page37_i310:vccin(217)" )
			)
			( pin "U5D1.BD81"
				( objectStatus "@baseboard_fab2_lib.baseboard_fab2(sch_1):page37_i310:vccin(218)" )
			)
			( pin "U5D1.BD79"
				( objectStatus "@baseboard_fab2_lib.baseboard_fab2(sch_1):page37_i310:vccin(219)" )
			)
			( pin "U5D1.BD77"
				( objectStatus "@baseboard_fab2_lib.baseboard_fab2(sch_1):page37_i310:vccin(220)" )
			)
			( pin "U5D1.BD75"
				( objectStatus "@baseboard_fab2_lib.baseboard_fab2(sch_1):page37_i310:vccin(221)" )
			)
			( pin "U5D1.BD73"
				( objectStatus "@baseboard_fab2_lib.baseboard_fab2(sch_1):page37_i310:vccin(222)" )
			)
			( pin "U5D1.BD61"
				( objectStatus "@baseboard_fab2_lib.baseboard_fab2(sch_1):page37_i310:vccin(223)" )
			)
			( pin "U5D1.BC84"
				( objectStatus "@baseboard_fab2_lib.baseboard_fab2(sch_1):page37_i310:vccin(224)" )
			)
			( pin "U5D1.BC62"
				( objectStatus "@baseboard_fab2_lib.baseboard_fab2(sch_1):page37_i310:vccin(225)" )
			)
			( pin "U5D1.BC60"
				( objectStatus "@baseboard_fab2_lib.baseboard_fab2(sch_1):page37_i310:vccin(226)" )
			)
			( pin "U5D1.BB85"
				( objectStatus "@baseboard_fab2_lib.baseboard_fab2(sch_1):page37_i310:vccin(227)" )
			)
			( pin "U5D1.BB61"
				( objectStatus "@baseboard_fab2_lib.baseboard_fab2(sch_1):page37_i310:vccin(228)" )
			)
			( pin "U5D1.BA60"
				( objectStatus "@baseboard_fab2_lib.baseboard_fab2(sch_1):page37_i310:vccin(229)" )
			)
			( pin "U5D1.AY61"
				( objectStatus "@baseboard_fab2_lib.baseboard_fab2(sch_1):page37_i310:vccin(230)" )
			)
			( pin "U5D1.AW60"
				( objectStatus "@baseboard_fab2_lib.baseboard_fab2(sch_1):page37_i310:vccin(231)" )
			)
			( pin "U5D1.AV61"
				( objectStatus "@baseboard_fab2_lib.baseboard_fab2(sch_1):page37_i310:vccin(232)" )
			)
			( pin "U5D1.AV59"
				( objectStatus "@baseboard_fab2_lib.baseboard_fab2(sch_1):page37_i310:vccin(233)" )
			)
			( pin "U5D1.AU60"
				( objectStatus "@baseboard_fab2_lib.baseboard_fab2(sch_1):page37_i310:vccin(234)" )
			)
			( pin "U5D1.AU58"
				( objectStatus "@baseboard_fab2_lib.baseboard_fab2(sch_1):page37_i310:vccin(235)" )
			)
			( pin "U5D1.AT59"
				( objectStatus "@baseboard_fab2_lib.baseboard_fab2(sch_1):page37_i310:vccin(236)" )
			)
			( pin "U5D1.AT57"
				( objectStatus "@baseboard_fab2_lib.baseboard_fab2(sch_1):page37_i310:vccin(237)" )
			)
			( pin "U5D1.AR58"
				( objectStatus "@baseboard_fab2_lib.baseboard_fab2(sch_1):page37_i310:vccin(238)" )
			)
			( pin "U5D1.AR56"
				( objectStatus "@baseboard_fab2_lib.baseboard_fab2(sch_1):page37_i310:vccin(239)" )
			)
			( pin "U5D1.AP57"
				( objectStatus "@baseboard_fab2_lib.baseboard_fab2(sch_1):page37_i310:vccin(240)" )
			)
			( pin "U5D1.AP55"
				( objectStatus "@baseboard_fab2_lib.baseboard_fab2(sch_1):page37_i310:vccin(241)" )
			)
			( pin "U5D1.AN56"
				( objectStatus "@baseboard_fab2_lib.baseboard_fab2(sch_1):page37_i310:vccin(242)" )
			)
			( pin "U5D1.AN54"
				( objectStatus "@baseboard_fab2_lib.baseboard_fab2(sch_1):page37_i310:vccin(243)" )
			)
			( pin "U5D1.AN32"
				( objectStatus "@baseboard_fab2_lib.baseboard_fab2(sch_1):page37_i310:vccin(244)" )
			)
			( pin "U5D1.AM55"
				( objectStatus "@baseboard_fab2_lib.baseboard_fab2(sch_1):page37_i310:vccin(245)" )
			)
			( pin "U5D1.AM53"
				( objectStatus "@baseboard_fab2_lib.baseboard_fab2(sch_1):page37_i310:vccin(246)" )
			)
			( pin "U5D1.AM33"
				( objectStatus "@baseboard_fab2_lib.baseboard_fab2(sch_1):page37_i310:vccin(247)" )
			)
			( pin "U5D1.AL54"
				( objectStatus "@baseboard_fab2_lib.baseboard_fab2(sch_1):page37_i310:vccin(248)" )
			)
			( pin "U5D1.AL52"
				( objectStatus "@baseboard_fab2_lib.baseboard_fab2(sch_1):page37_i310:vccin(249)" )
			)
			( pin "U5D1.AL50"
				( objectStatus "@baseboard_fab2_lib.baseboard_fab2(sch_1):page37_i310:vccin(250)" )
			)
			( pin "U5D1.AL48"
				( objectStatus "@baseboard_fab2_lib.baseboard_fab2(sch_1):page37_i310:vccin(251)" )
			)
			( pin "U5D1.AL46"
				( objectStatus "@baseboard_fab2_lib.baseboard_fab2(sch_1):page37_i310:vccin(252)" )
			)
			( pin "U5D1.AL34"
				( objectStatus "@baseboard_fab2_lib.baseboard_fab2(sch_1):page37_i310:vccin(253)" )
			)
			( pin "U5D1.AK53"
				( objectStatus "@baseboard_fab2_lib.baseboard_fab2(sch_1):page37_i310:vccin(254)" )
			)
			( pin "U5D1.AK51"
				( objectStatus "@baseboard_fab2_lib.baseboard_fab2(sch_1):page37_i310:vccin(255)" )
			)
			( pin "U5D1.AK49"
				( objectStatus "@baseboard_fab2_lib.baseboard_fab2(sch_1):page37_i310:vccin(256)" )
			)
			( pin "U5D1.AK47"
				( objectStatus "@baseboard_fab2_lib.baseboard_fab2(sch_1):page37_i310:vccin(257)" )
			)
			( pin "U5D1.AK45"
				( objectStatus "@baseboard_fab2_lib.baseboard_fab2(sch_1):page37_i310:vccin(258)" )
			)
			( pin "U5D1.AK35"
				( objectStatus "@baseboard_fab2_lib.baseboard_fab2(sch_1):page37_i310:vccin(259)" )
			)
			( pin "U5D1.AJ36"
				( objectStatus "@baseboard_fab2_lib.baseboard_fab2(sch_1):page37_i310:vccin(260)" )
			)
			( pin "U5D1.AH41"
				( objectStatus "@baseboard_fab2_lib.baseboard_fab2(sch_1):page37_i310:vccin(261)" )
			)
			( pin "U5D1.AH39"
				( objectStatus "@baseboard_fab2_lib.baseboard_fab2(sch_1):page37_i310:vccin(262)" )
			)
			( pin "U5D1.AH37"
				( objectStatus "@baseboard_fab2_lib.baseboard_fab2(sch_1):page37_i310:vccin(263)" )
			)
			( pin "U5D1.AG42"
				( objectStatus "@baseboard_fab2_lib.baseboard_fab2(sch_1):page37_i310:vccin(264)" )
			)
			( pin "U5D1.AG40"
				( objectStatus "@baseboard_fab2_lib.baseboard_fab2(sch_1):page37_i310:vccin(265)" )
			)
			( pin "U5D1.AG38"
				( objectStatus "@baseboard_fab2_lib.baseboard_fab2(sch_1):page37_i310:vccin(266)" )
			)
			( pin "U5D1.AF43"
				( objectStatus "@baseboard_fab2_lib.baseboard_fab2(sch_1):page37_i310:vccin(267)" )
			)
			( pin "U5D1.CY49"
				( objectStatus "@baseboard_fab2_lib.baseboard_fab2(sch_1):page37_i311:vccin(0)" )
			)
			( pin "U5D1.CY47"
				( objectStatus "@baseboard_fab2_lib.baseboard_fab2(sch_1):page37_i311:vccin(1)" )
			)
			( pin "U5D1.CW50"
				( objectStatus "@baseboard_fab2_lib.baseboard_fab2(sch_1):page37_i311:vccin(2)" )
			)
			( pin "U5D1.CW48"
				( objectStatus "@baseboard_fab2_lib.baseboard_fab2(sch_1):page37_i311:vccin(3)" )
			)
			( pin "U5D1.CW46"
				( objectStatus "@baseboard_fab2_lib.baseboard_fab2(sch_1):page37_i311:vccin(4)" )
			)
			( pin "U5D1.CV51"
				( objectStatus "@baseboard_fab2_lib.baseboard_fab2(sch_1):page37_i311:vccin(5)" )
			)
			( pin "U5D1.CU54"
				( objectStatus "@baseboard_fab2_lib.baseboard_fab2(sch_1):page37_i311:vccin(6)" )
			)
			( pin "U5D1.CU52"
				( objectStatus "@baseboard_fab2_lib.baseboard_fab2(sch_1):page37_i311:vccin(7)" )
			)
			( pin "U5D1.CU42"
				( objectStatus "@baseboard_fab2_lib.baseboard_fab2(sch_1):page37_i311:vccin(8)" )
			)
			( pin "U5D1.CU40"
				( objectStatus "@baseboard_fab2_lib.baseboard_fab2(sch_1):page37_i311:vccin(9)" )
			)
			( pin "U5D1.CU38"
				( objectStatus "@baseboard_fab2_lib.baseboard_fab2(sch_1):page37_i311:vccin(10)" )
			)
			( pin "U5D1.CT55"
				( objectStatus "@baseboard_fab2_lib.baseboard_fab2(sch_1):page37_i311:vccin(11)" )
			)
			( pin "U5D1.CT53"
				( objectStatus "@baseboard_fab2_lib.baseboard_fab2(sch_1):page37_i311:vccin(12)" )
			)
			( pin "U5D1.CT41"
				( objectStatus "@baseboard_fab2_lib.baseboard_fab2(sch_1):page37_i311:vccin(13)" )
			)
			( pin "U5D1.CT39"
				( objectStatus "@baseboard_fab2_lib.baseboard_fab2(sch_1):page37_i311:vccin(14)" )
			)
			( pin "U5D1.CT37"
				( objectStatus "@baseboard_fab2_lib.baseboard_fab2(sch_1):page37_i311:vccin(15)" )
			)
			( pin "U5D1.CR56"
				( objectStatus "@baseboard_fab2_lib.baseboard_fab2(sch_1):page37_i311:vccin(16)" )
			)
			( pin "U5D1.CR54"
				( objectStatus "@baseboard_fab2_lib.baseboard_fab2(sch_1):page37_i311:vccin(17)" )
			)
			( pin "U5D1.CR34"
				( objectStatus "@baseboard_fab2_lib.baseboard_fab2(sch_1):page37_i311:vccin(18)" )
			)
			( pin "U5D1.CP57"
				( objectStatus "@baseboard_fab2_lib.baseboard_fab2(sch_1):page37_i311:vccin(19)" )
			)
			( pin "U5D1.CP55"
				( objectStatus "@baseboard_fab2_lib.baseboard_fab2(sch_1):page37_i311:vccin(20)" )
			)
			( pin "U5D1.CP33"
				( objectStatus "@baseboard_fab2_lib.baseboard_fab2(sch_1):page37_i311:vccin(21)" )
			)
			( pin "U5D1.CN58"
				( objectStatus "@baseboard_fab2_lib.baseboard_fab2(sch_1):page37_i311:vccin(22)" )
			)
			( pin "U5D1.CN56"
				( objectStatus "@baseboard_fab2_lib.baseboard_fab2(sch_1):page37_i311:vccin(23)" )
			)
			( pin "U5D1.CM59"
				( objectStatus "@baseboard_fab2_lib.baseboard_fab2(sch_1):page37_i311:vccin(24)" )
			)
			( pin "U5D1.CM57"
				( objectStatus "@baseboard_fab2_lib.baseboard_fab2(sch_1):page37_i311:vccin(25)" )
			)
			( pin "U5D1.CL60"
				( objectStatus "@baseboard_fab2_lib.baseboard_fab2(sch_1):page37_i311:vccin(26)" )
			)
			( pin "U5D1.CL58"
				( objectStatus "@baseboard_fab2_lib.baseboard_fab2(sch_1):page37_i311:vccin(27)" )
			)
			( pin "U5D1.CK61"
				( objectStatus "@baseboard_fab2_lib.baseboard_fab2(sch_1):page37_i311:vccin(28)" )
			)
			( pin "U5D1.CK59"
				( objectStatus "@baseboard_fab2_lib.baseboard_fab2(sch_1):page37_i311:vccin(29)" )
			)
			( pin "U5D1.CJ60"
				( objectStatus "@baseboard_fab2_lib.baseboard_fab2(sch_1):page37_i311:vccin(30)" )
			)
			( pin "U5D1.CH85"
				( objectStatus "@baseboard_fab2_lib.baseboard_fab2(sch_1):page37_i311:vccin(31)" )
			)
			( pin "U5D1.CH61"
				( objectStatus "@baseboard_fab2_lib.baseboard_fab2(sch_1):page37_i311:vccin(32)" )
			)
			( pin "U5D1.CG84"
				( objectStatus "@baseboard_fab2_lib.baseboard_fab2(sch_1):page37_i311:vccin(33)" )
			)
			( pin "U5D1.CG60"
				( objectStatus "@baseboard_fab2_lib.baseboard_fab2(sch_1):page37_i311:vccin(34)" )
			)
			( pin "U5D1.CF85"
				( objectStatus "@baseboard_fab2_lib.baseboard_fab2(sch_1):page37_i311:vccin(35)" )
			)
			( pin "U5D1.CF61"
				( objectStatus "@baseboard_fab2_lib.baseboard_fab2(sch_1):page37_i311:vccin(36)" )
			)
			( pin "U5D1.CE84"
				( objectStatus "@baseboard_fab2_lib.baseboard_fab2(sch_1):page37_i311:vccin(37)" )
			)
			( pin "U5D1.CE60"
				( objectStatus "@baseboard_fab2_lib.baseboard_fab2(sch_1):page37_i311:vccin(38)" )
			)
			( pin "U5D1.CD85"
				( objectStatus "@baseboard_fab2_lib.baseboard_fab2(sch_1):page37_i311:vccin(39)" )
			)
			( pin "U5D1.CD83"
				( objectStatus "@baseboard_fab2_lib.baseboard_fab2(sch_1):page37_i311:vccin(40)" )
			)
			( pin "U5D1.CD61"
				( objectStatus "@baseboard_fab2_lib.baseboard_fab2(sch_1):page37_i311:vccin(41)" )
			)
			( pin "U5D1.CC84"
				( objectStatus "@baseboard_fab2_lib.baseboard_fab2(sch_1):page37_i311:vccin(42)" )
			)
			( pin "U5D1.CC62"
				( objectStatus "@baseboard_fab2_lib.baseboard_fab2(sch_1):page37_i311:vccin(43)" )
			)
			( pin "U5D1.CC60"
				( objectStatus "@baseboard_fab2_lib.baseboard_fab2(sch_1):page37_i311:vccin(44)" )
			)
			( pin "U5D1.CB83"
				( objectStatus "@baseboard_fab2_lib.baseboard_fab2(sch_1):page37_i311:vccin(45)" )
			)
			( pin "U5D1.CB81"
				( objectStatus "@baseboard_fab2_lib.baseboard_fab2(sch_1):page37_i311:vccin(46)" )
			)
			( pin "U5D1.CB79"
				( objectStatus "@baseboard_fab2_lib.baseboard_fab2(sch_1):page37_i311:vccin(47)" )
			)
			( pin "U5D1.CB77"
				( objectStatus "@baseboard_fab2_lib.baseboard_fab2(sch_1):page37_i311:vccin(48)" )
			)
			( pin "U5D1.CB75"
				( objectStatus "@baseboard_fab2_lib.baseboard_fab2(sch_1):page37_i311:vccin(49)" )
			)
			( pin "U5D1.CB73"
				( objectStatus "@baseboard_fab2_lib.baseboard_fab2(sch_1):page37_i311:vccin(50)" )
			)
			( pin "U5D1.CB61"
				( objectStatus "@baseboard_fab2_lib.baseboard_fab2(sch_1):page37_i311:vccin(51)" )
			)
			( pin "U5D1.CA84"
				( objectStatus "@baseboard_fab2_lib.baseboard_fab2(sch_1):page37_i311:vccin(52)" )
			)
			( pin "U5D1.CA82"
				( objectStatus "@baseboard_fab2_lib.baseboard_fab2(sch_1):page37_i311:vccin(53)" )
			)
			( pin "U5D1.CA80"
				( objectStatus "@baseboard_fab2_lib.baseboard_fab2(sch_1):page37_i311:vccin(54)" )
			)
			( pin "U5D1.CA78"
				( objectStatus "@baseboard_fab2_lib.baseboard_fab2(sch_1):page37_i311:vccin(55)" )
			)
			( pin "U5D1.CA76"
				( objectStatus "@baseboard_fab2_lib.baseboard_fab2(sch_1):page37_i311:vccin(56)" )
			)
			( pin "U5D1.CA74"
				( objectStatus "@baseboard_fab2_lib.baseboard_fab2(sch_1):page37_i311:vccin(57)" )
			)
			( pin "U5D1.CA72"
				( objectStatus "@baseboard_fab2_lib.baseboard_fab2(sch_1):page37_i311:vccin(58)" )
			)
			( pin "U5D1.CA62"
				( objectStatus "@baseboard_fab2_lib.baseboard_fab2(sch_1):page37_i311:vccin(59)" )
			)
			( pin "U5D1.CA60"
				( objectStatus "@baseboard_fab2_lib.baseboard_fab2(sch_1):page37_i311:vccin(60)" )
			)
			( pin "U5D1.BY83"
				( objectStatus "@baseboard_fab2_lib.baseboard_fab2(sch_1):page37_i311:vccin(61)" )
			)
			( pin "U5D1.BY81"
				( objectStatus "@baseboard_fab2_lib.baseboard_fab2(sch_1):page37_i311:vccin(62)" )
			)
			( pin "U5D1.BY79"
				( objectStatus "@baseboard_fab2_lib.baseboard_fab2(sch_1):page37_i311:vccin(63)" )
			)
			( pin "U5D1.BY77"
				( objectStatus "@baseboard_fab2_lib.baseboard_fab2(sch_1):page37_i311:vccin(64)" )
			)
			( pin "U5D1.BY75"
				( objectStatus "@baseboard_fab2_lib.baseboard_fab2(sch_1):page37_i311:vccin(65)" )
			)
			( pin "U5D1.BY73"
				( objectStatus "@baseboard_fab2_lib.baseboard_fab2(sch_1):page37_i311:vccin(66)" )
			)
			( pin "U5D1.BY61"
				( objectStatus "@baseboard_fab2_lib.baseboard_fab2(sch_1):page37_i311:vccin(67)" )
			)
			( pin "U5D1.BW84"
				( objectStatus "@baseboard_fab2_lib.baseboard_fab2(sch_1):page37_i311:vccin(68)" )
			)
			( pin "U5D1.BW70"
				( objectStatus "@baseboard_fab2_lib.baseboard_fab2(sch_1):page37_i311:vccin(69)" )
			)
			( pin "U5D1.BW68"
				( objectStatus "@baseboard_fab2_lib.baseboard_fab2(sch_1):page37_i311:vccin(70)" )
			)
			( pin "U5D1.BW66"
				( objectStatus "@baseboard_fab2_lib.baseboard_fab2(sch_1):page37_i311:vccin(71)" )
			)
			( pin "U5D1.BW64"
				( objectStatus "@baseboard_fab2_lib.baseboard_fab2(sch_1):page37_i311:vccin(72)" )
			)
			( pin "U5D1.BW62"
				( objectStatus "@baseboard_fab2_lib.baseboard_fab2(sch_1):page37_i311:vccin(73)" )
			)
			( pin "U5D1.BW60"
				( objectStatus "@baseboard_fab2_lib.baseboard_fab2(sch_1):page37_i311:vccin(74)" )
			)
			( pin "U5D1.BV83"
				( objectStatus "@baseboard_fab2_lib.baseboard_fab2(sch_1):page37_i311:vccin(75)" )
			)
			( pin "U5D1.BV81"
				( objectStatus "@baseboard_fab2_lib.baseboard_fab2(sch_1):page37_i311:vccin(76)" )
			)
			( pin "U5D1.BV79"
				( objectStatus "@baseboard_fab2_lib.baseboard_fab2(sch_1):page37_i311:vccin(77)" )
			)
			( pin "U5D1.BV77"
				( objectStatus "@baseboard_fab2_lib.baseboard_fab2(sch_1):page37_i311:vccin(78)" )
			)
			( pin "U5D1.BV75"
				( objectStatus "@baseboard_fab2_lib.baseboard_fab2(sch_1):page37_i311:vccin(79)" )
			)
			( pin "U5D1.BV73"
				( objectStatus "@baseboard_fab2_lib.baseboard_fab2(sch_1):page37_i311:vccin(80)" )
			)
			( pin "U5D1.BV71"
				( objectStatus "@baseboard_fab2_lib.baseboard_fab2(sch_1):page37_i311:vccin(81)" )
			)
			( pin "U5D1.BV69"
				( objectStatus "@baseboard_fab2_lib.baseboard_fab2(sch_1):page37_i311:vccin(82)" )
			)
			( pin "U5D1.BV67"
				( objectStatus "@baseboard_fab2_lib.baseboard_fab2(sch_1):page37_i311:vccin(83)" )
			)
			( pin "U5D1.BV65"
				( objectStatus "@baseboard_fab2_lib.baseboard_fab2(sch_1):page37_i311:vccin(84)" )
			)
			( pin "U5D1.BV63"
				( objectStatus "@baseboard_fab2_lib.baseboard_fab2(sch_1):page37_i311:vccin(85)" )
			)
			( pin "U5D1.BV61"
				( objectStatus "@baseboard_fab2_lib.baseboard_fab2(sch_1):page37_i311:vccin(86)" )
			)
			( pin "U5D1.BU84"
				( objectStatus "@baseboard_fab2_lib.baseboard_fab2(sch_1):page37_i311:vccin(87)" )
			)
			( pin "U5D1.BU82"
				( objectStatus "@baseboard_fab2_lib.baseboard_fab2(sch_1):page37_i311:vccin(88)" )
			)
			( pin "U5D1.BU80"
				( objectStatus "@baseboard_fab2_lib.baseboard_fab2(sch_1):page37_i311:vccin(89)" )
			)
			( pin "U5D1.BU78"
				( objectStatus "@baseboard_fab2_lib.baseboard_fab2(sch_1):page37_i311:vccin(90)" )
			)
			( pin "U5D1.BU76"
				( objectStatus "@baseboard_fab2_lib.baseboard_fab2(sch_1):page37_i311:vccin(91)" )
			)
			( pin "U5D1.BU74"
				( objectStatus "@baseboard_fab2_lib.baseboard_fab2(sch_1):page37_i311:vccin(92)" )
			)
			( pin "U5D1.BU72"
				( objectStatus "@baseboard_fab2_lib.baseboard_fab2(sch_1):page37_i311:vccin(93)" )
			)
			( pin "U5D1.BU70"
				( objectStatus "@baseboard_fab2_lib.baseboard_fab2(sch_1):page37_i311:vccin(94)" )
			)
			( pin "U5D1.BU68"
				( objectStatus "@baseboard_fab2_lib.baseboard_fab2(sch_1):page37_i311:vccin(95)" )
			)
			( pin "U5D1.BU66"
				( objectStatus "@baseboard_fab2_lib.baseboard_fab2(sch_1):page37_i311:vccin(96)" )
			)
			( pin "U5D1.BU64"
				( objectStatus "@baseboard_fab2_lib.baseboard_fab2(sch_1):page37_i311:vccin(97)" )
			)
			( pin "U5D1.BU62"
				( objectStatus "@baseboard_fab2_lib.baseboard_fab2(sch_1):page37_i311:vccin(98)" )
			)
			( pin "U5D1.BU60"
				( objectStatus "@baseboard_fab2_lib.baseboard_fab2(sch_1):page37_i311:vccin(99)" )
			)
			( pin "U5D1.BT83"
				( objectStatus "@baseboard_fab2_lib.baseboard_fab2(sch_1):page37_i311:vccin(100)" )
			)
			( pin "U5D1.BT81"
				( objectStatus "@baseboard_fab2_lib.baseboard_fab2(sch_1):page37_i311:vccin(101)" )
			)
			( pin "U5D1.BT79"
				( objectStatus "@baseboard_fab2_lib.baseboard_fab2(sch_1):page37_i311:vccin(102)" )
			)
			( pin "U5D1.BT77"
				( objectStatus "@baseboard_fab2_lib.baseboard_fab2(sch_1):page37_i311:vccin(103)" )
			)
			( pin "U5D1.BT75"
				( objectStatus "@baseboard_fab2_lib.baseboard_fab2(sch_1):page37_i311:vccin(104)" )
			)
			( pin "U5D1.BT73"
				( objectStatus "@baseboard_fab2_lib.baseboard_fab2(sch_1):page37_i311:vccin(105)" )
			)
			( pin "U5D1.BT71"
				( objectStatus "@baseboard_fab2_lib.baseboard_fab2(sch_1):page37_i311:vccin(106)" )
			)
			( pin "U5D1.BT69"
				( objectStatus "@baseboard_fab2_lib.baseboard_fab2(sch_1):page37_i311:vccin(107)" )
			)
			( pin "U5D1.BT67"
				( objectStatus "@baseboard_fab2_lib.baseboard_fab2(sch_1):page37_i311:vccin(108)" )
			)
			( pin "U5D1.BT65"
				( objectStatus "@baseboard_fab2_lib.baseboard_fab2(sch_1):page37_i311:vccin(109)" )
			)
			( pin "U5D1.BT63"
				( objectStatus "@baseboard_fab2_lib.baseboard_fab2(sch_1):page37_i311:vccin(110)" )
			)
			( pin "U5D1.BT61"
				( objectStatus "@baseboard_fab2_lib.baseboard_fab2(sch_1):page37_i311:vccin(111)" )
			)
			( pin "U5D1.BR84"
				( objectStatus "@baseboard_fab2_lib.baseboard_fab2(sch_1):page37_i311:vccin(112)" )
			)
			( pin "U5D1.BR62"
				( objectStatus "@baseboard_fab2_lib.baseboard_fab2(sch_1):page37_i311:vccin(113)" )
			)
			( pin "U5D1.BR60"
				( objectStatus "@baseboard_fab2_lib.baseboard_fab2(sch_1):page37_i311:vccin(114)" )
			)
			( pin "U5D1.BP83"
				( objectStatus "@baseboard_fab2_lib.baseboard_fab2(sch_1):page37_i311:vccin(115)" )
			)
			( pin "U5D1.BP81"
				( objectStatus "@baseboard_fab2_lib.baseboard_fab2(sch_1):page37_i311:vccin(116)" )
			)
			( pin "U5D1.BP79"
				( objectStatus "@baseboard_fab2_lib.baseboard_fab2(sch_1):page37_i311:vccin(117)" )
			)
			( pin "U5D1.BP77"
				( objectStatus "@baseboard_fab2_lib.baseboard_fab2(sch_1):page37_i311:vccin(118)" )
			)
			( pin "U5D1.BP75"
				( objectStatus "@baseboard_fab2_lib.baseboard_fab2(sch_1):page37_i311:vccin(119)" )
			)
			( pin "U5D1.BP73"
				( objectStatus "@baseboard_fab2_lib.baseboard_fab2(sch_1):page37_i311:vccin(120)" )
			)
			( pin "U5D1.BP71"
				( objectStatus "@baseboard_fab2_lib.baseboard_fab2(sch_1):page37_i311:vccin(121)" )
			)
			( pin "U5D1.BP69"
				( objectStatus "@baseboard_fab2_lib.baseboard_fab2(sch_1):page37_i311:vccin(122)" )
			)
			( pin "U5D1.BP67"
				( objectStatus "@baseboard_fab2_lib.baseboard_fab2(sch_1):page37_i311:vccin(123)" )
			)
			( pin "U5D1.BP65"
				( objectStatus "@baseboard_fab2_lib.baseboard_fab2(sch_1):page37_i311:vccin(124)" )
			)
			( pin "U5D1.BP63"
				( objectStatus "@baseboard_fab2_lib.baseboard_fab2(sch_1):page37_i311:vccin(125)" )
			)
			( pin "U5D1.BP61"
				( objectStatus "@baseboard_fab2_lib.baseboard_fab2(sch_1):page37_i311:vccin(126)" )
			)
			( pin "U5D1.BN84"
				( objectStatus "@baseboard_fab2_lib.baseboard_fab2(sch_1):page37_i311:vccin(127)" )
			)
			( pin "U5D1.BN82"
				( objectStatus "@baseboard_fab2_lib.baseboard_fab2(sch_1):page37_i311:vccin(128)" )
			)
			( pin "U5D1.BN80"
				( objectStatus "@baseboard_fab2_lib.baseboard_fab2(sch_1):page37_i311:vccin(129)" )
			)
			( pin "U5D1.BA86"
				( objectStatus "@baseboard_fab2_lib.baseboard_fab2(sch_1):page37_i311:vccin_sense" )
			)
			( pin "U5D1.AW86"
				( objectStatus "@baseboard_fab2_lib.baseboard_fab2(sch_1):page37_i311:vccinpmax(0)" )
			)
			( pin "U5D1.AV85"
				( objectStatus "@baseboard_fab2_lib.baseboard_fab2(sch_1):page37_i311:vccinpmax(1)" )
			)
			( pin "U5D1.AD41"
				( objectStatus "@baseboard_fab2_lib.baseboard_fab2(sch_1):page37_i311:vsensepmax" )
			)
			( pin "U5D1.AY85"
				( objectStatus "@baseboard_fab2_lib.baseboard_fab2(sch_1):page37_i311:vss_vccin_sense" )
			)
			( pin "R5D6.1"
				( objectStatus "@baseboard_fab2_lib.baseboard_fab2(sch_1):page37_i312:a" )
			)
			( pin "R5D6.2"
				( objectStatus "@baseboard_fab2_lib.baseboard_fab2(sch_1):page37_i312:b" )
			)
			( pin "C6D1.1"
				( objectStatus "@baseboard_fab2_lib.baseboard_fab2(sch_1):page38_i19:a" )
			)
			( pin "C6D1.2"
				( objectStatus "@baseboard_fab2_lib.baseboard_fab2(sch_1):page38_i19:b" )
			)
			( pin "U5D1.B49"
				( objectStatus "@baseboard_fab2_lib.baseboard_fab2(sch_1):page38_i33:vccd012(0)" )
			)
			( pin "U5D1.B53"
				( objectStatus "@baseboard_fab2_lib.baseboard_fab2(sch_1):page38_i33:vccd012(1)" )
			)
			( pin "U5D1.B59"
				( objectStatus "@baseboard_fab2_lib.baseboard_fab2(sch_1):page38_i33:vccd012(2)" )
			)
			( pin "U5D1.E46"
				( objectStatus "@baseboard_fab2_lib.baseboard_fab2(sch_1):page38_i33:vccd012(3)" )
			)
			( pin "U5D1.E48"
				( objectStatus "@baseboard_fab2_lib.baseboard_fab2(sch_1):page38_i33:vccd012(4)" )
			)
			( pin "U5D1.E50"
				( objectStatus "@baseboard_fab2_lib.baseboard_fab2(sch_1):page38_i33:vccd012(5)" )
			)
			( pin "U5D1.E52"
				( objectStatus "@baseboard_fab2_lib.baseboard_fab2(sch_1):page38_i33:vccd012(6)" )
			)
			( pin "U5D1.E54"
				( objectStatus "@baseboard_fab2_lib.baseboard_fab2(sch_1):page38_i33:vccd012(7)" )
			)
			( pin "U5D1.E56"
				( objectStatus "@baseboard_fab2_lib.baseboard_fab2(sch_1):page38_i33:vccd012(8)" )
			)
			( pin "U5D1.E58"
				( objectStatus "@baseboard_fab2_lib.baseboard_fab2(sch_1):page38_i33:vccd012(9)" )
			)
			( pin "U5D1.E60"
				( objectStatus "@baseboard_fab2_lib.baseboard_fab2(sch_1):page38_i33:vccd012(10)" )
			)
			( pin "U5D1.E62"
				( objectStatus "@baseboard_fab2_lib.baseboard_fab2(sch_1):page38_i33:vccd012(11)" )
			)
			( pin "U5D1.E64"
				( objectStatus "@baseboard_fab2_lib.baseboard_fab2(sch_1):page38_i33:vccd012(12)" )
			)
			( pin "U5D1.L46"
				( objectStatus "@baseboard_fab2_lib.baseboard_fab2(sch_1):page38_i33:vccd012(13)" )
			)
			( pin "U5D1.L48"
				( objectStatus "@baseboard_fab2_lib.baseboard_fab2(sch_1):page38_i33:vccd012(14)" )
			)
			( pin "U5D1.L50"
				( objectStatus "@baseboard_fab2_lib.baseboard_fab2(sch_1):page38_i33:vccd012(15)" )
			)
			( pin "U5D1.L52"
				( objectStatus "@baseboard_fab2_lib.baseboard_fab2(sch_1):page38_i33:vccd012(16)" )
			)
			( pin "U5D1.L54"
				( objectStatus "@baseboard_fab2_lib.baseboard_fab2(sch_1):page38_i33:vccd012(17)" )
			)
			( pin "U5D1.L56"
				( objectStatus "@baseboard_fab2_lib.baseboard_fab2(sch_1):page38_i33:vccd012(18)" )
			)
			( pin "U5D1.L58"
				( objectStatus "@baseboard_fab2_lib.baseboard_fab2(sch_1):page38_i33:vccd012(19)" )
			)
			( pin "U5D1.L60"
				( objectStatus "@baseboard_fab2_lib.baseboard_fab2(sch_1):page38_i33:vccd012(20)" )
			)
			( pin "U5D1.L62"
				( objectStatus "@baseboard_fab2_lib.baseboard_fab2(sch_1):page38_i33:vccd012(21)" )
			)
			( pin "U5D1.N64"
				( objectStatus "@baseboard_fab2_lib.baseboard_fab2(sch_1):page38_i33:vccd012(22)" )
			)
			( pin "U5D1.U46"
				( objectStatus "@baseboard_fab2_lib.baseboard_fab2(sch_1):page38_i33:vccd012(23)" )
			)
			( pin "U5D1.U48"
				( objectStatus "@baseboard_fab2_lib.baseboard_fab2(sch_1):page38_i33:vccd012(24)" )
			)
			( pin "U5D1.U50"
				( objectStatus "@baseboard_fab2_lib.baseboard_fab2(sch_1):page38_i33:vccd012(25)" )
			)
			( pin "U5D1.U52"
				( objectStatus "@baseboard_fab2_lib.baseboard_fab2(sch_1):page38_i33:vccd012(26)" )
			)
			( pin "U5D1.U54"
				( objectStatus "@baseboard_fab2_lib.baseboard_fab2(sch_1):page38_i33:vccd012(27)" )
			)
			( pin "U5D1.U56"
				( objectStatus "@baseboard_fab2_lib.baseboard_fab2(sch_1):page38_i33:vccd012(28)" )
			)
			( pin "U5D1.U58"
				( objectStatus "@baseboard_fab2_lib.baseboard_fab2(sch_1):page38_i33:vccd012(29)" )
			)
			( pin "U5D1.U60"
				( objectStatus "@baseboard_fab2_lib.baseboard_fab2(sch_1):page38_i33:vccd012(30)" )
			)
			( pin "U5D1.U62"
				( objectStatus "@baseboard_fab2_lib.baseboard_fab2(sch_1):page38_i33:vccd012(31)" )
			)
			( pin "U5D1.W64"
				( objectStatus "@baseboard_fab2_lib.baseboard_fab2(sch_1):page38_i33:vccd012(32)" )
			)
			( pin "U5D1.Y45"
				( objectStatus "@baseboard_fab2_lib.baseboard_fab2(sch_1):page38_i33:vccd012(33)" )
			)
			( pin "U5D1.Y47"
				( objectStatus "@baseboard_fab2_lib.baseboard_fab2(sch_1):page38_i33:vccd012(34)" )
			)
			( pin "U5D1.Y49"
				( objectStatus "@baseboard_fab2_lib.baseboard_fab2(sch_1):page38_i33:vccd012(35)" )
			)
			( pin "U5D1.Y51"
				( objectStatus "@baseboard_fab2_lib.baseboard_fab2(sch_1):page38_i33:vccd012(36)" )
			)
			( pin "U5D1.Y53"
				( objectStatus "@baseboard_fab2_lib.baseboard_fab2(sch_1):page38_i33:vccd012(37)" )
			)
			( pin "U5D1.Y55"
				( objectStatus "@baseboard_fab2_lib.baseboard_fab2(sch_1):page38_i33:vccd012(38)" )
			)
			( pin "U5D1.Y57"
				( objectStatus "@baseboard_fab2_lib.baseboard_fab2(sch_1):page38_i33:vccd012(39)" )
			)
			( pin "U5D1.Y59"
				( objectStatus "@baseboard_fab2_lib.baseboard_fab2(sch_1):page38_i33:vccd012(40)" )
			)
			( pin "U5D1.Y61"
				( objectStatus "@baseboard_fab2_lib.baseboard_fab2(sch_1):page38_i33:vccd012(41)" )
			)
			( pin "U5D1.Y63"
				( objectStatus "@baseboard_fab2_lib.baseboard_fab2(sch_1):page38_i33:vccd012(42)" )
			)
			( pin "U5D1.AD45"
				( objectStatus "@baseboard_fab2_lib.baseboard_fab2(sch_1):page38_i33:vccd012(43)" )
			)
			( pin "U5D1.AF55"
				( objectStatus "@baseboard_fab2_lib.baseboard_fab2(sch_1):page38_i33:vccd012(44)" )
			)
			( pin "U5D1.AF57"
				( objectStatus "@baseboard_fab2_lib.baseboard_fab2(sch_1):page38_i33:vccd012(45)" )
			)
			( pin "U5D1.AF59"
				( objectStatus "@baseboard_fab2_lib.baseboard_fab2(sch_1):page38_i33:vccd012(46)" )
			)
			( pin "U5D1.AF61"
				( objectStatus "@baseboard_fab2_lib.baseboard_fab2(sch_1):page38_i33:vccd012(47)" )
			)
			( pin "U5D1.AF63"
				( objectStatus "@baseboard_fab2_lib.baseboard_fab2(sch_1):page38_i33:vccd012(48)" )
			)
			( pin "U5D1.D45"
				( objectStatus "@baseboard_fab2_lib.baseboard_fab2(sch_1):page38_i33:vccd012(49)" )
			)
			( pin "U5D1.C46"
				( objectStatus "@baseboard_fab2_lib.baseboard_fab2(sch_1):page38_i33:vccd012(50)" )
			)
			( pin "U5D1.B47"
				( objectStatus "@baseboard_fab2_lib.baseboard_fab2(sch_1):page38_i33:vccd012(51)" )
			)
			( pin "U5D1.EF59"
				( objectStatus "@baseboard_fab2_lib.baseboard_fab2(sch_1):page38_i33:vccd345(0)" )
			)
			( pin "U5D1.EF53"
				( objectStatus "@baseboard_fab2_lib.baseboard_fab2(sch_1):page38_i33:vccd345(1)" )
			)
			( pin "U5D1.EF49"
				( objectStatus "@baseboard_fab2_lib.baseboard_fab2(sch_1):page38_i33:vccd345(2)" )
			)
			( pin "U5D1.EC62"
				( objectStatus "@baseboard_fab2_lib.baseboard_fab2(sch_1):page38_i33:vccd345(3)" )
			)
			( pin "U5D1.EC60"
				( objectStatus "@baseboard_fab2_lib.baseboard_fab2(sch_1):page38_i33:vccd345(4)" )
			)
			( pin "U5D1.EC58"
				( objectStatus "@baseboard_fab2_lib.baseboard_fab2(sch_1):page38_i33:vccd345(5)" )
			)
			( pin "U5D1.EC56"
				( objectStatus "@baseboard_fab2_lib.baseboard_fab2(sch_1):page38_i33:vccd345(6)" )
			)
			( pin "U5D1.EC54"
				( objectStatus "@baseboard_fab2_lib.baseboard_fab2(sch_1):page38_i33:vccd345(7)" )
			)
			( pin "U5D1.EC52"
				( objectStatus "@baseboard_fab2_lib.baseboard_fab2(sch_1):page38_i33:vccd345(8)" )
			)
			( pin "U5D1.EC50"
				( objectStatus "@baseboard_fab2_lib.baseboard_fab2(sch_1):page38_i33:vccd345(9)" )
			)
			( pin "U5D1.EC48"
				( objectStatus "@baseboard_fab2_lib.baseboard_fab2(sch_1):page38_i33:vccd345(10)" )
			)
			( pin "U5D1.EC46"
				( objectStatus "@baseboard_fab2_lib.baseboard_fab2(sch_1):page38_i33:vccd345(11)" )
			)
			( pin "U5D1.DU64"
				( objectStatus "@baseboard_fab2_lib.baseboard_fab2(sch_1):page38_i33:vccd345(12)" )
			)
			( pin "U5D1.DU62"
				( objectStatus "@baseboard_fab2_lib.baseboard_fab2(sch_1):page38_i33:vccd345(13)" )
			)
			( pin "U5D1.DU60"
				( objectStatus "@baseboard_fab2_lib.baseboard_fab2(sch_1):page38_i33:vccd345(14)" )
			)
			( pin "U5D1.DU58"
				( objectStatus "@baseboard_fab2_lib.baseboard_fab2(sch_1):page38_i33:vccd345(15)" )
			)
			( pin "U5D1.DU56"
				( objectStatus "@baseboard_fab2_lib.baseboard_fab2(sch_1):page38_i33:vccd345(16)" )
			)
			( pin "U5D1.DU54"
				( objectStatus "@baseboard_fab2_lib.baseboard_fab2(sch_1):page38_i33:vccd345(17)" )
			)
			( pin "U5D1.DU52"
				( objectStatus "@baseboard_fab2_lib.baseboard_fab2(sch_1):page38_i33:vccd345(18)" )
			)
			( pin "U5D1.DU50"
				( objectStatus "@baseboard_fab2_lib.baseboard_fab2(sch_1):page38_i33:vccd345(19)" )
			)
			( pin "U5D1.DU48"
				( objectStatus "@baseboard_fab2_lib.baseboard_fab2(sch_1):page38_i33:vccd345(20)" )
			)
			( pin "U5D1.DU46"
				( objectStatus "@baseboard_fab2_lib.baseboard_fab2(sch_1):page38_i33:vccd345(21)" )
			)
			( pin "U5D1.DL62"
				( objectStatus "@baseboard_fab2_lib.baseboard_fab2(sch_1):page38_i33:vccd345(22)" )
			)
			( pin "U5D1.DL60"
				( objectStatus "@baseboard_fab2_lib.baseboard_fab2(sch_1):page38_i33:vccd345(23)" )
			)
			( pin "U5D1.DL58"
				( objectStatus "@baseboard_fab2_lib.baseboard_fab2(sch_1):page38_i33:vccd345(24)" )
			)
			( pin "U5D1.DL56"
				( objectStatus "@baseboard_fab2_lib.baseboard_fab2(sch_1):page38_i33:vccd345(25)" )
			)
			( pin "U5D1.DL54"
				( objectStatus "@baseboard_fab2_lib.baseboard_fab2(sch_1):page38_i33:vccd345(26)" )
			)
			( pin "U5D1.DL52"
				( objectStatus "@baseboard_fab2_lib.baseboard_fab2(sch_1):page38_i33:vccd345(27)" )
			)
			( pin "U5D1.DL50"
				( objectStatus "@baseboard_fab2_lib.baseboard_fab2(sch_1):page38_i33:vccd345(28)" )
			)
			( pin "U5D1.DL48"
				( objectStatus "@baseboard_fab2_lib.baseboard_fab2(sch_1):page38_i33:vccd345(29)" )
			)
			( pin "U5D1.DL46"
				( objectStatus "@baseboard_fab2_lib.baseboard_fab2(sch_1):page38_i33:vccd345(30)" )
			)
			( pin "U5D1.DJ64"
				( objectStatus "@baseboard_fab2_lib.baseboard_fab2(sch_1):page38_i33:vccd345(31)" )
			)
			( pin "U5D1.DH63"
				( objectStatus "@baseboard_fab2_lib.baseboard_fab2(sch_1):page38_i33:vccd345(32)" )
			)
			( pin "U5D1.DH61"
				( objectStatus "@baseboard_fab2_lib.baseboard_fab2(sch_1):page38_i33:vccd345(33)" )
			)
			( pin "U5D1.DH59"
				( objectStatus "@baseboard_fab2_lib.baseboard_fab2(sch_1):page38_i33:vccd345(34)" )
			)
			( pin "U5D1.DH57"
				( objectStatus "@baseboard_fab2_lib.baseboard_fab2(sch_1):page38_i33:vccd345(35)" )
			)
			( pin "U5D1.DH55"
				( objectStatus "@baseboard_fab2_lib.baseboard_fab2(sch_1):page38_i33:vccd345(36)" )
			)
			( pin "U5D1.DH53"
				( objectStatus "@baseboard_fab2_lib.baseboard_fab2(sch_1):page38_i33:vccd345(37)" )
			)
			( pin "U5D1.DH51"
				( objectStatus "@baseboard_fab2_lib.baseboard_fab2(sch_1):page38_i33:vccd345(38)" )
			)
			( pin "U5D1.DH49"
				( objectStatus "@baseboard_fab2_lib.baseboard_fab2(sch_1):page38_i33:vccd345(39)" )
			)
			( pin "U5D1.DH47"
				( objectStatus "@baseboard_fab2_lib.baseboard_fab2(sch_1):page38_i33:vccd345(40)" )
			)
			( pin "U5D1.DH45"
				( objectStatus "@baseboard_fab2_lib.baseboard_fab2(sch_1):page38_i33:vccd345(41)" )
			)
			( pin "U5D1.DD45"
				( objectStatus "@baseboard_fab2_lib.baseboard_fab2(sch_1):page38_i33:vccd345(42)" )
			)
			( pin "U5D1.DB63"
				( objectStatus "@baseboard_fab2_lib.baseboard_fab2(sch_1):page38_i33:vccd345(43)" )
			)
			( pin "U5D1.DB61"
				( objectStatus "@baseboard_fab2_lib.baseboard_fab2(sch_1):page38_i33:vccd345(44)" )
			)
			( pin "U5D1.DB59"
				( objectStatus "@baseboard_fab2_lib.baseboard_fab2(sch_1):page38_i33:vccd345(45)" )
			)
			( pin "U5D1.DB57"
				( objectStatus "@baseboard_fab2_lib.baseboard_fab2(sch_1):page38_i33:vccd345(46)" )
			)
			( pin "U5D1.DB55"
				( objectStatus "@baseboard_fab2_lib.baseboard_fab2(sch_1):page38_i33:vccd345(47)" )
			)
			( pin "U5D1.DB53"
				( objectStatus "@baseboard_fab2_lib.baseboard_fab2(sch_1):page38_i33:vccd345(48)" )
			)
			( pin "U5D1.EF45"
				( objectStatus "@baseboard_fab2_lib.baseboard_fab2(sch_1):page38_i33:vccd345(49)" )
			)
			( pin "U5D1.EE44"
				( objectStatus "@baseboard_fab2_lib.baseboard_fab2(sch_1):page38_i33:vccd345(50)" )
			)
			( pin "U5D1.BL14"
				( objectStatus "@baseboard_fab2_lib.baseboard_fab2(sch_1):page38_i34:cd_vcc_core(0)" )
			)
			( pin "U5D1.BK15"
				( objectStatus "@baseboard_fab2_lib.baseboard_fab2(sch_1):page38_i34:cd_vcc_core(1)" )
			)
			( pin "U5D1.BK13"
				( objectStatus "@baseboard_fab2_lib.baseboard_fab2(sch_1):page38_i34:cd_vcc_core(2)" )
			)
			( pin "U5D1.BJ14"
				( objectStatus "@baseboard_fab2_lib.baseboard_fab2(sch_1):page38_i34:cd_vcc_core(3)" )
			)
			( pin "U5D1.BJ12"
				( objectStatus "@baseboard_fab2_lib.baseboard_fab2(sch_1):page38_i34:cd_vcc_core(4)" )
			)
			( pin "U5D1.BH13"
				( objectStatus "@baseboard_fab2_lib.baseboard_fab2(sch_1):page38_i34:cd_vcc_core(5)" )
			)
			( pin "U5D1.BG14"
				( objectStatus "@baseboard_fab2_lib.baseboard_fab2(sch_1):page38_i34:cd_vcc_core(6)" )
			)
			( pin "U5D1.BG12"
				( objectStatus "@baseboard_fab2_lib.baseboard_fab2(sch_1):page38_i34:cd_vcc_core(7)" )
			)
			( pin "U5D1.BF13"
				( objectStatus "@baseboard_fab2_lib.baseboard_fab2(sch_1):page38_i34:cd_vcc_core(8)" )
			)
			( pin "U5D1.BF11"
				( objectStatus "@baseboard_fab2_lib.baseboard_fab2(sch_1):page38_i34:cd_vcc_core(9)" )
			)
			( pin "U5D1.BE14"
				( objectStatus "@baseboard_fab2_lib.baseboard_fab2(sch_1):page38_i34:cd_vcc_core(10)" )
			)
			( pin "U5D1.BE12"
				( objectStatus "@baseboard_fab2_lib.baseboard_fab2(sch_1):page38_i34:cd_vcc_core(11)" )
			)
			( pin "U5D1.BD13"
				( objectStatus "@baseboard_fab2_lib.baseboard_fab2(sch_1):page38_i34:cd_vcc_core(12)" )
			)
			( pin "U5D1.BT27"
				( objectStatus "@baseboard_fab2_lib.baseboard_fab2(sch_1):page38_i34:cd_vccin(0)" )
			)
			( pin "U5D1.BU26"
				( objectStatus "@baseboard_fab2_lib.baseboard_fab2(sch_1):page38_i34:cd_vccin(1)" )
			)
			( pin "U5D1.BV27"
				( objectStatus "@baseboard_fab2_lib.baseboard_fab2(sch_1):page38_i34:cd_vccin(2)" )
			)
			( pin "U5D1.BY27"
				( objectStatus "@baseboard_fab2_lib.baseboard_fab2(sch_1):page38_i34:cd_vccin(3)" )
			)
			( pin "U5D1.BV15"
				( objectStatus "@baseboard_fab2_lib.baseboard_fab2(sch_1):page38_i34:cd_vccp(0)" )
			)
			( pin "U5D1.BV13"
				( objectStatus "@baseboard_fab2_lib.baseboard_fab2(sch_1):page38_i34:cd_vccp(1)" )
			)
			( pin "U5D1.BV11"
				( objectStatus "@baseboard_fab2_lib.baseboard_fab2(sch_1):page38_i34:cd_vccp(2)" )
			)
			( pin "U5D1.BU14"
				( objectStatus "@baseboard_fab2_lib.baseboard_fab2(sch_1):page38_i34:cd_vccp(3)" )
			)
			( pin "U5D1.BU12"
				( objectStatus "@baseboard_fab2_lib.baseboard_fab2(sch_1):page38_i34:cd_vccp(4)" )
			)
			( pin "U5D1.BT15"
				( objectStatus "@baseboard_fab2_lib.baseboard_fab2(sch_1):page38_i34:cd_vccp(5)" )
			)
			( pin "U5D1.BT13"
				( objectStatus "@baseboard_fab2_lib.baseboard_fab2(sch_1):page38_i34:cd_vccp(6)" )
			)
			( pin "U5D1.BT11"
				( objectStatus "@baseboard_fab2_lib.baseboard_fab2(sch_1):page38_i34:cd_vccp(7)" )
			)
			( pin "U5D1.BR14"
				( objectStatus "@baseboard_fab2_lib.baseboard_fab2(sch_1):page38_i34:cd_vccp(8)" )
			)
			( pin "U5D1.BR12"
				( objectStatus "@baseboard_fab2_lib.baseboard_fab2(sch_1):page38_i34:cd_vccp(9)" )
			)
			( pin "U5D1.BP15"
				( objectStatus "@baseboard_fab2_lib.baseboard_fab2(sch_1):page38_i34:cd_vccp(10)" )
			)
			( pin "U5D1.BP13"
				( objectStatus "@baseboard_fab2_lib.baseboard_fab2(sch_1):page38_i34:cd_vccp(11)" )
			)
			( pin "U5D1.BP11"
				( objectStatus "@baseboard_fab2_lib.baseboard_fab2(sch_1):page38_i34:cd_vccp(12)" )
			)
			( pin "U5D1.BN14"
				( objectStatus "@baseboard_fab2_lib.baseboard_fab2(sch_1):page38_i34:cd_vccp(13)" )
			)
			( pin "U5D1.BN12"
				( objectStatus "@baseboard_fab2_lib.baseboard_fab2(sch_1):page38_i34:cd_vccp(14)" )
			)
			( pin "U5D1.BM11"
				( objectStatus "@baseboard_fab2_lib.baseboard_fab2(sch_1):page38_i34:cd_vccp(15)" )
			)
			( pin "U5D1.B11"
				( objectStatus "@baseboard_fab2_lib.baseboard_fab2(sch_1):page38_i34:cd_vpp(0)" )
			)
			( pin "U5D1.A12"
				( objectStatus "@baseboard_fab2_lib.baseboard_fab2(sch_1):page38_i34:cd_vpp(1)" )
			)
			( pin "U5D1.A10"
				( objectStatus "@baseboard_fab2_lib.baseboard_fab2(sch_1):page38_i34:cd_vpp(2)" )
			)
			( pin "U5D1.A8"
				( objectStatus "@baseboard_fab2_lib.baseboard_fab2(sch_1):page38_i34:cd_vpp(3)" )
			)
			( pin "U5D1.CY55"
				( objectStatus "@baseboard_fab2_lib.baseboard_fab2(sch_1):page38_i34:vcc33" )
			)
			( pin "U5D1.CM15"
				( objectStatus "@baseboard_fab2_lib.baseboard_fab2(sch_1):page38_i34:vccio(20)" )
			)
			( pin "U5D1.CL12"
				( objectStatus "@baseboard_fab2_lib.baseboard_fab2(sch_1):page38_i34:vccio(21)" )
			)
			( pin "U5D1.CK5"
				( objectStatus "@baseboard_fab2_lib.baseboard_fab2(sch_1):page38_i34:vccio(22)" )
			)
			( pin "U5D1.CV7"
				( objectStatus "@baseboard_fab2_lib.baseboard_fab2(sch_1):page38_i34:vccio(23)" )
			)
			( pin "U5D1.CH9"
				( objectStatus "@baseboard_fab2_lib.baseboard_fab2(sch_1):page38_i34:vccio(24)" )
			)
			( pin "U5D1.D7"
				( objectStatus "@baseboard_fab2_lib.baseboard_fab2(sch_1):page38_i34:vccio(25)" )
			)
			( pin "U5D1.CE18"
				( objectStatus "@baseboard_fab2_lib.baseboard_fab2(sch_1):page38_i34:vccio(26)" )
			)
			( pin "U5D1.CD9"
				( objectStatus "@baseboard_fab2_lib.baseboard_fab2(sch_1):page38_i34:vccio(27)" )
			)
			( pin "U5D1.CB17"
				( objectStatus "@baseboard_fab2_lib.baseboard_fab2(sch_1):page38_i34:vccio(28)" )
			)
			( pin "U5D1.CB13"
				( objectStatus "@baseboard_fab2_lib.baseboard_fab2(sch_1):page38_i34:vccio(29)" )
			)
			( pin "U5D1.BP25"
				( objectStatus "@baseboard_fab2_lib.baseboard_fab2(sch_1):page38_i34:vccio(30)" )
			)
			( pin "U5D1.BJ24"
				( objectStatus "@baseboard_fab2_lib.baseboard_fab2(sch_1):page38_i34:vccio(31)" )
			)
			( pin "U5D1.BF23"
				( objectStatus "@baseboard_fab2_lib.baseboard_fab2(sch_1):page38_i34:vccio(32)" )
			)
			( pin "U5D1.DA14"
				( objectStatus "@baseboard_fab2_lib.baseboard_fab2(sch_1):page38_i34:vccio(33)" )
			)
			( pin "U5D1.BB5"
				( objectStatus "@baseboard_fab2_lib.baseboard_fab2(sch_1):page38_i34:vccio(34)" )
			)
			( pin "U5D1.BA24"
				( objectStatus "@baseboard_fab2_lib.baseboard_fab2(sch_1):page38_i34:vccio(35)" )
			)
			( pin "U5D1.AY11"
				( objectStatus "@baseboard_fab2_lib.baseboard_fab2(sch_1):page38_i34:vccio(36)" )
			)
			( pin "U5D1.AW6"
				( objectStatus "@baseboard_fab2_lib.baseboard_fab2(sch_1):page38_i34:vccio(37)" )
			)
			( pin "U5D1.AT11"
				( objectStatus "@baseboard_fab2_lib.baseboard_fab2(sch_1):page38_i34:vccio(38)" )
			)
			( pin "U5D1.DD7"
				( objectStatus "@baseboard_fab2_lib.baseboard_fab2(sch_1):page38_i34:vccio(39)" )
			)
			( pin "U5D1.AN10"
				( objectStatus "@baseboard_fab2_lib.baseboard_fab2(sch_1):page38_i34:vccio(40)" )
			)
			( pin "U5D1.DF13"
				( objectStatus "@baseboard_fab2_lib.baseboard_fab2(sch_1):page38_i34:vccio(41)" )
			)
			( pin "U5D1.AH9"
				( objectStatus "@baseboard_fab2_lib.baseboard_fab2(sch_1):page38_i34:vccio(42)" )
			)
			( pin "U5D1.AC4"
				( objectStatus "@baseboard_fab2_lib.baseboard_fab2(sch_1):page38_i34:vccio(43)" )
			)
			( pin "U5D1.AC20"
				( objectStatus "@baseboard_fab2_lib.baseboard_fab2(sch_1):page38_i34:vccio(44)" )
			)
			( pin "U5D1.AA10"
				( objectStatus "@baseboard_fab2_lib.baseboard_fab2(sch_1):page38_i34:vccio(45)" )
			)
			( pin "U5D1.W6"
				( objectStatus "@baseboard_fab2_lib.baseboard_fab2(sch_1):page38_i34:vccio(46)" )
			)
			( pin "U5D1.W4"
				( objectStatus "@baseboard_fab2_lib.baseboard_fab2(sch_1):page38_i34:vccio(47)" )
			)
			( pin "U5D1.DF21"
				( objectStatus "@baseboard_fab2_lib.baseboard_fab2(sch_1):page38_i34:vccio(48)" )
			)
			( pin "U5D1.U14"
				( objectStatus "@baseboard_fab2_lib.baseboard_fab2(sch_1):page38_i34:vccio(49)" )
			)
			( pin "U5D1.T3"
				( objectStatus "@baseboard_fab2_lib.baseboard_fab2(sch_1):page38_i34:vccio(50)" )
			)
			( pin "U5D1.P5"
				( objectStatus "@baseboard_fab2_lib.baseboard_fab2(sch_1):page38_i34:vccio(51)" )
			)
			( pin "U5D1.M21"
				( objectStatus "@baseboard_fab2_lib.baseboard_fab2(sch_1):page38_i34:vccio(52)" )
			)
			( pin "U5D1.M11"
				( objectStatus "@baseboard_fab2_lib.baseboard_fab2(sch_1):page38_i34:vccio(53)" )
			)
			( pin "U5D1.DG8"
				( objectStatus "@baseboard_fab2_lib.baseboard_fab2(sch_1):page38_i34:vccio(54)" )
			)
			( pin "U5D1.DH7"
				( objectStatus "@baseboard_fab2_lib.baseboard_fab2(sch_1):page38_i34:vccio(55)" )
			)
			( pin "U5D1.L16"
				( objectStatus "@baseboard_fab2_lib.baseboard_fab2(sch_1):page38_i34:vccio(56)" )
			)
			( pin "U5D1.L14"
				( objectStatus "@baseboard_fab2_lib.baseboard_fab2(sch_1):page38_i34:vccio(57)" )
			)
			( pin "U5D1.J10"
				( objectStatus "@baseboard_fab2_lib.baseboard_fab2(sch_1):page38_i34:vccio(58)" )
			)
			( pin "U5D1.H13"
				( objectStatus "@baseboard_fab2_lib.baseboard_fab2(sch_1):page38_i34:vccio(59)" )
			)
			( pin "U5D1.DJ16"
				( objectStatus "@baseboard_fab2_lib.baseboard_fab2(sch_1):page38_i34:vccio(60)" )
			)
			( pin "U5D1.DM17"
				( objectStatus "@baseboard_fab2_lib.baseboard_fab2(sch_1):page38_i34:vccio(61)" )
			)
			( pin "U5D1.DN8"
				( objectStatus "@baseboard_fab2_lib.baseboard_fab2(sch_1):page38_i34:vccio(62)" )
			)
			( pin "U5D1.DP19"
				( objectStatus "@baseboard_fab2_lib.baseboard_fab2(sch_1):page38_i34:vccio(63)" )
			)
			( pin "U5D1.DR10"
				( objectStatus "@baseboard_fab2_lib.baseboard_fab2(sch_1):page38_i34:vccio(64)" )
			)
			( pin "U5D1.DR2"
				( objectStatus "@baseboard_fab2_lib.baseboard_fab2(sch_1):page38_i34:vccio(65)" )
			)
			( pin "U5D1.DU20"
				( objectStatus "@baseboard_fab2_lib.baseboard_fab2(sch_1):page38_i34:vccio(66)" )
			)
			( pin "U5D1.EA12"
				( objectStatus "@baseboard_fab2_lib.baseboard_fab2(sch_1):page38_i34:vccio(67)" )
			)
			( pin "U5D1.EB15"
				( objectStatus "@baseboard_fab2_lib.baseboard_fab2(sch_1):page38_i34:vccio(68)" )
			)
			( pin "U5D1.J2"
				( objectStatus "@baseboard_fab2_lib.baseboard_fab2(sch_1):page38_i34:vccio(69)" )
			)
			( pin "U5D1.K15"
				( objectStatus "@baseboard_fab2_lib.baseboard_fab2(sch_1):page38_i34:vccio(70)" )
			)
			( pin "U5D1.M7"
				( objectStatus "@baseboard_fab2_lib.baseboard_fab2(sch_1):page38_i34:vccio(71)" )
			)
			( pin "U5D1.M9"
				( objectStatus "@baseboard_fab2_lib.baseboard_fab2(sch_1):page38_i34:vccio(72)" )
			)
			( pin "U5D1.N18"
				( objectStatus "@baseboard_fab2_lib.baseboard_fab2(sch_1):page38_i34:vccio(73)" )
			)
			( pin "U5D1.W10"
				( objectStatus "@baseboard_fab2_lib.baseboard_fab2(sch_1):page38_i34:vccio(74)" )
			)
			( pin "U5D1.BC26"
				( objectStatus "@baseboard_fab2_lib.baseboard_fab2(sch_1):page38_i34:vccio(75)" )
			)
			( pin "U5D1.BB27"
				( objectStatus "@baseboard_fab2_lib.baseboard_fab2(sch_1):page38_i34:vccio(76)" )
			)
			( pin "U5D1.BA26"
				( objectStatus "@baseboard_fab2_lib.baseboard_fab2(sch_1):page38_i34:vccio(77)" )
			)
			( pin "U5D1.AY27"
				( objectStatus "@baseboard_fab2_lib.baseboard_fab2(sch_1):page38_i34:vccio(78)" )
			)
			( pin "U5D1.AW26"
				( objectStatus "@baseboard_fab2_lib.baseboard_fab2(sch_1):page38_i34:vccio(79)" )
			)
			( pin "U5D1.AV27"
				( objectStatus "@baseboard_fab2_lib.baseboard_fab2(sch_1):page38_i34:vccio(80)" )
			)
			( pin "U5D1.CF27"
				( objectStatus "@baseboard_fab2_lib.baseboard_fab2(sch_1):page38_i34:vccio(81)" )
			)
			( pin "U5D1.CD27"
				( objectStatus "@baseboard_fab2_lib.baseboard_fab2(sch_1):page38_i34:vccio(82)" )
			)
			( pin "U5D1.CC26"
				( objectStatus "@baseboard_fab2_lib.baseboard_fab2(sch_1):page38_i34:vccio(83)" )
			)
			( pin "U5D1.CJ28"
				( objectStatus "@baseboard_fab2_lib.baseboard_fab2(sch_1):page38_i34:vccio(84)" )
			)
			( pin "U5D1.CH27"
				( objectStatus "@baseboard_fab2_lib.baseboard_fab2(sch_1):page38_i34:vccio(85)" )
			)
			( pin "U5D1.BM27"
				( objectStatus "@baseboard_fab2_lib.baseboard_fab2(sch_1):page38_i34:vccio(86)" )
			)
			( pin "U5D1.BL26"
				( objectStatus "@baseboard_fab2_lib.baseboard_fab2(sch_1):page38_i34:vccio(87)" )
			)
			( pin "U5D1.BK27"
				( objectStatus "@baseboard_fab2_lib.baseboard_fab2(sch_1):page38_i34:vccio(88)" )
			)
			( pin "U5D1.BK25"
				( objectStatus "@baseboard_fab2_lib.baseboard_fab2(sch_1):page38_i34:vccio(89)" )
			)
			( pin "U5D1.BJ26"
				( objectStatus "@baseboard_fab2_lib.baseboard_fab2(sch_1):page38_i34:vccio(90)" )
			)
			( pin "U5D1.BH27"
				( objectStatus "@baseboard_fab2_lib.baseboard_fab2(sch_1):page38_i34:vccio(91)" )
			)
			( pin "U5D1.BH25"
				( objectStatus "@baseboard_fab2_lib.baseboard_fab2(sch_1):page38_i34:vccio(92)" )
			)
			( pin "U5D1.BG26"
				( objectStatus "@baseboard_fab2_lib.baseboard_fab2(sch_1):page38_i34:vccio(93)" )
			)
			( pin "U5D1.BF27"
				( objectStatus "@baseboard_fab2_lib.baseboard_fab2(sch_1):page38_i34:vccio(94)" )
			)
			( pin "U5D1.AE36"
				( objectStatus "@baseboard_fab2_lib.baseboard_fab2(sch_1):page38_i34:vccio(95)" )
			)
			( pin "U5D1.AD37"
				( objectStatus "@baseboard_fab2_lib.baseboard_fab2(sch_1):page38_i34:vccio(96)" )
			)
			( pin "U5D1.AC36"
				( objectStatus "@baseboard_fab2_lib.baseboard_fab2(sch_1):page38_i34:vccio(97)" )
			)
			( pin "U5D1.AF35"
				( objectStatus "@baseboard_fab2_lib.baseboard_fab2(sch_1):page38_i34:vccio(98)" )
			)
			( pin "U5D1.AD35"
				( objectStatus "@baseboard_fab2_lib.baseboard_fab2(sch_1):page38_i34:vccio(99)" )
			)
			( pin "U5D1.AE34"
				( objectStatus "@baseboard_fab2_lib.baseboard_fab2(sch_1):page38_i34:vccio(100)" )
			)
			( pin "U5D1.AG34"
				( objectStatus "@baseboard_fab2_lib.baseboard_fab2(sch_1):page38_i34:vccio(101)" )
			)
			( pin "U5D1.AM29"
				( objectStatus "@baseboard_fab2_lib.baseboard_fab2(sch_1):page38_i34:vccio(102)" )
			)
			( pin "U5D1.AL28"
				( objectStatus "@baseboard_fab2_lib.baseboard_fab2(sch_1):page38_i34:vccio(103)" )
			)
			( pin "U5D1.AR28"
				( objectStatus "@baseboard_fab2_lib.baseboard_fab2(sch_1):page38_i34:vccio(104)" )
			)
			( pin "U5D1.CJ66"
				( objectStatus "@baseboard_fab2_lib.baseboard_fab2(sch_1):page38_i34:vccsa(0)" )
			)
			( pin "U5D1.CJ64"
				( objectStatus "@baseboard_fab2_lib.baseboard_fab2(sch_1):page38_i34:vccsa(1)" )
			)
			( pin "U5D1.CH75"
				( objectStatus "@baseboard_fab2_lib.baseboard_fab2(sch_1):page38_i34:vccsa(2)" )
			)
			( pin "U5D1.CH65"
				( objectStatus "@baseboard_fab2_lib.baseboard_fab2(sch_1):page38_i34:vccsa(3)" )
			)
			( pin "U5D1.CG74"
				( objectStatus "@baseboard_fab2_lib.baseboard_fab2(sch_1):page38_i34:vccsa(4)" )
			)
			( pin "U5D1.CG66"
				( objectStatus "@baseboard_fab2_lib.baseboard_fab2(sch_1):page38_i34:vccsa(5)" )
			)
			( pin "U5D1.CG64"
				( objectStatus "@baseboard_fab2_lib.baseboard_fab2(sch_1):page38_i34:vccsa(6)" )
			)
			( pin "U5D1.CF75"
				( objectStatus "@baseboard_fab2_lib.baseboard_fab2(sch_1):page38_i34:vccsa(7)" )
			)
			( pin "U5D1.CF73"
				( objectStatus "@baseboard_fab2_lib.baseboard_fab2(sch_1):page38_i34:vccsa(8)" )
			)
			( pin "U5D1.CF67"
				( objectStatus "@baseboard_fab2_lib.baseboard_fab2(sch_1):page38_i34:vccsa(9)" )
			)
			( pin "U5D1.CF65"
				( objectStatus "@baseboard_fab2_lib.baseboard_fab2(sch_1):page38_i34:vccsa(10)" )
			)
			( pin "U5D1.CE74"
				( objectStatus "@baseboard_fab2_lib.baseboard_fab2(sch_1):page38_i34:vccsa(11)" )
			)
			( pin "U5D1.CE72"
				( objectStatus "@baseboard_fab2_lib.baseboard_fab2(sch_1):page38_i34:vccsa(12)" )
			)
			( pin "U5D1.CE68"
				( objectStatus "@baseboard_fab2_lib.baseboard_fab2(sch_1):page38_i34:vccsa(13)" )
			)
			( pin "U5D1.CE66"
				( objectStatus "@baseboard_fab2_lib.baseboard_fab2(sch_1):page38_i34:vccsa(14)" )
			)
			( pin "U5D1.CE64"
				( objectStatus "@baseboard_fab2_lib.baseboard_fab2(sch_1):page38_i34:vccsa(15)" )
			)
			( pin "U5D1.CD71"
				( objectStatus "@baseboard_fab2_lib.baseboard_fab2(sch_1):page38_i34:vccsa(16)" )
			)
			( pin "U5D1.CD69"
				( objectStatus "@baseboard_fab2_lib.baseboard_fab2(sch_1):page38_i34:vccsa(17)" )
			)
			( pin "U5D1.CD67"
				( objectStatus "@baseboard_fab2_lib.baseboard_fab2(sch_1):page38_i34:vccsa(18)" )
			)
			( pin "U5D1.CD65"
				( objectStatus "@baseboard_fab2_lib.baseboard_fab2(sch_1):page38_i34:vccsa(19)" )
			)
			( pin "U5D1.CC70"
				( objectStatus "@baseboard_fab2_lib.baseboard_fab2(sch_1):page38_i34:vccsa(20)" )
			)
			( pin "U5D1.CC68"
				( objectStatus "@baseboard_fab2_lib.baseboard_fab2(sch_1):page38_i34:vccsa(21)" )
			)
			( pin "U5D1.CC66"
				( objectStatus "@baseboard_fab2_lib.baseboard_fab2(sch_1):page38_i34:vccsa(22)" )
			)
			( pin "U5D1.CB69"
				( objectStatus "@baseboard_fab2_lib.baseboard_fab2(sch_1):page38_i34:vccsa(23)" )
			)
			( pin "U5D1.CB67"
				( objectStatus "@baseboard_fab2_lib.baseboard_fab2(sch_1):page38_i34:vccsa(24)" )
			)
			( pin "U5D1.CB65"
				( objectStatus "@baseboard_fab2_lib.baseboard_fab2(sch_1):page38_i34:vccsa(25)" )
			)
			( pin "U5D1.BN16"
				( objectStatus "@baseboard_fab2_lib.baseboard_fab2(sch_1):page39_i127:cd_vcc_core_sense" )
			)
			( pin "U5D1.BU16"
				( objectStatus "@baseboard_fab2_lib.baseboard_fab2(sch_1):page39_i127:cd_vccp_sense(0)" )
			)
			( pin "U5D1.BT17"
				( objectStatus "@baseboard_fab2_lib.baseboard_fab2(sch_1):page39_i127:cd_vccp_sense(1)" )
			)
			( pin "U5D1.BL16"
				( objectStatus "@baseboard_fab2_lib.baseboard_fab2(sch_1):page39_i127:cd_vss_vcc_core_sense" )
			)
			( pin "U5D1.EF83"
				( objectStatus "@baseboard_fab2_lib.baseboard_fab2(sch_1):page39_i127:rsvd(0)" )
			)
			( pin "U5D1.EF81"
				( objectStatus "@baseboard_fab2_lib.baseboard_fab2(sch_1):page39_i127:rsvd(1)" )
			)
			( pin "U5D1.EF77"
				( objectStatus "@baseboard_fab2_lib.baseboard_fab2(sch_1):page39_i127:rsvd(2)" )
			)
			( pin "U5D1.EF47"
				( objectStatus "@baseboard_fab2_lib.baseboard_fab2(sch_1):page39_i127:rsvd(3)" )
			)
			( pin "U5D1.EE84"
				( objectStatus "@baseboard_fab2_lib.baseboard_fab2(sch_1):page39_i127:rsvd(4)" )
			)
			( pin "U5D1.EE82"
				( objectStatus "@baseboard_fab2_lib.baseboard_fab2(sch_1):page39_i127:rsvd(5)" )
			)
			( pin "U5D1.EE6"
				( objectStatus "@baseboard_fab2_lib.baseboard_fab2(sch_1):page39_i127:rsvd(6)" )
			)
			( pin "U5D1.EE46"
				( objectStatus "@baseboard_fab2_lib.baseboard_fab2(sch_1):page39_i127:rsvd(7)" )
			)
			( pin "U5D1.EE16"
				( objectStatus "@baseboard_fab2_lib.baseboard_fab2(sch_1):page39_i127:rsvd(8)" )
			)
			( pin "U5D1.ED83"
				( objectStatus "@baseboard_fab2_lib.baseboard_fab2(sch_1):page39_i127:rsvd(9)" )
			)
			( pin "U5D1.ED5"
				( objectStatus "@baseboard_fab2_lib.baseboard_fab2(sch_1):page39_i127:rsvd(10)" )
			)
			( pin "U5D1.ED45"
				( objectStatus "@baseboard_fab2_lib.baseboard_fab2(sch_1):page39_i127:rsvd(11)" )
			)
			( pin "U5D1.EC84"
				( objectStatus "@baseboard_fab2_lib.baseboard_fab2(sch_1):page39_i127:rsvd(12)" )
			)
			( pin "U5D1.EC44"
				( objectStatus "@baseboard_fab2_lib.baseboard_fab2(sch_1):page39_i127:rsvd(13)" )
			)
			( pin "U5D1.EC4"
				( objectStatus "@baseboard_fab2_lib.baseboard_fab2(sch_1):page39_i127:rsvd(14)" )
			)
			( pin "U5D1.EC16"
				( objectStatus "@baseboard_fab2_lib.baseboard_fab2(sch_1):page39_i127:rsvd(15)" )
			)
			( pin "U5D1.EB85"
				( objectStatus "@baseboard_fab2_lib.baseboard_fab2(sch_1):page39_i127:rsvd(16)" )
			)
			( pin "U5D1.EB5"
				( objectStatus "@baseboard_fab2_lib.baseboard_fab2(sch_1):page39_i127:rsvd(17)" )
			)
			( pin "U5D1.EB3"
				( objectStatus "@baseboard_fab2_lib.baseboard_fab2(sch_1):page39_i127:rsvd(18)" )
			)
			( pin "U5D1.EA44"
				( objectStatus "@baseboard_fab2_lib.baseboard_fab2(sch_1):page39_i127:rsvd(19)" )
			)
			( pin "U5D1.EA4"
				( objectStatus "@baseboard_fab2_lib.baseboard_fab2(sch_1):page39_i127:rsvd(20)" )
			)
			( pin "U5D1.DY3"
				( objectStatus "@baseboard_fab2_lib.baseboard_fab2(sch_1):page39_i127:rsvd(21)" )
			)
			( pin "U5D1.DW46"
				( objectStatus "@baseboard_fab2_lib.baseboard_fab2(sch_1):page39_i127:rsvd(22)" )
			)
			( pin "U5D1.DW44"
				( objectStatus "@baseboard_fab2_lib.baseboard_fab2(sch_1):page39_i127:rsvd(23)" )
			)
			( pin "U5D1.DV71"
				( objectStatus "@baseboard_fab2_lib.baseboard_fab2(sch_1):page39_i127:rsvd(24)" )
			)
			( pin "U5D1.DV61"
				( objectStatus "@baseboard_fab2_lib.baseboard_fab2(sch_1):page39_i127:rsvd(25)" )
			)
			( pin "U5D1.DU44"
				( objectStatus "@baseboard_fab2_lib.baseboard_fab2(sch_1):page39_i127:rsvd(26)" )
			)
			( pin "U5D1.DT71"
				( objectStatus "@baseboard_fab2_lib.baseboard_fab2(sch_1):page39_i127:rsvd(27)" )
			)
			( pin "U5D1.DR44"
				( objectStatus "@baseboard_fab2_lib.baseboard_fab2(sch_1):page39_i127:rsvd(28)" )
			)
			( pin "U5D1.DP65"
				( objectStatus "@baseboard_fab2_lib.baseboard_fab2(sch_1):page39_i127:rsvd(29)" )
			)
			( pin "U5D1.DP17"
				( objectStatus "@baseboard_fab2_lib.baseboard_fab2(sch_1):page39_i127:rsvd(30)" )
			)
			( pin "U5D1.DN66"
				( objectStatus "@baseboard_fab2_lib.baseboard_fab2(sch_1):page39_i127:rsvd(31)" )
			)
			( pin "U5D1.DN62"
				( objectStatus "@baseboard_fab2_lib.baseboard_fab2(sch_1):page39_i127:rsvd(32)" )
			)
			( pin "U5D1.DM67"
				( objectStatus "@baseboard_fab2_lib.baseboard_fab2(sch_1):page39_i127:rsvd(33)" )
			)
			( pin "U5D1.DL66"
				( objectStatus "@baseboard_fab2_lib.baseboard_fab2(sch_1):page39_i127:rsvd(34)" )
			)
			( pin "U5D1.DL38"
				( objectStatus "@baseboard_fab2_lib.baseboard_fab2(sch_1):page39_i127:rsvd(35)" )
			)
			( pin "U5D1.DK67"
				( objectStatus "@baseboard_fab2_lib.baseboard_fab2(sch_1):page39_i127:rsvd(36)" )
			)
			( pin "U5D1.DK65"
				( objectStatus "@baseboard_fab2_lib.baseboard_fab2(sch_1):page39_i127:rsvd(37)" )
			)
			( pin "U5D1.DK37"
				( objectStatus "@baseboard_fab2_lib.baseboard_fab2(sch_1):page39_i127:rsvd(38)" )
			)
			( pin "U5D1.DK15"
				( objectStatus "@baseboard_fab2_lib.baseboard_fab2(sch_1):page39_i127:rsvd(39)" )
			)
			( pin "U5D1.DJ66"
				( objectStatus "@baseboard_fab2_lib.baseboard_fab2(sch_1):page39_i127:rsvd(40)" )
			)
			( pin "U5D1.DJ36"
				( objectStatus "@baseboard_fab2_lib.baseboard_fab2(sch_1):page39_i127:rsvd(41)" )
			)
			( pin "U5D1.DH65"
				( objectStatus "@baseboard_fab2_lib.baseboard_fab2(sch_1):page39_i127:rsvd(42)" )
			)
			( pin "U5D1.DG64"
				( objectStatus "@baseboard_fab2_lib.baseboard_fab2(sch_1):page39_i127:rsvd(43)" )
			)
			( pin "U5D1.DG36"
				( objectStatus "@baseboard_fab2_lib.baseboard_fab2(sch_1):page39_i127:rsvd(44)" )
			)
			( pin "U5D1.DD51"
				( objectStatus "@baseboard_fab2_lib.baseboard_fab2(sch_1):page39_i127:rsvd(45)" )
			)
			( pin "U5D1.DC52"
				( objectStatus "@baseboard_fab2_lib.baseboard_fab2(sch_1):page39_i127:rsvd(46)" )
			)
			( pin "U5D1.DC46"
				( objectStatus "@baseboard_fab2_lib.baseboard_fab2(sch_1):page39_i127:rsvd(47)" )
			)
			( pin "U5D1.DA56"
				( objectStatus "@baseboard_fab2_lib.baseboard_fab2(sch_1):page39_i127:rsvd(48)" )
			)
			( pin "U5D1.DA54"
				( objectStatus "@baseboard_fab2_lib.baseboard_fab2(sch_1):page39_i127:rsvd(49)" )
			)
			( pin "U5D1.DA52"
				( objectStatus "@baseboard_fab2_lib.baseboard_fab2(sch_1):page39_i127:rsvd(50)" )
			)
			( pin "U5D1.DA40"
				( objectStatus "@baseboard_fab2_lib.baseboard_fab2(sch_1):page39_i127:rsvd(51)" )
			)
			( pin "U5D1.DA24"
				( objectStatus "@baseboard_fab2_lib.baseboard_fab2(sch_1):page39_i127:rsvd(52)" )
			)
			( pin "U5D1.CY73"
				( objectStatus "@baseboard_fab2_lib.baseboard_fab2(sch_1):page39_i127:rsvd(53)" )
			)
			( pin "U5D1.CY63"
				( objectStatus "@baseboard_fab2_lib.baseboard_fab2(sch_1):page39_i127:rsvd(54)" )
			)
			( pin "U5D1.CY57"
				( objectStatus "@baseboard_fab2_lib.baseboard_fab2(sch_1):page39_i127:rsvd(55)" )
			)
			( pin "U5D1.CY53"
				( objectStatus "@baseboard_fab2_lib.baseboard_fab2(sch_1):page39_i127:rsvd(56)" )
			)
			( pin "U5D1.CY39"
				( objectStatus "@baseboard_fab2_lib.baseboard_fab2(sch_1):page39_i127:rsvd(57)" )
			)
			( pin "U5D1.CY25"
				( objectStatus "@baseboard_fab2_lib.baseboard_fab2(sch_1):page39_i127:rsvd(58)" )
			)
			( pin "U5D1.CY23"
				( objectStatus "@baseboard_fab2_lib.baseboard_fab2(sch_1):page39_i127:rsvd(59)" )
			)
			( pin "U5D1.CW62"
				( objectStatus "@baseboard_fab2_lib.baseboard_fab2(sch_1):page39_i127:rsvd(60)" )
			)
			( pin "U5D1.CW60"
				( objectStatus "@baseboard_fab2_lib.baseboard_fab2(sch_1):page39_i127:rsvd(61)" )
			)
			( pin "U5D1.CW24"
				( objectStatus "@baseboard_fab2_lib.baseboard_fab2(sch_1):page39_i127:rsvd(62)" )
			)
			( pin "U5D1.CW22"
				( objectStatus "@baseboard_fab2_lib.baseboard_fab2(sch_1):page39_i127:rsvd(63)" )
			)
			( pin "U5D1.CV69"
				( objectStatus "@baseboard_fab2_lib.baseboard_fab2(sch_1):page39_i127:rsvd(64)" )
			)
			( pin "U5D1.CV23"
				( objectStatus "@baseboard_fab2_lib.baseboard_fab2(sch_1):page39_i127:rsvd(65)" )
			)
			( pin "U5D1.CU60"
				( objectStatus "@baseboard_fab2_lib.baseboard_fab2(sch_1):page39_i127:rsvd(66)" )
			)
			( pin "U5D1.CU6"
				( objectStatus "@baseboard_fab2_lib.baseboard_fab2(sch_1):page39_i127:rsvd(67)" )
			)
			( pin "U5D1.CU24"
				( objectStatus "@baseboard_fab2_lib.baseboard_fab2(sch_1):page39_i127:rsvd(68)" )
			)
			( pin "U5D1.CT69"
				( objectStatus "@baseboard_fab2_lib.baseboard_fab2(sch_1):page39_i127:rsvd(69)" )
			)
			( pin "U5D1.CT5"
				( objectStatus "@baseboard_fab2_lib.baseboard_fab2(sch_1):page39_i127:rsvd(70)" )
			)
			( pin "U5D1.CT23"
				( objectStatus "@baseboard_fab2_lib.baseboard_fab2(sch_1):page39_i127:rsvd(71)" )
			)
			( pin "U5D1.CR60"
				( objectStatus "@baseboard_fab2_lib.baseboard_fab2(sch_1):page39_i127:rsvd(72)" )
			)
			( pin "U5D1.CP31"
				( objectStatus "@baseboard_fab2_lib.baseboard_fab2(sch_1):page39_i127:rsvd(73)" )
			)
			( pin "U5D1.CP23"
				( objectStatus "@baseboard_fab2_lib.baseboard_fab2(sch_1):page39_i127:rsvd(74)" )
			)
			( pin "U5D1.CN28"
				( objectStatus "@baseboard_fab2_lib.baseboard_fab2(sch_1):page39_i127:rsvd(75)" )
			)
			( pin "U5D1.CN24"
				( objectStatus "@baseboard_fab2_lib.baseboard_fab2(sch_1):page39_i127:rsvd(76)" )
			)
			( pin "U5D1.CN22"
				( objectStatus "@baseboard_fab2_lib.baseboard_fab2(sch_1):page39_i127:rsvd(77)" )
			)
			( pin "U5D1.CM25"
				( objectStatus "@baseboard_fab2_lib.baseboard_fab2(sch_1):page39_i127:rsvd(78)" )
			)
			( pin "U5D1.CM23"
				( objectStatus "@baseboard_fab2_lib.baseboard_fab2(sch_1):page39_i127:rsvd(79)" )
			)
			( pin "U5D1.CL26"
				( objectStatus "@baseboard_fab2_lib.baseboard_fab2(sch_1):page39_i127:rsvd(80)" )
			)
			( pin "U5D1.EE10"
				( objectStatus "@baseboard_fab2_lib.baseboard_fab2(sch_1):page39_i127:vccio(0)" )
			)
			( pin "U5D1.AE10"
				( objectStatus "@baseboard_fab2_lib.baseboard_fab2(sch_1):page39_i127:vccio(1)" )
			)
			( pin "U5D1.AF5"
				( objectStatus "@baseboard_fab2_lib.baseboard_fab2(sch_1):page39_i127:vccio(2)" )
			)
			( pin "U5D1.DV11"
				( objectStatus "@baseboard_fab2_lib.baseboard_fab2(sch_1):page39_i127:vccio(3)" )
			)
			( pin "U5D1.AM5"
				( objectStatus "@baseboard_fab2_lib.baseboard_fab2(sch_1):page39_i127:vccio(4)" )
			)
			( pin "U5D1.AT5"
				( objectStatus "@baseboard_fab2_lib.baseboard_fab2(sch_1):page39_i127:vccio(5)" )
			)
			( pin "U5D1.AT7"
				( objectStatus "@baseboard_fab2_lib.baseboard_fab2(sch_1):page39_i127:vccio(6)" )
			)
			( pin "U5D1.BE24"
				( objectStatus "@baseboard_fab2_lib.baseboard_fab2(sch_1):page39_i127:vccio(7)" )
			)
			( pin "U5D1.DK21"
				( objectStatus "@baseboard_fab2_lib.baseboard_fab2(sch_1):page39_i127:vccio(8)" )
			)
			( pin "U5D1.CF5"
				( objectStatus "@baseboard_fab2_lib.baseboard_fab2(sch_1):page39_i127:vccio(9)" )
			)
			( pin "U5D1.CG14"
				( objectStatus "@baseboard_fab2_lib.baseboard_fab2(sch_1):page39_i127:vccio(10)" )
			)
			( pin "U5D1.CL20"
				( objectStatus "@baseboard_fab2_lib.baseboard_fab2(sch_1):page39_i127:vccio(11)" )
			)
			( pin "U5D1.CP13"
				( objectStatus "@baseboard_fab2_lib.baseboard_fab2(sch_1):page39_i127:vccio(12)" )
			)
			( pin "U5D1.DE14"
				( objectStatus "@baseboard_fab2_lib.baseboard_fab2(sch_1):page39_i127:vccio(13)" )
			)
			( pin "U5D1.DC18"
				( objectStatus "@baseboard_fab2_lib.baseboard_fab2(sch_1):page39_i127:vccio(14)" )
			)
			( pin "U5D1.CY17"
				( objectStatus "@baseboard_fab2_lib.baseboard_fab2(sch_1):page39_i127:vccio(15)" )
			)
			( pin "U5D1.CU18"
				( objectStatus "@baseboard_fab2_lib.baseboard_fab2(sch_1):page39_i127:vccio(16)" )
			)
			( pin "U5D1.CV21"
				( objectStatus "@baseboard_fab2_lib.baseboard_fab2(sch_1):page39_i127:vccio(17)" )
			)
			( pin "U5D1.CU12"
				( objectStatus "@baseboard_fab2_lib.baseboard_fab2(sch_1):page39_i127:vccio(18)" )
			)
			( pin "U5D1.CN6"
				( objectStatus "@baseboard_fab2_lib.baseboard_fab2(sch_1):page39_i127:vccio(19)" )
			)
			( pin "U5D1.BH5"
				( objectStatus "@baseboard_fab2_lib.baseboard_fab2(sch_1):page39_i127:vccio_sense" )
			)
			( pin "U5D1.CE76"
				( objectStatus "@baseboard_fab2_lib.baseboard_fab2(sch_1):page39_i127:vccsa_sense" )
			)
			( pin "U5D1.BF5"
				( objectStatus "@baseboard_fab2_lib.baseboard_fab2(sch_1):page39_i127:vss_vccio_sense" )
			)
			( pin "U5D1.CG76"
				( objectStatus "@baseboard_fab2_lib.baseboard_fab2(sch_1):page39_i127:vss_vccsa_sense" )
			)
			( pin "U5D1.J74"
				( objectStatus "@baseboard_fab2_lib.baseboard_fab2(sch_1):page40_i20:vss(1094)" )
			)
			( pin "U5D1.J72"
				( objectStatus "@baseboard_fab2_lib.baseboard_fab2(sch_1):page40_i20:vss(1095)" )
			)
			( pin "U5D1.J40"
				( objectStatus "@baseboard_fab2_lib.baseboard_fab2(sch_1):page40_i20:vss(1096)" )
			)
			( pin "U5D1.J38"
				( objectStatus "@baseboard_fab2_lib.baseboard_fab2(sch_1):page40_i20:vss(1097)" )
			)
			( pin "U5D1.J34"
				( objectStatus "@baseboard_fab2_lib.baseboard_fab2(sch_1):page40_i20:vss(1098)" )
			)
			( pin "U5D1.J32"
				( objectStatus "@baseboard_fab2_lib.baseboard_fab2(sch_1):page40_i20:vss(1099)" )
			)
			( pin "U5D1.J28"
				( objectStatus "@baseboard_fab2_lib.baseboard_fab2(sch_1):page40_i20:vss(1100)" )
			)
			( pin "U5D1.J26"
				( objectStatus "@baseboard_fab2_lib.baseboard_fab2(sch_1):page40_i20:vss(1101)" )
			)
			( pin "U5D1.J22"
				( objectStatus "@baseboard_fab2_lib.baseboard_fab2(sch_1):page40_i20:vss(1102)" )
			)
			( pin "U5D1.J14"
				( objectStatus "@baseboard_fab2_lib.baseboard_fab2(sch_1):page40_i20:vss(1103)" )
			)
			( pin "U5D1.J12"
				( objectStatus "@baseboard_fab2_lib.baseboard_fab2(sch_1):page40_i20:vss(1104)" )
			)
			( pin "U5D1.J4"
				( objectStatus "@baseboard_fab2_lib.baseboard_fab2(sch_1):page40_i20:vss(1105)" )
			)
			( pin "U5D1.DN44"
				( objectStatus "@baseboard_fab2_lib.baseboard_fab2(sch_1):page40_i20:vss(1106)" )
			)
			( pin "U5D1.H75"
				( objectStatus "@baseboard_fab2_lib.baseboard_fab2(sch_1):page40_i20:vss(1107)" )
			)
			( pin "U5D1.H71"
				( objectStatus "@baseboard_fab2_lib.baseboard_fab2(sch_1):page40_i20:vss(1108)" )
			)
			( pin "U5D1.H65"
				( objectStatus "@baseboard_fab2_lib.baseboard_fab2(sch_1):page40_i20:vss(1109)" )
			)
			( pin "U5D1.H41"
				( objectStatus "@baseboard_fab2_lib.baseboard_fab2(sch_1):page40_i20:vss(1110)" )
			)
			( pin "U5D1.H39"
				( objectStatus "@baseboard_fab2_lib.baseboard_fab2(sch_1):page40_i20:vss(1111)" )
			)
			( pin "U5D1.H37"
				( objectStatus "@baseboard_fab2_lib.baseboard_fab2(sch_1):page40_i20:vss(1112)" )
			)
			( pin "U5D1.H35"
				( objectStatus "@baseboard_fab2_lib.baseboard_fab2(sch_1):page40_i20:vss(1113)" )
			)
			( pin "U5D1.H33"
				( objectStatus "@baseboard_fab2_lib.baseboard_fab2(sch_1):page40_i20:vss(1114)" )
			)
			( pin "U5D1.H31"
				( objectStatus "@baseboard_fab2_lib.baseboard_fab2(sch_1):page40_i20:vss(1115)" )
			)
			( pin "U5D1.H29"
				( objectStatus "@baseboard_fab2_lib.baseboard_fab2(sch_1):page40_i20:vss(1116)" )
			)
			( pin "U5D1.H27"
				( objectStatus "@baseboard_fab2_lib.baseboard_fab2(sch_1):page40_i20:vss(1117)" )
			)
			( pin "U5D1.H25"
				( objectStatus "@baseboard_fab2_lib.baseboard_fab2(sch_1):page40_i20:vss(1118)" )
			)
			( pin "U5D1.H11"
				( objectStatus "@baseboard_fab2_lib.baseboard_fab2(sch_1):page40_i20:vss(1119)" )
			)
			( pin "U5D1.H3"
				( objectStatus "@baseboard_fab2_lib.baseboard_fab2(sch_1):page40_i20:vss(1120)" )
			)
			( pin "U5D1.G82"
				( objectStatus "@baseboard_fab2_lib.baseboard_fab2(sch_1):page40_i20:vss(1121)" )
			)
			( pin "U5D1.G80"
				( objectStatus "@baseboard_fab2_lib.baseboard_fab2(sch_1):page40_i20:vss(1122)" )
			)
			( pin "U5D1.G78"
				( objectStatus "@baseboard_fab2_lib.baseboard_fab2(sch_1):page40_i20:vss(1123)" )
			)
			( pin "U5D1.G76"
				( objectStatus "@baseboard_fab2_lib.baseboard_fab2(sch_1):page40_i20:vss(1124)" )
			)
			( pin "U5D1.G70"
				( objectStatus "@baseboard_fab2_lib.baseboard_fab2(sch_1):page40_i20:vss(1125)" )
			)
			( pin "U5D1.G66"
				( objectStatus "@baseboard_fab2_lib.baseboard_fab2(sch_1):page40_i20:vss(1126)" )
			)
			( pin "U5D1.G42"
				( objectStatus "@baseboard_fab2_lib.baseboard_fab2(sch_1):page40_i20:vss(1127)" )
			)
			( pin "U5D1.G38"
				( objectStatus "@baseboard_fab2_lib.baseboard_fab2(sch_1):page40_i20:vss(1128)" )
			)
			( pin "U5D1.G36"
				( objectStatus "@baseboard_fab2_lib.baseboard_fab2(sch_1):page40_i20:vss(1129)" )
			)
			( pin "U5D1.G32"
				( objectStatus "@baseboard_fab2_lib.baseboard_fab2(sch_1):page40_i20:vss(1130)" )
			)
			( pin "U5D1.G30"
				( objectStatus "@baseboard_fab2_lib.baseboard_fab2(sch_1):page40_i20:vss(1131)" )
			)
			( pin "U5D1.G26"
				( objectStatus "@baseboard_fab2_lib.baseboard_fab2(sch_1):page40_i20:vss(1132)" )
			)
			( pin "U5D1.G24"
				( objectStatus "@baseboard_fab2_lib.baseboard_fab2(sch_1):page40_i20:vss(1133)" )
			)
			( pin "U5D1.G22"
				( objectStatus "@baseboard_fab2_lib.baseboard_fab2(sch_1):page40_i20:vss(1134)" )
			)
			( pin "U5D1.G8"
				( objectStatus "@baseboard_fab2_lib.baseboard_fab2(sch_1):page40_i20:vss(1135)" )
			)
			( pin "U5D1.G4"
				( objectStatus "@baseboard_fab2_lib.baseboard_fab2(sch_1):page40_i20:vss(1136)" )
			)
			( pin "U5D1.F69"
				( objectStatus "@baseboard_fab2_lib.baseboard_fab2(sch_1):page40_i20:vss(1137)" )
			)
			( pin "U5D1.F67"
				( objectStatus "@baseboard_fab2_lib.baseboard_fab2(sch_1):page40_i20:vss(1138)" )
			)
			( pin "U5D1.F43"
				( objectStatus "@baseboard_fab2_lib.baseboard_fab2(sch_1):page40_i20:vss(1139)" )
			)
			( pin "U5D1.F37"
				( objectStatus "@baseboard_fab2_lib.baseboard_fab2(sch_1):page40_i20:vss(1140)" )
			)
			( pin "U5D1.F31"
				( objectStatus "@baseboard_fab2_lib.baseboard_fab2(sch_1):page40_i20:vss(1141)" )
			)
			( pin "U5D1.F25"
				( objectStatus "@baseboard_fab2_lib.baseboard_fab2(sch_1):page40_i20:vss(1142)" )
			)
			( pin "U5D1.F19"
				( objectStatus "@baseboard_fab2_lib.baseboard_fab2(sch_1):page40_i20:vss(1143)" )
			)
			( pin "U5D1.F17"
				( objectStatus "@baseboard_fab2_lib.baseboard_fab2(sch_1):page40_i20:vss(1144)" )
			)
			( pin "U5D1.F5"
				( objectStatus "@baseboard_fab2_lib.baseboard_fab2(sch_1):page40_i20:vss(1145)" )
			)
			( pin "U5D1.E76"
				( objectStatus "@baseboard_fab2_lib.baseboard_fab2(sch_1):page40_i20:vss(1146)" )
			)
			( pin "U5D1.E74"
				( objectStatus "@baseboard_fab2_lib.baseboard_fab2(sch_1):page40_i20:vss(1147)" )
			)
			( pin "U5D1.E72"
				( objectStatus "@baseboard_fab2_lib.baseboard_fab2(sch_1):page40_i20:vss(1148)" )
			)
			( pin "U5D1.E22"
				( objectStatus "@baseboard_fab2_lib.baseboard_fab2(sch_1):page40_i20:vss(1149)" )
			)
			( pin "U5D1.E20"
				( objectStatus "@baseboard_fab2_lib.baseboard_fab2(sch_1):page40_i20:vss(1150)" )
			)
			( pin "U5D1.E18"
				( objectStatus "@baseboard_fab2_lib.baseboard_fab2(sch_1):page40_i20:vss(1151)" )
			)
			( pin "U5D1.E16"
				( objectStatus "@baseboard_fab2_lib.baseboard_fab2(sch_1):page40_i20:vss(1152)" )
			)
			( pin "U5D1.E8"
				( objectStatus "@baseboard_fab2_lib.baseboard_fab2(sch_1):page40_i20:vss(1153)" )
			)
			( pin "U5D1.E6"
				( objectStatus "@baseboard_fab2_lib.baseboard_fab2(sch_1):page40_i20:vss(1154)" )
			)
			( pin "U5D1.D77"
				( objectStatus "@baseboard_fab2_lib.baseboard_fab2(sch_1):page40_i20:vss(1155)" )
			)
			( pin "U5D1.D43"
				( objectStatus "@baseboard_fab2_lib.baseboard_fab2(sch_1):page40_i20:vss(1156)" )
			)
			( pin "U5D1.D41"
				( objectStatus "@baseboard_fab2_lib.baseboard_fab2(sch_1):page40_i20:vss(1157)" )
			)
			( pin "U5D1.D39"
				( objectStatus "@baseboard_fab2_lib.baseboard_fab2(sch_1):page40_i20:vss(1158)" )
			)
			( pin "U5D1.D37"
				( objectStatus "@baseboard_fab2_lib.baseboard_fab2(sch_1):page40_i20:vss(1159)" )
			)
			( pin "U5D1.D35"
				( objectStatus "@baseboard_fab2_lib.baseboard_fab2(sch_1):page40_i20:vss(1160)" )
			)
			( pin "U5D1.D33"
				( objectStatus "@baseboard_fab2_lib.baseboard_fab2(sch_1):page40_i20:vss(1161)" )
			)
			( pin "U5D1.D31"
				( objectStatus "@baseboard_fab2_lib.baseboard_fab2(sch_1):page40_i20:vss(1162)" )
			)
			( pin "U5D1.D29"
				( objectStatus "@baseboard_fab2_lib.baseboard_fab2(sch_1):page40_i20:vss(1163)" )
			)
			( pin "U5D1.D27"
				( objectStatus "@baseboard_fab2_lib.baseboard_fab2(sch_1):page40_i20:vss(1164)" )
			)
			( pin "U5D1.D25"
				( objectStatus "@baseboard_fab2_lib.baseboard_fab2(sch_1):page40_i20:vss(1165)" )
			)
			( pin "U5D1.D13"
				( objectStatus "@baseboard_fab2_lib.baseboard_fab2(sch_1):page40_i20:vss(1166)" )
			)
			( pin "U5D1.D11"
				( objectStatus "@baseboard_fab2_lib.baseboard_fab2(sch_1):page40_i20:vss(1167)" )
			)
			( pin "U5D1.CM27"
				( objectStatus "@baseboard_fab2_lib.baseboard_fab2(sch_1):page40_i20:vss(1168)" )
			)
			( pin "U5D1.C78"
				( objectStatus "@baseboard_fab2_lib.baseboard_fab2(sch_1):page40_i20:vss(1169)" )
			)
			( pin "U5D1.C76"
				( objectStatus "@baseboard_fab2_lib.baseboard_fab2(sch_1):page40_i20:vss(1170)" )
			)
			( pin "U5D1.C16"
				( objectStatus "@baseboard_fab2_lib.baseboard_fab2(sch_1):page40_i20:vss(1171)" )
			)
			( pin "U5D1.C14"
				( objectStatus "@baseboard_fab2_lib.baseboard_fab2(sch_1):page40_i20:vss(1172)" )
			)
			( pin "U5D1.C12"
				( objectStatus "@baseboard_fab2_lib.baseboard_fab2(sch_1):page40_i20:vss(1173)" )
			)
			( pin "U5D1.C10"
				( objectStatus "@baseboard_fab2_lib.baseboard_fab2(sch_1):page40_i20:vss(1174)" )
			)
			( pin "U5D1.C8"
				( objectStatus "@baseboard_fab2_lib.baseboard_fab2(sch_1):page40_i20:vss(1175)" )
			)
			( pin "U5D1.B75"
				( objectStatus "@baseboard_fab2_lib.baseboard_fab2(sch_1):page40_i20:vss(1176)" )
			)
			( pin "U5D1.B71"
				( objectStatus "@baseboard_fab2_lib.baseboard_fab2(sch_1):page40_i20:vss(1177)" )
			)
			( pin "U5D1.B37"
				( objectStatus "@baseboard_fab2_lib.baseboard_fab2(sch_1):page40_i20:vss(1178)" )
			)
			( pin "U5D1.B31"
				( objectStatus "@baseboard_fab2_lib.baseboard_fab2(sch_1):page40_i20:vss(1179)" )
			)
			( pin "U5D1.B25"
				( objectStatus "@baseboard_fab2_lib.baseboard_fab2(sch_1):page40_i20:vss(1180)" )
			)
			( pin "U5D1.A38"
				( objectStatus "@baseboard_fab2_lib.baseboard_fab2(sch_1):page40_i20:vss(1181)" )
			)
			( pin "U5D1.A36"
				( objectStatus "@baseboard_fab2_lib.baseboard_fab2(sch_1):page40_i20:vss(1182)" )
			)
			( pin "U5D1.A32"
				( objectStatus "@baseboard_fab2_lib.baseboard_fab2(sch_1):page40_i20:vss(1183)" )
			)
			( pin "U5D1.A30"
				( objectStatus "@baseboard_fab2_lib.baseboard_fab2(sch_1):page40_i20:vss(1184)" )
			)
			( pin "U5D1.A26"
				( objectStatus "@baseboard_fab2_lib.baseboard_fab2(sch_1):page40_i20:vss(1185)" )
			)
			( pin "U5D1.AC58"
				( objectStatus "@baseboard_fab2_lib.baseboard_fab2(sch_1):page40_i20:vss(1186)" )
			)
			( pin "U5D1.AC60"
				( objectStatus "@baseboard_fab2_lib.baseboard_fab2(sch_1):page40_i20:vss(1187)" )
			)
			( pin "U5D1.AC62"
				( objectStatus "@baseboard_fab2_lib.baseboard_fab2(sch_1):page40_i20:vss(1188)" )
			)
			( pin "U5D1.AJ4"
				( objectStatus "@baseboard_fab2_lib.baseboard_fab2(sch_1):page40_i20:vss(1189)" )
			)
			( pin "U5D1.AR6"
				( objectStatus "@baseboard_fab2_lib.baseboard_fab2(sch_1):page40_i20:vss(1190)" )
			)
			( pin "U5D1.CG6"
				( objectStatus "@baseboard_fab2_lib.baseboard_fab2(sch_1):page40_i20:vss(1191)" )
			)
			( pin "U5D1.CW6"
				( objectStatus "@baseboard_fab2_lib.baseboard_fab2(sch_1):page40_i20:vss(1192)" )
			)
			( pin "U5D1.DE48"
				( objectStatus "@baseboard_fab2_lib.baseboard_fab2(sch_1):page40_i20:vss(1193)" )
			)
			( pin "U5D1.DE50"
				( objectStatus "@baseboard_fab2_lib.baseboard_fab2(sch_1):page40_i20:vss(1194)" )
			)
			( pin "U5D1.DE52"
				( objectStatus "@baseboard_fab2_lib.baseboard_fab2(sch_1):page40_i20:vss(1195)" )
			)
			( pin "U5D1.DE54"
				( objectStatus "@baseboard_fab2_lib.baseboard_fab2(sch_1):page40_i20:vss(1196)" )
			)
			( pin "U5D1.DE56"
				( objectStatus "@baseboard_fab2_lib.baseboard_fab2(sch_1):page40_i20:vss(1197)" )
			)
			( pin "U5D1.DE58"
				( objectStatus "@baseboard_fab2_lib.baseboard_fab2(sch_1):page40_i20:vss(1198)" )
			)
			( pin "U5D1.DE60"
				( objectStatus "@baseboard_fab2_lib.baseboard_fab2(sch_1):page40_i20:vss(1199)" )
			)
			( pin "U5D1.DE62"
				( objectStatus "@baseboard_fab2_lib.baseboard_fab2(sch_1):page40_i20:vss(1200)" )
			)
			( pin "U5D1.DL8"
				( objectStatus "@baseboard_fab2_lib.baseboard_fab2(sch_1):page40_i20:vss(1201)" )
			)
			( pin "U5D1.DN18"
				( objectStatus "@baseboard_fab2_lib.baseboard_fab2(sch_1):page40_i20:vss(1202)" )
			)
			( pin "U5D1.DP45"
				( objectStatus "@baseboard_fab2_lib.baseboard_fab2(sch_1):page40_i20:vss(1203)" )
			)
			( pin "U5D1.DP47"
				( objectStatus "@baseboard_fab2_lib.baseboard_fab2(sch_1):page40_i20:vss(1204)" )
			)
			( pin "U5D1.DP49"
				( objectStatus "@baseboard_fab2_lib.baseboard_fab2(sch_1):page40_i20:vss(1205)" )
			)
			( pin "U5D1.DP51"
				( objectStatus "@baseboard_fab2_lib.baseboard_fab2(sch_1):page40_i20:vss(1206)" )
			)
			( pin "U5D1.DP53"
				( objectStatus "@baseboard_fab2_lib.baseboard_fab2(sch_1):page40_i20:vss(1207)" )
			)
			( pin "U5D1.DP55"
				( objectStatus "@baseboard_fab2_lib.baseboard_fab2(sch_1):page40_i20:vss(1208)" )
			)
			( pin "U5D1.DP57"
				( objectStatus "@baseboard_fab2_lib.baseboard_fab2(sch_1):page40_i20:vss(1209)" )
			)
			( pin "U5D1.DP59"
				( objectStatus "@baseboard_fab2_lib.baseboard_fab2(sch_1):page40_i20:vss(1210)" )
			)
			( pin "U5D1.DP61"
				( objectStatus "@baseboard_fab2_lib.baseboard_fab2(sch_1):page40_i20:vss(1211)" )
			)
			( pin "U5D1.DP63"
				( objectStatus "@baseboard_fab2_lib.baseboard_fab2(sch_1):page40_i20:vss(1212)" )
			)
			( pin "U5D1.DP9"
				( objectStatus "@baseboard_fab2_lib.baseboard_fab2(sch_1):page40_i20:vss(1213)" )
			)
			( pin "U5D1.DV19"
				( objectStatus "@baseboard_fab2_lib.baseboard_fab2(sch_1):page40_i20:vss(1214)" )
			)
			( pin "U5D1.DY45"
				( objectStatus "@baseboard_fab2_lib.baseboard_fab2(sch_1):page40_i20:vss(1215)" )
			)
			( pin "U5D1.DY47"
				( objectStatus "@baseboard_fab2_lib.baseboard_fab2(sch_1):page40_i20:vss(1216)" )
			)
			( pin "U5D1.DY49"
				( objectStatus "@baseboard_fab2_lib.baseboard_fab2(sch_1):page40_i20:vss(1217)" )
			)
			( pin "U5D1.DY51"
				( objectStatus "@baseboard_fab2_lib.baseboard_fab2(sch_1):page40_i20:vss(1218)" )
			)
			( pin "U5D1.DY53"
				( objectStatus "@baseboard_fab2_lib.baseboard_fab2(sch_1):page40_i20:vss(1219)" )
			)
			( pin "U5D1.DY55"
				( objectStatus "@baseboard_fab2_lib.baseboard_fab2(sch_1):page40_i20:vss(1220)" )
			)
			( pin "U5D1.DY57"
				( objectStatus "@baseboard_fab2_lib.baseboard_fab2(sch_1):page40_i20:vss(1221)" )
			)
			( pin "U5D1.DY59"
				( objectStatus "@baseboard_fab2_lib.baseboard_fab2(sch_1):page40_i20:vss(1222)" )
			)
			( pin "U5D1.DY61"
				( objectStatus "@baseboard_fab2_lib.baseboard_fab2(sch_1):page40_i20:vss(1223)" )
			)
			( pin "U5D1.DY63"
				( objectStatus "@baseboard_fab2_lib.baseboard_fab2(sch_1):page40_i20:vss(1224)" )
			)
			( pin "U5D1.EA14"
				( objectStatus "@baseboard_fab2_lib.baseboard_fab2(sch_1):page40_i20:vss(1225)" )
			)
			( pin "U5D1.L8"
				( objectStatus "@baseboard_fab2_lib.baseboard_fab2(sch_1):page40_i20:vss(1226)" )
			)
			( pin "U5D1.V11"
				( objectStatus "@baseboard_fab2_lib.baseboard_fab2(sch_1):page40_i20:vss(1227)" )
			)
			( pin "U5D1.E66"
				( objectStatus "@baseboard_fab2_lib.baseboard_fab2(sch_1):page40_i20:vss(1228)" )
			)
			( pin "U5D1.ED69"
				( objectStatus "@baseboard_fab2_lib.baseboard_fab2(sch_1):page40_i20:vss(1229)" )
			)
			( pin "U5D1.EE80"
				( objectStatus "@baseboard_fab2_lib.baseboard_fab2(sch_1):page40_i20:vss(1230)" )
			)
			( pin "U5D1.EE8"
				( objectStatus "@baseboard_fab2_lib.baseboard_fab2(sch_1):page40_i20:vss(1231)" )
			)
			( pin "U5D1.EE40"
				( objectStatus "@baseboard_fab2_lib.baseboard_fab2(sch_1):page40_i20:vss(1232)" )
			)
			( pin "U5D1.ED81"
				( objectStatus "@baseboard_fab2_lib.baseboard_fab2(sch_1):page40_i20:vss(1233)" )
			)
			( pin "U5D1.ED7"
				( objectStatus "@baseboard_fab2_lib.baseboard_fab2(sch_1):page40_i20:vss(1234)" )
			)
			( pin "U5D1.ED41"
				( objectStatus "@baseboard_fab2_lib.baseboard_fab2(sch_1):page40_i20:vss(1235)" )
			)
			( pin "U5D1.EC82"
				( objectStatus "@baseboard_fab2_lib.baseboard_fab2(sch_1):page40_i20:vss(1236)" )
			)
			( pin "U5D1.EC6"
				( objectStatus "@baseboard_fab2_lib.baseboard_fab2(sch_1):page40_i20:vss(1237)" )
			)
			( pin "U5D1.EC42"
				( objectStatus "@baseboard_fab2_lib.baseboard_fab2(sch_1):page40_i20:vss(1238)" )
			)
			( pin "U5D1.DW2"
				( objectStatus "@baseboard_fab2_lib.baseboard_fab2(sch_1):page40_i20:vss(1239)" )
			)
			( pin "U5D1.EB83"
				( objectStatus "@baseboard_fab2_lib.baseboard_fab2(sch_1):page40_i20:vss(1240)" )
			)
			( pin "U5D1.EA84"
				( objectStatus "@baseboard_fab2_lib.baseboard_fab2(sch_1):page40_i20:vss(1241)" )
			)
			( pin "U5D1.DY85"
				( objectStatus "@baseboard_fab2_lib.baseboard_fab2(sch_1):page40_i20:vss(1242)" )
			)
			( pin "U5D1.J86"
				( objectStatus "@baseboard_fab2_lib.baseboard_fab2(sch_1):page40_i20:vss(1243)" )
			)
			( pin "U5D1.E82"
				( objectStatus "@baseboard_fab2_lib.baseboard_fab2(sch_1):page40_i20:vss(1244)" )
			)
			( pin "U5D1.D81"
				( objectStatus "@baseboard_fab2_lib.baseboard_fab2(sch_1):page40_i20:vss(1245)" )
			)
			( pin "U5D1.D3"
				( objectStatus "@baseboard_fab2_lib.baseboard_fab2(sch_1):page40_i20:vss(1246)" )
			)
			( pin "U5D1.C80"
				( objectStatus "@baseboard_fab2_lib.baseboard_fab2(sch_1):page40_i20:vss(1247)" )
			)
			( pin "U5D1.C4"
				( objectStatus "@baseboard_fab2_lib.baseboard_fab2(sch_1):page40_i20:vss(1248)" )
			)
			( pin "U5D1.B79"
				( objectStatus "@baseboard_fab2_lib.baseboard_fab2(sch_1):page40_i20:vss(1249)" )
			)
			( pin "U5D1.B5"
				( objectStatus "@baseboard_fab2_lib.baseboard_fab2(sch_1):page40_i20:vss(1250)" )
			)
			( pin "U5D1.B43"
				( objectStatus "@baseboard_fab2_lib.baseboard_fab2(sch_1):page40_i20:vss(1251)" )
			)
			( pin "U5D1.A42"
				( objectStatus "@baseboard_fab2_lib.baseboard_fab2(sch_1):page40_i20:vss(1252)" )
			)
			( pin "U5D1.B9"
				( objectStatus "@baseboard_fab2_lib.baseboard_fab2(sch_1):page40_i20:vss(1253)" )
			)
			( pin "U5D1.AA16"
				( objectStatus "@baseboard_fab2_lib.baseboard_fab2(sch_1):page40_i21:vss(934)" )
			)
			( pin "U5D1.AA4"
				( objectStatus "@baseboard_fab2_lib.baseboard_fab2(sch_1):page40_i21:vss(935)" )
			)
			( pin "U5D1.Y85"
				( objectStatus "@baseboard_fab2_lib.baseboard_fab2(sch_1):page40_i21:vss(936)" )
			)
			( pin "U5D1.Y83"
				( objectStatus "@baseboard_fab2_lib.baseboard_fab2(sch_1):page40_i21:vss(937)" )
			)
			( pin "U5D1.Y81"
				( objectStatus "@baseboard_fab2_lib.baseboard_fab2(sch_1):page40_i21:vss(938)" )
			)
			( pin "U5D1.Y79"
				( objectStatus "@baseboard_fab2_lib.baseboard_fab2(sch_1):page40_i21:vss(939)" )
			)
			( pin "U5D1.Y73"
				( objectStatus "@baseboard_fab2_lib.baseboard_fab2(sch_1):page40_i21:vss(940)" )
			)
			( pin "U5D1.Y71"
				( objectStatus "@baseboard_fab2_lib.baseboard_fab2(sch_1):page40_i21:vss(941)" )
			)
			( pin "U5D1.Y9"
				( objectStatus "@baseboard_fab2_lib.baseboard_fab2(sch_1):page40_i21:vss(942)" )
			)
			( pin "U5D1.Y7"
				( objectStatus "@baseboard_fab2_lib.baseboard_fab2(sch_1):page40_i21:vss(943)" )
			)
			( pin "U5D1.Y67"
				( objectStatus "@baseboard_fab2_lib.baseboard_fab2(sch_1):page40_i21:vss(944)" )
			)
			( pin "U5D1.Y5"
				( objectStatus "@baseboard_fab2_lib.baseboard_fab2(sch_1):page40_i21:vss(945)" )
			)
			( pin "U5D1.Y17"
				( objectStatus "@baseboard_fab2_lib.baseboard_fab2(sch_1):page40_i21:vss(946)" )
			)
			( pin "U5D1.Y15"
				( objectStatus "@baseboard_fab2_lib.baseboard_fab2(sch_1):page40_i21:vss(947)" )
			)
			( pin "U5D1.W82"
				( objectStatus "@baseboard_fab2_lib.baseboard_fab2(sch_1):page40_i21:vss(948)" )
			)
			( pin "U5D1.W78"
				( objectStatus "@baseboard_fab2_lib.baseboard_fab2(sch_1):page40_i21:vss(949)" )
			)
			( pin "U5D1.W74"
				( objectStatus "@baseboard_fab2_lib.baseboard_fab2(sch_1):page40_i21:vss(950)" )
			)
			( pin "U5D1.W68"
				( objectStatus "@baseboard_fab2_lib.baseboard_fab2(sch_1):page40_i21:vss(951)" )
			)
			( pin "U5D1.W42"
				( objectStatus "@baseboard_fab2_lib.baseboard_fab2(sch_1):page40_i21:vss(952)" )
			)
			( pin "U5D1.W40"
				( objectStatus "@baseboard_fab2_lib.baseboard_fab2(sch_1):page40_i21:vss(953)" )
			)
			( pin "U5D1.W38"
				( objectStatus "@baseboard_fab2_lib.baseboard_fab2(sch_1):page40_i21:vss(954)" )
			)
			( pin "U5D1.W36"
				( objectStatus "@baseboard_fab2_lib.baseboard_fab2(sch_1):page40_i21:vss(955)" )
			)
			( pin "U5D1.W34"
				( objectStatus "@baseboard_fab2_lib.baseboard_fab2(sch_1):page40_i21:vss(956)" )
			)
			( pin "U5D1.W32"
				( objectStatus "@baseboard_fab2_lib.baseboard_fab2(sch_1):page40_i21:vss(957)" )
			)
			( pin "U5D1.W30"
				( objectStatus "@baseboard_fab2_lib.baseboard_fab2(sch_1):page40_i21:vss(958)" )
			)
			( pin "U5D1.W28"
				( objectStatus "@baseboard_fab2_lib.baseboard_fab2(sch_1):page40_i21:vss(959)" )
			)
			( pin "U5D1.W26"
				( objectStatus "@baseboard_fab2_lib.baseboard_fab2(sch_1):page40_i21:vss(960)" )
			)
			( pin "U5D1.W24"
				( objectStatus "@baseboard_fab2_lib.baseboard_fab2(sch_1):page40_i21:vss(961)" )
			)
			( pin "U5D1.W22"
				( objectStatus "@baseboard_fab2_lib.baseboard_fab2(sch_1):page40_i21:vss(962)" )
			)
			( pin "U5D1.W12"
				( objectStatus "@baseboard_fab2_lib.baseboard_fab2(sch_1):page40_i21:vss(963)" )
			)
			( pin "U5D1.AC56"
				( objectStatus "@baseboard_fab2_lib.baseboard_fab2(sch_1):page40_i21:vss(964)" )
			)
			( pin "U5D1.W8"
				( objectStatus "@baseboard_fab2_lib.baseboard_fab2(sch_1):page40_i21:vss(965)" )
			)
			( pin "U5D1.V83"
				( objectStatus "@baseboard_fab2_lib.baseboard_fab2(sch_1):page40_i21:vss(966)" )
			)
			( pin "U5D1.V77"
				( objectStatus "@baseboard_fab2_lib.baseboard_fab2(sch_1):page40_i21:vss(967)" )
			)
			( pin "U5D1.V75"
				( objectStatus "@baseboard_fab2_lib.baseboard_fab2(sch_1):page40_i21:vss(968)" )
			)
			( pin "U5D1.V73"
				( objectStatus "@baseboard_fab2_lib.baseboard_fab2(sch_1):page40_i21:vss(969)" )
			)
			( pin "U5D1.V43"
				( objectStatus "@baseboard_fab2_lib.baseboard_fab2(sch_1):page40_i21:vss(970)" )
			)
			( pin "U5D1.V23"
				( objectStatus "@baseboard_fab2_lib.baseboard_fab2(sch_1):page40_i21:vss(971)" )
			)
			( pin "U5D1.V21"
				( objectStatus "@baseboard_fab2_lib.baseboard_fab2(sch_1):page40_i21:vss(972)" )
			)
			( pin "U5D1.V15"
				( objectStatus "@baseboard_fab2_lib.baseboard_fab2(sch_1):page40_i21:vss(973)" )
			)
			( pin "U5D1.V13"
				( objectStatus "@baseboard_fab2_lib.baseboard_fab2(sch_1):page40_i21:vss(974)" )
			)
			( pin "U5D1.V9"
				( objectStatus "@baseboard_fab2_lib.baseboard_fab2(sch_1):page40_i21:vss(975)" )
			)
			( pin "U5D1.V5"
				( objectStatus "@baseboard_fab2_lib.baseboard_fab2(sch_1):page40_i21:vss(976)" )
			)
			( pin "U5D1.V1"
				( objectStatus "@baseboard_fab2_lib.baseboard_fab2(sch_1):page40_i21:vss(977)" )
			)
			( pin "U5D1.U86"
				( objectStatus "@baseboard_fab2_lib.baseboard_fab2(sch_1):page40_i21:vss(978)" )
			)
			( pin "U5D1.U80"
				( objectStatus "@baseboard_fab2_lib.baseboard_fab2(sch_1):page40_i21:vss(979)" )
			)
			( pin "U5D1.U78"
				( objectStatus "@baseboard_fab2_lib.baseboard_fab2(sch_1):page40_i21:vss(980)" )
			)
			( pin "U5D1.U76"
				( objectStatus "@baseboard_fab2_lib.baseboard_fab2(sch_1):page40_i21:vss(981)" )
			)
			( pin "U5D1.U74"
				( objectStatus "@baseboard_fab2_lib.baseboard_fab2(sch_1):page40_i21:vss(982)" )
			)
			( pin "U5D1.U70"
				( objectStatus "@baseboard_fab2_lib.baseboard_fab2(sch_1):page40_i21:vss(983)" )
			)
			( pin "U5D1.U68"
				( objectStatus "@baseboard_fab2_lib.baseboard_fab2(sch_1):page40_i21:vss(984)" )
			)
			( pin "U5D1.U42"
				( objectStatus "@baseboard_fab2_lib.baseboard_fab2(sch_1):page40_i21:vss(985)" )
			)
			( pin "U5D1.U36"
				( objectStatus "@baseboard_fab2_lib.baseboard_fab2(sch_1):page40_i21:vss(986)" )
			)
			( pin "U5D1.U30"
				( objectStatus "@baseboard_fab2_lib.baseboard_fab2(sch_1):page40_i21:vss(987)" )
			)
			( pin "U5D1.U24"
				( objectStatus "@baseboard_fab2_lib.baseboard_fab2(sch_1):page40_i21:vss(988)" )
			)
			( pin "U5D1.U22"
				( objectStatus "@baseboard_fab2_lib.baseboard_fab2(sch_1):page40_i21:vss(989)" )
			)
			( pin "U5D1.U20"
				( objectStatus "@baseboard_fab2_lib.baseboard_fab2(sch_1):page40_i21:vss(990)" )
			)
			( pin "U5D1.U6"
				( objectStatus "@baseboard_fab2_lib.baseboard_fab2(sch_1):page40_i21:vss(991)" )
			)
			( pin "U5D1.U4"
				( objectStatus "@baseboard_fab2_lib.baseboard_fab2(sch_1):page40_i21:vss(992)" )
			)
			( pin "U5D1.U2"
				( objectStatus "@baseboard_fab2_lib.baseboard_fab2(sch_1):page40_i21:vss(993)" )
			)
			( pin "U5D1.T85"
				( objectStatus "@baseboard_fab2_lib.baseboard_fab2(sch_1):page40_i21:vss(994)" )
			)
			( pin "U5D1.T83"
				( objectStatus "@baseboard_fab2_lib.baseboard_fab2(sch_1):page40_i21:vss(995)" )
			)
			( pin "U5D1.T77"
				( objectStatus "@baseboard_fab2_lib.baseboard_fab2(sch_1):page40_i21:vss(996)" )
			)
			( pin "U5D1.T73"
				( objectStatus "@baseboard_fab2_lib.baseboard_fab2(sch_1):page40_i21:vss(997)" )
			)
			( pin "U5D1.T65"
				( objectStatus "@baseboard_fab2_lib.baseboard_fab2(sch_1):page40_i21:vss(998)" )
			)
			( pin "U5D1.T41"
				( objectStatus "@baseboard_fab2_lib.baseboard_fab2(sch_1):page40_i21:vss(999)" )
			)
			( pin "U5D1.T37"
				( objectStatus "@baseboard_fab2_lib.baseboard_fab2(sch_1):page40_i21:vss(1000)" )
			)
			( pin "U5D1.T35"
				( objectStatus "@baseboard_fab2_lib.baseboard_fab2(sch_1):page40_i21:vss(1001)" )
			)
			( pin "U5D1.T31"
				( objectStatus "@baseboard_fab2_lib.baseboard_fab2(sch_1):page40_i21:vss(1002)" )
			)
			( pin "U5D1.T29"
				( objectStatus "@baseboard_fab2_lib.baseboard_fab2(sch_1):page40_i21:vss(1003)" )
			)
			( pin "U5D1.T25"
				( objectStatus "@baseboard_fab2_lib.baseboard_fab2(sch_1):page40_i21:vss(1004)" )
			)
			( pin "U5D1.T17"
				( objectStatus "@baseboard_fab2_lib.baseboard_fab2(sch_1):page40_i21:vss(1005)" )
			)
			( pin "U5D1.T13"
				( objectStatus "@baseboard_fab2_lib.baseboard_fab2(sch_1):page40_i21:vss(1006)" )
			)
			( pin "U5D1.R86"
				( objectStatus "@baseboard_fab2_lib.baseboard_fab2(sch_1):page40_i21:vss(1007)" )
			)
			( pin "U5D1.R78"
				( objectStatus "@baseboard_fab2_lib.baseboard_fab2(sch_1):page40_i21:vss(1008)" )
			)
			( pin "U5D1.R72"
				( objectStatus "@baseboard_fab2_lib.baseboard_fab2(sch_1):page40_i21:vss(1009)" )
			)
			( pin "U5D1.R68"
				( objectStatus "@baseboard_fab2_lib.baseboard_fab2(sch_1):page40_i21:vss(1010)" )
			)
			( pin "U5D1.R40"
				( objectStatus "@baseboard_fab2_lib.baseboard_fab2(sch_1):page40_i21:vss(1011)" )
			)
			( pin "U5D1.R38"
				( objectStatus "@baseboard_fab2_lib.baseboard_fab2(sch_1):page40_i21:vss(1012)" )
			)
			( pin "U5D1.R34"
				( objectStatus "@baseboard_fab2_lib.baseboard_fab2(sch_1):page40_i21:vss(1013)" )
			)
			( pin "U5D1.R32"
				( objectStatus "@baseboard_fab2_lib.baseboard_fab2(sch_1):page40_i21:vss(1014)" )
			)
			( pin "U5D1.R28"
				( objectStatus "@baseboard_fab2_lib.baseboard_fab2(sch_1):page40_i21:vss(1015)" )
			)
			( pin "U5D1.R26"
				( objectStatus "@baseboard_fab2_lib.baseboard_fab2(sch_1):page40_i21:vss(1016)" )
			)
			( pin "U5D1.R22"
				( objectStatus "@baseboard_fab2_lib.baseboard_fab2(sch_1):page40_i21:vss(1017)" )
			)
			( pin "U5D1.R4"
				( objectStatus "@baseboard_fab2_lib.baseboard_fab2(sch_1):page40_i21:vss(1018)" )
			)
			( pin "U5D1.R2"
				( objectStatus "@baseboard_fab2_lib.baseboard_fab2(sch_1):page40_i21:vss(1019)" )
			)
			( pin "U5D1.R18"
				( objectStatus "@baseboard_fab2_lib.baseboard_fab2(sch_1):page40_i21:vss(1020)" )
			)
			( pin "U5D1.R14"
				( objectStatus "@baseboard_fab2_lib.baseboard_fab2(sch_1):page40_i21:vss(1021)" )
			)
			( pin "U5D1.P83"
				( objectStatus "@baseboard_fab2_lib.baseboard_fab2(sch_1):page40_i21:vss(1022)" )
			)
			( pin "U5D1.P81"
				( objectStatus "@baseboard_fab2_lib.baseboard_fab2(sch_1):page40_i21:vss(1023)" )
			)
			( pin "U5D1.P71"
				( objectStatus "@baseboard_fab2_lib.baseboard_fab2(sch_1):page40_i21:vss(1024)" )
			)
			( pin "U5D1.P69"
				( objectStatus "@baseboard_fab2_lib.baseboard_fab2(sch_1):page40_i21:vss(1025)" )
			)
			( pin "U5D1.P67"
				( objectStatus "@baseboard_fab2_lib.baseboard_fab2(sch_1):page40_i21:vss(1026)" )
			)
			( pin "U5D1.P39"
				( objectStatus "@baseboard_fab2_lib.baseboard_fab2(sch_1):page40_i21:vss(1027)" )
			)
			( pin "U5D1.P33"
				( objectStatus "@baseboard_fab2_lib.baseboard_fab2(sch_1):page40_i21:vss(1028)" )
			)
			( pin "U5D1.P27"
				( objectStatus "@baseboard_fab2_lib.baseboard_fab2(sch_1):page40_i21:vss(1029)" )
			)
			( pin "U5D1.P15"
				( objectStatus "@baseboard_fab2_lib.baseboard_fab2(sch_1):page40_i21:vss(1030)" )
			)
			( pin "U5D1.P11"
				( objectStatus "@baseboard_fab2_lib.baseboard_fab2(sch_1):page40_i21:vss(1031)" )
			)
			( pin "U5D1.N8"
				( objectStatus "@baseboard_fab2_lib.baseboard_fab2(sch_1):page40_i21:vss(1032)" )
			)
			( pin "U5D1.N4"
				( objectStatus "@baseboard_fab2_lib.baseboard_fab2(sch_1):page40_i21:vss(1033)" )
			)
			( pin "U5D1.N78"
				( objectStatus "@baseboard_fab2_lib.baseboard_fab2(sch_1):page40_i21:vss(1034)" )
			)
			( pin "U5D1.N76"
				( objectStatus "@baseboard_fab2_lib.baseboard_fab2(sch_1):page40_i21:vss(1035)" )
			)
			( pin "U5D1.N74"
				( objectStatus "@baseboard_fab2_lib.baseboard_fab2(sch_1):page40_i21:vss(1036)" )
			)
			( pin "U5D1.N72"
				( objectStatus "@baseboard_fab2_lib.baseboard_fab2(sch_1):page40_i21:vss(1037)" )
			)
			( pin "U5D1.N70"
				( objectStatus "@baseboard_fab2_lib.baseboard_fab2(sch_1):page40_i21:vss(1038)" )
			)
			( pin "U5D1.N66"
				( objectStatus "@baseboard_fab2_lib.baseboard_fab2(sch_1):page40_i21:vss(1039)" )
			)
			( pin "U5D1.N6"
				( objectStatus "@baseboard_fab2_lib.baseboard_fab2(sch_1):page40_i21:vss(1040)" )
			)
			( pin "U5D1.N22"
				( objectStatus "@baseboard_fab2_lib.baseboard_fab2(sch_1):page40_i21:vss(1041)" )
			)
			( pin "U5D1.N20"
				( objectStatus "@baseboard_fab2_lib.baseboard_fab2(sch_1):page40_i21:vss(1042)" )
			)
			( pin "U5D1.DM19"
				( objectStatus "@baseboard_fab2_lib.baseboard_fab2(sch_1):page40_i21:vss(1043)" )
			)
			( pin "U5D1.M85"
				( objectStatus "@baseboard_fab2_lib.baseboard_fab2(sch_1):page40_i21:vss(1044)" )
			)
			( pin "U5D1.M83"
				( objectStatus "@baseboard_fab2_lib.baseboard_fab2(sch_1):page40_i21:vss(1045)" )
			)
			( pin "U5D1.M79"
				( objectStatus "@baseboard_fab2_lib.baseboard_fab2(sch_1):page40_i21:vss(1046)" )
			)
			( pin "U5D1.M71"
				( objectStatus "@baseboard_fab2_lib.baseboard_fab2(sch_1):page40_i21:vss(1047)" )
			)
			( pin "U5D1.M65"
				( objectStatus "@baseboard_fab2_lib.baseboard_fab2(sch_1):page40_i21:vss(1048)" )
			)
			( pin "U5D1.M43"
				( objectStatus "@baseboard_fab2_lib.baseboard_fab2(sch_1):page40_i21:vss(1049)" )
			)
			( pin "U5D1.M41"
				( objectStatus "@baseboard_fab2_lib.baseboard_fab2(sch_1):page40_i21:vss(1050)" )
			)
			( pin "U5D1.M39"
				( objectStatus "@baseboard_fab2_lib.baseboard_fab2(sch_1):page40_i21:vss(1051)" )
			)
			( pin "U5D1.M37"
				( objectStatus "@baseboard_fab2_lib.baseboard_fab2(sch_1):page40_i21:vss(1052)" )
			)
			( pin "U5D1.M35"
				( objectStatus "@baseboard_fab2_lib.baseboard_fab2(sch_1):page40_i21:vss(1053)" )
			)
			( pin "U5D1.M33"
				( objectStatus "@baseboard_fab2_lib.baseboard_fab2(sch_1):page40_i21:vss(1054)" )
			)
			( pin "U5D1.M31"
				( objectStatus "@baseboard_fab2_lib.baseboard_fab2(sch_1):page40_i21:vss(1055)" )
			)
			( pin "U5D1.M29"
				( objectStatus "@baseboard_fab2_lib.baseboard_fab2(sch_1):page40_i21:vss(1056)" )
			)
			( pin "U5D1.M27"
				( objectStatus "@baseboard_fab2_lib.baseboard_fab2(sch_1):page40_i21:vss(1057)" )
			)
			( pin "U5D1.M25"
				( objectStatus "@baseboard_fab2_lib.baseboard_fab2(sch_1):page40_i21:vss(1058)" )
			)
			( pin "U5D1.M23"
				( objectStatus "@baseboard_fab2_lib.baseboard_fab2(sch_1):page40_i21:vss(1059)" )
			)
			( pin "U5D1.M19"
				( objectStatus "@baseboard_fab2_lib.baseboard_fab2(sch_1):page40_i21:vss(1060)" )
			)
			( pin "U5D1.M17"
				( objectStatus "@baseboard_fab2_lib.baseboard_fab2(sch_1):page40_i21:vss(1061)" )
			)
			( pin "U5D1.M15"
				( objectStatus "@baseboard_fab2_lib.baseboard_fab2(sch_1):page40_i21:vss(1062)" )
			)
			( pin "U5D1.CT7"
				( objectStatus "@baseboard_fab2_lib.baseboard_fab2(sch_1):page40_i21:vss(1063)" )
			)
			( pin "U5D1.BT9"
				( objectStatus "@baseboard_fab2_lib.baseboard_fab2(sch_1):page40_i21:vss(1064)" )
			)
			( pin "U5D1.L82"
				( objectStatus "@baseboard_fab2_lib.baseboard_fab2(sch_1):page40_i21:vss(1065)" )
			)
			( pin "U5D1.L80"
				( objectStatus "@baseboard_fab2_lib.baseboard_fab2(sch_1):page40_i21:vss(1066)" )
			)
			( pin "U5D1.L78"
				( objectStatus "@baseboard_fab2_lib.baseboard_fab2(sch_1):page40_i21:vss(1067)" )
			)
			( pin "U5D1.L72"
				( objectStatus "@baseboard_fab2_lib.baseboard_fab2(sch_1):page40_i21:vss(1068)" )
			)
			( pin "U5D1.L22"
				( objectStatus "@baseboard_fab2_lib.baseboard_fab2(sch_1):page40_i21:vss(1069)" )
			)
			( pin "U5D1.L20"
				( objectStatus "@baseboard_fab2_lib.baseboard_fab2(sch_1):page40_i21:vss(1070)" )
			)
			( pin "U5D1.L6"
				( objectStatus "@baseboard_fab2_lib.baseboard_fab2(sch_1):page40_i21:vss(1071)" )
			)
			( pin "U5D1.L2"
				( objectStatus "@baseboard_fab2_lib.baseboard_fab2(sch_1):page40_i21:vss(1072)" )
			)
			( pin "U5D1.L10"
				( objectStatus "@baseboard_fab2_lib.baseboard_fab2(sch_1):page40_i21:vss(1073)" )
			)
			( pin "U5D1.K85"
				( objectStatus "@baseboard_fab2_lib.baseboard_fab2(sch_1):page40_i21:vss(1074)" )
			)
			( pin "U5D1.K83"
				( objectStatus "@baseboard_fab2_lib.baseboard_fab2(sch_1):page40_i21:vss(1075)" )
			)
			( pin "U5D1.K81"
				( objectStatus "@baseboard_fab2_lib.baseboard_fab2(sch_1):page40_i21:vss(1076)" )
			)
			( pin "U5D1.K77"
				( objectStatus "@baseboard_fab2_lib.baseboard_fab2(sch_1):page40_i21:vss(1077)" )
			)
			( pin "U5D1.K73"
				( objectStatus "@baseboard_fab2_lib.baseboard_fab2(sch_1):page40_i21:vss(1078)" )
			)
			( pin "U5D1.K71"
				( objectStatus "@baseboard_fab2_lib.baseboard_fab2(sch_1):page40_i21:vss(1079)" )
			)
			( pin "U5D1.K69"
				( objectStatus "@baseboard_fab2_lib.baseboard_fab2(sch_1):page40_i21:vss(1080)" )
			)
			( pin "U5D1.K67"
				( objectStatus "@baseboard_fab2_lib.baseboard_fab2(sch_1):page40_i21:vss(1081)" )
			)
			( pin "U5D1.K65"
				( objectStatus "@baseboard_fab2_lib.baseboard_fab2(sch_1):page40_i21:vss(1082)" )
			)
			( pin "U5D1.K39"
				( objectStatus "@baseboard_fab2_lib.baseboard_fab2(sch_1):page40_i21:vss(1083)" )
			)
			( pin "U5D1.K33"
				( objectStatus "@baseboard_fab2_lib.baseboard_fab2(sch_1):page40_i21:vss(1084)" )
			)
			( pin "U5D1.K27"
				( objectStatus "@baseboard_fab2_lib.baseboard_fab2(sch_1):page40_i21:vss(1085)" )
			)
			( pin "U5D1.DB7"
				( objectStatus "@baseboard_fab2_lib.baseboard_fab2(sch_1):page40_i21:vss(1086)" )
			)
			( pin "U5D1.K17"
				( objectStatus "@baseboard_fab2_lib.baseboard_fab2(sch_1):page40_i21:vss(1087)" )
			)
			( pin "U5D1.K13"
				( objectStatus "@baseboard_fab2_lib.baseboard_fab2(sch_1):page40_i21:vss(1088)" )
			)
			( pin "U5D1.K11"
				( objectStatus "@baseboard_fab2_lib.baseboard_fab2(sch_1):page40_i21:vss(1089)" )
			)
			( pin "U5D1.K1"
				( objectStatus "@baseboard_fab2_lib.baseboard_fab2(sch_1):page40_i21:vss(1090)" )
			)
			( pin "U5D1.J84"
				( objectStatus "@baseboard_fab2_lib.baseboard_fab2(sch_1):page40_i21:vss(1091)" )
			)
			( pin "U5D1.J82"
				( objectStatus "@baseboard_fab2_lib.baseboard_fab2(sch_1):page40_i21:vss(1092)" )
			)
			( pin "U5D1.J76"
				( objectStatus "@baseboard_fab2_lib.baseboard_fab2(sch_1):page40_i21:vss(1093)" )
			)
			( pin "U5D1.AL68"
				( objectStatus "@baseboard_fab2_lib.baseboard_fab2(sch_1):page40_i22:vss(774)" )
			)
			( pin "U5D1.AL64"
				( objectStatus "@baseboard_fab2_lib.baseboard_fab2(sch_1):page40_i22:vss(775)" )
			)
			( pin "U5D1.AL56"
				( objectStatus "@baseboard_fab2_lib.baseboard_fab2(sch_1):page40_i22:vss(776)" )
			)
			( pin "U5D1.AL32"
				( objectStatus "@baseboard_fab2_lib.baseboard_fab2(sch_1):page40_i22:vss(777)" )
			)
			( pin "U5D1.AL30"
				( objectStatus "@baseboard_fab2_lib.baseboard_fab2(sch_1):page40_i22:vss(778)" )
			)
			( pin "U5D1.AL24"
				( objectStatus "@baseboard_fab2_lib.baseboard_fab2(sch_1):page40_i22:vss(779)" )
			)
			( pin "U5D1.AL10"
				( objectStatus "@baseboard_fab2_lib.baseboard_fab2(sch_1):page40_i22:vss(780)" )
			)
			( pin "U5D1.AL4"
				( objectStatus "@baseboard_fab2_lib.baseboard_fab2(sch_1):page40_i22:vss(781)" )
			)
			( pin "U5D1.AK85"
				( objectStatus "@baseboard_fab2_lib.baseboard_fab2(sch_1):page40_i22:vss(782)" )
			)
			( pin "U5D1.AK83"
				( objectStatus "@baseboard_fab2_lib.baseboard_fab2(sch_1):page40_i22:vss(783)" )
			)
			( pin "U5D1.AK81"
				( objectStatus "@baseboard_fab2_lib.baseboard_fab2(sch_1):page40_i22:vss(784)" )
			)
			( pin "U5D1.AK79"
				( objectStatus "@baseboard_fab2_lib.baseboard_fab2(sch_1):page40_i22:vss(785)" )
			)
			( pin "U5D1.AK73"
				( objectStatus "@baseboard_fab2_lib.baseboard_fab2(sch_1):page40_i22:vss(786)" )
			)
			( pin "U5D1.AK67"
				( objectStatus "@baseboard_fab2_lib.baseboard_fab2(sch_1):page40_i22:vss(787)" )
			)
			( pin "U5D1.AK65"
				( objectStatus "@baseboard_fab2_lib.baseboard_fab2(sch_1):page40_i22:vss(788)" )
			)
			( pin "U5D1.AK55"
				( objectStatus "@baseboard_fab2_lib.baseboard_fab2(sch_1):page40_i22:vss(789)" )
			)
			( pin "U5D1.AK33"
				( objectStatus "@baseboard_fab2_lib.baseboard_fab2(sch_1):page40_i22:vss(790)" )
			)
			( pin "U5D1.AK31"
				( objectStatus "@baseboard_fab2_lib.baseboard_fab2(sch_1):page40_i22:vss(791)" )
			)
			( pin "U5D1.AK29"
				( objectStatus "@baseboard_fab2_lib.baseboard_fab2(sch_1):page40_i22:vss(792)" )
			)
			( pin "U5D1.AK25"
				( objectStatus "@baseboard_fab2_lib.baseboard_fab2(sch_1):page40_i22:vss(793)" )
			)
			( pin "U5D1.AK23"
				( objectStatus "@baseboard_fab2_lib.baseboard_fab2(sch_1):page40_i22:vss(794)" )
			)
			( pin "U5D1.AK19"
				( objectStatus "@baseboard_fab2_lib.baseboard_fab2(sch_1):page40_i22:vss(795)" )
			)
			( pin "U5D1.AK13"
				( objectStatus "@baseboard_fab2_lib.baseboard_fab2(sch_1):page40_i22:vss(796)" )
			)
			( pin "U5D1.AK9"
				( objectStatus "@baseboard_fab2_lib.baseboard_fab2(sch_1):page40_i22:vss(797)" )
			)
			( pin "U5D1.AJ86"
				( objectStatus "@baseboard_fab2_lib.baseboard_fab2(sch_1):page40_i22:vss(798)" )
			)
			( pin "U5D1.AJ82"
				( objectStatus "@baseboard_fab2_lib.baseboard_fab2(sch_1):page40_i22:vss(799)" )
			)
			( pin "U5D1.AJ78"
				( objectStatus "@baseboard_fab2_lib.baseboard_fab2(sch_1):page40_i22:vss(800)" )
			)
			( pin "U5D1.AJ74"
				( objectStatus "@baseboard_fab2_lib.baseboard_fab2(sch_1):page40_i22:vss(801)" )
			)
			( pin "U5D1.AJ68"
				( objectStatus "@baseboard_fab2_lib.baseboard_fab2(sch_1):page40_i22:vss(802)" )
			)
			( pin "U5D1.AJ66"
				( objectStatus "@baseboard_fab2_lib.baseboard_fab2(sch_1):page40_i22:vss(803)" )
			)
			( pin "U5D1.AJ54"
				( objectStatus "@baseboard_fab2_lib.baseboard_fab2(sch_1):page40_i22:vss(804)" )
			)
			( pin "U5D1.AJ52"
				( objectStatus "@baseboard_fab2_lib.baseboard_fab2(sch_1):page40_i22:vss(805)" )
			)
			( pin "U5D1.AJ50"
				( objectStatus "@baseboard_fab2_lib.baseboard_fab2(sch_1):page40_i22:vss(806)" )
			)
			( pin "U5D1.AJ48"
				( objectStatus "@baseboard_fab2_lib.baseboard_fab2(sch_1):page40_i22:vss(807)" )
			)
			( pin "U5D1.AJ46"
				( objectStatus "@baseboard_fab2_lib.baseboard_fab2(sch_1):page40_i22:vss(808)" )
			)
			( pin "U5D1.AJ34"
				( objectStatus "@baseboard_fab2_lib.baseboard_fab2(sch_1):page40_i22:vss(809)" )
			)
			( pin "U5D1.AJ32"
				( objectStatus "@baseboard_fab2_lib.baseboard_fab2(sch_1):page40_i22:vss(810)" )
			)
			( pin "U5D1.AJ28"
				( objectStatus "@baseboard_fab2_lib.baseboard_fab2(sch_1):page40_i22:vss(811)" )
			)
			( pin "U5D1.AJ26"
				( objectStatus "@baseboard_fab2_lib.baseboard_fab2(sch_1):page40_i22:vss(812)" )
			)
			( pin "U5D1.AJ22"
				( objectStatus "@baseboard_fab2_lib.baseboard_fab2(sch_1):page40_i22:vss(813)" )
			)
			( pin "U5D1.AJ8"
				( objectStatus "@baseboard_fab2_lib.baseboard_fab2(sch_1):page40_i22:vss(814)" )
			)
			( pin "U5D1.AH83"
				( objectStatus "@baseboard_fab2_lib.baseboard_fab2(sch_1):page40_i22:vss(815)" )
			)
			( pin "U5D1.AH77"
				( objectStatus "@baseboard_fab2_lib.baseboard_fab2(sch_1):page40_i22:vss(816)" )
			)
			( pin "U5D1.AH75"
				( objectStatus "@baseboard_fab2_lib.baseboard_fab2(sch_1):page40_i22:vss(817)" )
			)
			( pin "U5D1.AH69"
				( objectStatus "@baseboard_fab2_lib.baseboard_fab2(sch_1):page40_i22:vss(818)" )
			)
			( pin "U5D1.AH65"
				( objectStatus "@baseboard_fab2_lib.baseboard_fab2(sch_1):page40_i22:vss(819)" )
			)
			( pin "U5D1.AH61"
				( objectStatus "@baseboard_fab2_lib.baseboard_fab2(sch_1):page40_i22:vss(820)" )
			)
			( pin "U5D1.AH59"
				( objectStatus "@baseboard_fab2_lib.baseboard_fab2(sch_1):page40_i22:vss(821)" )
			)
			( pin "U5D1.AH53"
				( objectStatus "@baseboard_fab2_lib.baseboard_fab2(sch_1):page40_i22:vss(822)" )
			)
			( pin "U5D1.AH51"
				( objectStatus "@baseboard_fab2_lib.baseboard_fab2(sch_1):page40_i22:vss(823)" )
			)
			( pin "U5D1.AH49"
				( objectStatus "@baseboard_fab2_lib.baseboard_fab2(sch_1):page40_i22:vss(824)" )
			)
			( pin "U5D1.AH47"
				( objectStatus "@baseboard_fab2_lib.baseboard_fab2(sch_1):page40_i22:vss(825)" )
			)
			( pin "U5D1.AH45"
				( objectStatus "@baseboard_fab2_lib.baseboard_fab2(sch_1):page40_i22:vss(826)" )
			)
			( pin "U5D1.AH35"
				( objectStatus "@baseboard_fab2_lib.baseboard_fab2(sch_1):page40_i22:vss(827)" )
			)
			( pin "U5D1.AH33"
				( objectStatus "@baseboard_fab2_lib.baseboard_fab2(sch_1):page40_i22:vss(828)" )
			)
			( pin "U5D1.AH27"
				( objectStatus "@baseboard_fab2_lib.baseboard_fab2(sch_1):page40_i22:vss(829)" )
			)
			( pin "U5D1.AH21"
				( objectStatus "@baseboard_fab2_lib.baseboard_fab2(sch_1):page40_i22:vss(830)" )
			)
			( pin "U5D1.AH5"
				( objectStatus "@baseboard_fab2_lib.baseboard_fab2(sch_1):page40_i22:vss(831)" )
			)
			( pin "U5D1.AH1"
				( objectStatus "@baseboard_fab2_lib.baseboard_fab2(sch_1):page40_i22:vss(832)" )
			)
			( pin "U5D1.AG80"
				( objectStatus "@baseboard_fab2_lib.baseboard_fab2(sch_1):page40_i22:vss(833)" )
			)
			( pin "U5D1.AG78"
				( objectStatus "@baseboard_fab2_lib.baseboard_fab2(sch_1):page40_i22:vss(834)" )
			)
			( pin "U5D1.AG76"
				( objectStatus "@baseboard_fab2_lib.baseboard_fab2(sch_1):page40_i22:vss(835)" )
			)
			( pin "U5D1.AG74"
				( objectStatus "@baseboard_fab2_lib.baseboard_fab2(sch_1):page40_i22:vss(836)" )
			)
			( pin "U5D1.AG70"
				( objectStatus "@baseboard_fab2_lib.baseboard_fab2(sch_1):page40_i22:vss(837)" )
			)
			( pin "U5D1.AG64"
				( objectStatus "@baseboard_fab2_lib.baseboard_fab2(sch_1):page40_i22:vss(838)" )
			)
			( pin "U5D1.AG36"
				( objectStatus "@baseboard_fab2_lib.baseboard_fab2(sch_1):page40_i22:vss(839)" )
			)
			( pin "U5D1.AG18"
				( objectStatus "@baseboard_fab2_lib.baseboard_fab2(sch_1):page40_i22:vss(840)" )
			)
			( pin "U5D1.AG14"
				( objectStatus "@baseboard_fab2_lib.baseboard_fab2(sch_1):page40_i22:vss(841)" )
			)
			( pin "U5D1.AG12"
				( objectStatus "@baseboard_fab2_lib.baseboard_fab2(sch_1):page40_i22:vss(842)" )
			)
			( pin "U5D1.AF85"
				( objectStatus "@baseboard_fab2_lib.baseboard_fab2(sch_1):page40_i22:vss(843)" )
			)
			( pin "U5D1.AF83"
				( objectStatus "@baseboard_fab2_lib.baseboard_fab2(sch_1):page40_i22:vss(844)" )
			)
			( pin "U5D1.AF77"
				( objectStatus "@baseboard_fab2_lib.baseboard_fab2(sch_1):page40_i22:vss(845)" )
			)
			( pin "U5D1.AF73"
				( objectStatus "@baseboard_fab2_lib.baseboard_fab2(sch_1):page40_i22:vss(846)" )
			)
			( pin "U5D1.AF41"
				( objectStatus "@baseboard_fab2_lib.baseboard_fab2(sch_1):page40_i22:vss(847)" )
			)
			( pin "U5D1.AF39"
				( objectStatus "@baseboard_fab2_lib.baseboard_fab2(sch_1):page40_i22:vss(848)" )
			)
			( pin "U5D1.AF37"
				( objectStatus "@baseboard_fab2_lib.baseboard_fab2(sch_1):page40_i22:vss(849)" )
			)
			( pin "U5D1.AF33"
				( objectStatus "@baseboard_fab2_lib.baseboard_fab2(sch_1):page40_i22:vss(850)" )
			)
			( pin "U5D1.AF31"
				( objectStatus "@baseboard_fab2_lib.baseboard_fab2(sch_1):page40_i22:vss(851)" )
			)
			( pin "U5D1.AF29"
				( objectStatus "@baseboard_fab2_lib.baseboard_fab2(sch_1):page40_i22:vss(852)" )
			)
			( pin "U5D1.AF27"
				( objectStatus "@baseboard_fab2_lib.baseboard_fab2(sch_1):page40_i22:vss(853)" )
			)
			( pin "U5D1.AF25"
				( objectStatus "@baseboard_fab2_lib.baseboard_fab2(sch_1):page40_i22:vss(854)" )
			)
			( pin "U5D1.AF23"
				( objectStatus "@baseboard_fab2_lib.baseboard_fab2(sch_1):page40_i22:vss(855)" )
			)
			( pin "U5D1.AF21"
				( objectStatus "@baseboard_fab2_lib.baseboard_fab2(sch_1):page40_i22:vss(856)" )
			)
			( pin "U5D1.AF9"
				( objectStatus "@baseboard_fab2_lib.baseboard_fab2(sch_1):page40_i22:vss(857)" )
			)
			( pin "U5D1.AC52"
				( objectStatus "@baseboard_fab2_lib.baseboard_fab2(sch_1):page40_i22:vss(858)" )
			)
			( pin "U5D1.AF1"
				( objectStatus "@baseboard_fab2_lib.baseboard_fab2(sch_1):page40_i22:vss(859)" )
			)
			( pin "U5D1.AE78"
				( objectStatus "@baseboard_fab2_lib.baseboard_fab2(sch_1):page40_i22:vss(860)" )
			)
			( pin "U5D1.AE70"
				( objectStatus "@baseboard_fab2_lib.baseboard_fab2(sch_1):page40_i22:vss(861)" )
			)
			( pin "U5D1.AE68"
				( objectStatus "@baseboard_fab2_lib.baseboard_fab2(sch_1):page40_i22:vss(862)" )
			)
			( pin "U5D1.AE66"
				( objectStatus "@baseboard_fab2_lib.baseboard_fab2(sch_1):page40_i22:vss(863)" )
			)
			( pin "U5D1.AE64"
				( objectStatus "@baseboard_fab2_lib.baseboard_fab2(sch_1):page40_i22:vss(864)" )
			)
			( pin "U5D1.AE42"
				( objectStatus "@baseboard_fab2_lib.baseboard_fab2(sch_1):page40_i22:vss(865)" )
			)
			( pin "U5D1.AE40"
				( objectStatus "@baseboard_fab2_lib.baseboard_fab2(sch_1):page40_i22:vss(866)" )
			)
			( pin "U5D1.AE38"
				( objectStatus "@baseboard_fab2_lib.baseboard_fab2(sch_1):page40_i22:vss(867)" )
			)
			( pin "U5D1.AE16"
				( objectStatus "@baseboard_fab2_lib.baseboard_fab2(sch_1):page40_i22:vss(868)" )
			)
			( pin "U5D1.AC54"
				( objectStatus "@baseboard_fab2_lib.baseboard_fab2(sch_1):page40_i22:vss(869)" )
			)
			( pin "U5D1.AE8"
				( objectStatus "@baseboard_fab2_lib.baseboard_fab2(sch_1):page40_i22:vss(870)" )
			)
			( pin "U5D1.AE4"
				( objectStatus "@baseboard_fab2_lib.baseboard_fab2(sch_1):page40_i22:vss(871)" )
			)
			( pin "U5D1.AD85"
				( objectStatus "@baseboard_fab2_lib.baseboard_fab2(sch_1):page40_i22:vss(872)" )
			)
			( pin "U5D1.AD83"
				( objectStatus "@baseboard_fab2_lib.baseboard_fab2(sch_1):page40_i22:vss(873)" )
			)
			( pin "U5D1.AD81"
				( objectStatus "@baseboard_fab2_lib.baseboard_fab2(sch_1):page40_i22:vss(874)" )
			)
			( pin "U5D1.AD75"
				( objectStatus "@baseboard_fab2_lib.baseboard_fab2(sch_1):page40_i22:vss(875)" )
			)
			( pin "U5D1.AD73"
				( objectStatus "@baseboard_fab2_lib.baseboard_fab2(sch_1):page40_i22:vss(876)" )
			)
			( pin "U5D1.AD71"
				( objectStatus "@baseboard_fab2_lib.baseboard_fab2(sch_1):page40_i22:vss(877)" )
			)
			( pin "U5D1.AD43"
				( objectStatus "@baseboard_fab2_lib.baseboard_fab2(sch_1):page40_i22:vss(878)" )
			)
			( pin "U5D1.AD39"
				( objectStatus "@baseboard_fab2_lib.baseboard_fab2(sch_1):page40_i22:vss(879)" )
			)
			( pin "U5D1.AD33"
				( objectStatus "@baseboard_fab2_lib.baseboard_fab2(sch_1):page40_i22:vss(880)" )
			)
			( pin "U5D1.AD27"
				( objectStatus "@baseboard_fab2_lib.baseboard_fab2(sch_1):page40_i22:vss(881)" )
			)
			( pin "U5D1.AD21"
				( objectStatus "@baseboard_fab2_lib.baseboard_fab2(sch_1):page40_i22:vss(882)" )
			)
			( pin "U5D1.AD19"
				( objectStatus "@baseboard_fab2_lib.baseboard_fab2(sch_1):page40_i22:vss(883)" )
			)
			( pin "U5D1.AD15"
				( objectStatus "@baseboard_fab2_lib.baseboard_fab2(sch_1):page40_i22:vss(884)" )
			)
			( pin "U5D1.AD13"
				( objectStatus "@baseboard_fab2_lib.baseboard_fab2(sch_1):page40_i22:vss(885)" )
			)
			( pin "U5D1.AD11"
				( objectStatus "@baseboard_fab2_lib.baseboard_fab2(sch_1):page40_i22:vss(886)" )
			)
			( pin "U5D1.AD9"
				( objectStatus "@baseboard_fab2_lib.baseboard_fab2(sch_1):page40_i22:vss(887)" )
			)
			( pin "U5D1.AD7"
				( objectStatus "@baseboard_fab2_lib.baseboard_fab2(sch_1):page40_i22:vss(888)" )
			)
			( pin "U5D1.AD3"
				( objectStatus "@baseboard_fab2_lib.baseboard_fab2(sch_1):page40_i22:vss(889)" )
			)
			( pin "U5D1.AC86"
				( objectStatus "@baseboard_fab2_lib.baseboard_fab2(sch_1):page40_i22:vss(890)" )
			)
			( pin "U5D1.AC84"
				( objectStatus "@baseboard_fab2_lib.baseboard_fab2(sch_1):page40_i22:vss(891)" )
			)
			( pin "U5D1.AC78"
				( objectStatus "@baseboard_fab2_lib.baseboard_fab2(sch_1):page40_i22:vss(892)" )
			)
			( pin "U5D1.AC72"
				( objectStatus "@baseboard_fab2_lib.baseboard_fab2(sch_1):page40_i22:vss(893)" )
			)
			( pin "U5D1.AC70"
				( objectStatus "@baseboard_fab2_lib.baseboard_fab2(sch_1):page40_i22:vss(894)" )
			)
			( pin "U5D1.AC64"
				( objectStatus "@baseboard_fab2_lib.baseboard_fab2(sch_1):page40_i22:vss(895)" )
			)
			( pin "U5D1.AC40"
				( objectStatus "@baseboard_fab2_lib.baseboard_fab2(sch_1):page40_i22:vss(896)" )
			)
			( pin "U5D1.AC38"
				( objectStatus "@baseboard_fab2_lib.baseboard_fab2(sch_1):page40_i22:vss(897)" )
			)
			( pin "U5D1.AC34"
				( objectStatus "@baseboard_fab2_lib.baseboard_fab2(sch_1):page40_i22:vss(898)" )
			)
			( pin "U5D1.AC32"
				( objectStatus "@baseboard_fab2_lib.baseboard_fab2(sch_1):page40_i22:vss(899)" )
			)
			( pin "U5D1.AC28"
				( objectStatus "@baseboard_fab2_lib.baseboard_fab2(sch_1):page40_i22:vss(900)" )
			)
			( pin "U5D1.AC26"
				( objectStatus "@baseboard_fab2_lib.baseboard_fab2(sch_1):page40_i22:vss(901)" )
			)
			( pin "U5D1.AC22"
				( objectStatus "@baseboard_fab2_lib.baseboard_fab2(sch_1):page40_i22:vss(902)" )
			)
			( pin "U5D1.AC18"
				( objectStatus "@baseboard_fab2_lib.baseboard_fab2(sch_1):page40_i22:vss(903)" )
			)
			( pin "U5D1.AB85"
				( objectStatus "@baseboard_fab2_lib.baseboard_fab2(sch_1):page40_i22:vss(904)" )
			)
			( pin "U5D1.AB83"
				( objectStatus "@baseboard_fab2_lib.baseboard_fab2(sch_1):page40_i22:vss(905)" )
			)
			( pin "U5D1.AB79"
				( objectStatus "@baseboard_fab2_lib.baseboard_fab2(sch_1):page40_i22:vss(906)" )
			)
			( pin "U5D1.AB73"
				( objectStatus "@baseboard_fab2_lib.baseboard_fab2(sch_1):page40_i22:vss(907)" )
			)
			( pin "U5D1.AB69"
				( objectStatus "@baseboard_fab2_lib.baseboard_fab2(sch_1):page40_i22:vss(908)" )
			)
			( pin "U5D1.AB65"
				( objectStatus "@baseboard_fab2_lib.baseboard_fab2(sch_1):page40_i22:vss(909)" )
			)
			( pin "U5D1.AB41"
				( objectStatus "@baseboard_fab2_lib.baseboard_fab2(sch_1):page40_i22:vss(910)" )
			)
			( pin "U5D1.AB37"
				( objectStatus "@baseboard_fab2_lib.baseboard_fab2(sch_1):page40_i22:vss(911)" )
			)
			( pin "U5D1.AB35"
				( objectStatus "@baseboard_fab2_lib.baseboard_fab2(sch_1):page40_i22:vss(912)" )
			)
			( pin "U5D1.AB31"
				( objectStatus "@baseboard_fab2_lib.baseboard_fab2(sch_1):page40_i22:vss(913)" )
			)
			( pin "U5D1.AB29"
				( objectStatus "@baseboard_fab2_lib.baseboard_fab2(sch_1):page40_i22:vss(914)" )
			)
			( pin "U5D1.AB25"
				( objectStatus "@baseboard_fab2_lib.baseboard_fab2(sch_1):page40_i22:vss(915)" )
			)
			( pin "U5D1.AB23"
				( objectStatus "@baseboard_fab2_lib.baseboard_fab2(sch_1):page40_i22:vss(916)" )
			)
			( pin "U5D1.AB21"
				( objectStatus "@baseboard_fab2_lib.baseboard_fab2(sch_1):page40_i22:vss(917)" )
			)
			( pin "U5D1.AB11"
				( objectStatus "@baseboard_fab2_lib.baseboard_fab2(sch_1):page40_i22:vss(918)" )
			)
			( pin "U5D1.AB5"
				( objectStatus "@baseboard_fab2_lib.baseboard_fab2(sch_1):page40_i22:vss(919)" )
			)
			( pin "U5D1.AB1"
				( objectStatus "@baseboard_fab2_lib.baseboard_fab2(sch_1):page40_i22:vss(920)" )
			)
			( pin "U5D1.AA82"
				( objectStatus "@baseboard_fab2_lib.baseboard_fab2(sch_1):page40_i22:vss(921)" )
			)
			( pin "U5D1.AA80"
				( objectStatus "@baseboard_fab2_lib.baseboard_fab2(sch_1):page40_i22:vss(922)" )
			)
			( pin "U5D1.AA78"
				( objectStatus "@baseboard_fab2_lib.baseboard_fab2(sch_1):page40_i22:vss(923)" )
			)
			( pin "U5D1.AA76"
				( objectStatus "@baseboard_fab2_lib.baseboard_fab2(sch_1):page40_i22:vss(924)" )
			)
			( pin "U5D1.AA68"
				( objectStatus "@baseboard_fab2_lib.baseboard_fab2(sch_1):page40_i22:vss(925)" )
			)
			( pin "U5D1.AA66"
				( objectStatus "@baseboard_fab2_lib.baseboard_fab2(sch_1):page40_i22:vss(926)" )
			)
			( pin "U5D1.AA64"
				( objectStatus "@baseboard_fab2_lib.baseboard_fab2(sch_1):page40_i22:vss(927)" )
			)
			( pin "U5D1.AA42"
				( objectStatus "@baseboard_fab2_lib.baseboard_fab2(sch_1):page40_i22:vss(928)" )
			)
			( pin "U5D1.AA36"
				( objectStatus "@baseboard_fab2_lib.baseboard_fab2(sch_1):page40_i22:vss(929)" )
			)
			( pin "U5D1.AA30"
				( objectStatus "@baseboard_fab2_lib.baseboard_fab2(sch_1):page40_i22:vss(930)" )
			)
			( pin "U5D1.AA24"
				( objectStatus "@baseboard_fab2_lib.baseboard_fab2(sch_1):page40_i22:vss(931)" )
			)
			( pin "U5D1.AA22"
				( objectStatus "@baseboard_fab2_lib.baseboard_fab2(sch_1):page40_i22:vss(932)" )
			)
			( pin "U5D1.AA18"
				( objectStatus "@baseboard_fab2_lib.baseboard_fab2(sch_1):page40_i22:vss(933)" )
			)
			( pin "U5D1.BG72"
				( objectStatus "@baseboard_fab2_lib.baseboard_fab2(sch_1):page40_i23:vss(614)" )
			)
			( pin "U5D1.BG24"
				( objectStatus "@baseboard_fab2_lib.baseboard_fab2(sch_1):page40_i23:vss(615)" )
			)
			( pin "U5D1.BG22"
				( objectStatus "@baseboard_fab2_lib.baseboard_fab2(sch_1):page40_i23:vss(616)" )
			)
			( pin "U5D1.BG10"
				( objectStatus "@baseboard_fab2_lib.baseboard_fab2(sch_1):page40_i23:vss(617)" )
			)
			( pin "U5D1.BG8"
				( objectStatus "@baseboard_fab2_lib.baseboard_fab2(sch_1):page40_i23:vss(618)" )
			)
			( pin "U5D1.BG6"
				( objectStatus "@baseboard_fab2_lib.baseboard_fab2(sch_1):page40_i23:vss(619)" )
			)
			( pin "U5D1.BF71"
				( objectStatus "@baseboard_fab2_lib.baseboard_fab2(sch_1):page40_i23:vss(620)" )
			)
			( pin "U5D1.BF69"
				( objectStatus "@baseboard_fab2_lib.baseboard_fab2(sch_1):page40_i23:vss(621)" )
			)
			( pin "U5D1.BF67"
				( objectStatus "@baseboard_fab2_lib.baseboard_fab2(sch_1):page40_i23:vss(622)" )
			)
			( pin "U5D1.BF65"
				( objectStatus "@baseboard_fab2_lib.baseboard_fab2(sch_1):page40_i23:vss(623)" )
			)
			( pin "U5D1.BF63"
				( objectStatus "@baseboard_fab2_lib.baseboard_fab2(sch_1):page40_i23:vss(624)" )
			)
			( pin "U5D1.BF25"
				( objectStatus "@baseboard_fab2_lib.baseboard_fab2(sch_1):page40_i23:vss(625)" )
			)
			( pin "U5D1.BF19"
				( objectStatus "@baseboard_fab2_lib.baseboard_fab2(sch_1):page40_i23:vss(626)" )
			)
			( pin "U5D1.BF17"
				( objectStatus "@baseboard_fab2_lib.baseboard_fab2(sch_1):page40_i23:vss(627)" )
			)
			( pin "U5D1.BF15"
				( objectStatus "@baseboard_fab2_lib.baseboard_fab2(sch_1):page40_i23:vss(628)" )
			)
			( pin "U5D1.BF9"
				( objectStatus "@baseboard_fab2_lib.baseboard_fab2(sch_1):page40_i23:vss(629)" )
			)
			( pin "U5D1.BE70"
				( objectStatus "@baseboard_fab2_lib.baseboard_fab2(sch_1):page40_i23:vss(630)" )
			)
			( pin "U5D1.BE68"
				( objectStatus "@baseboard_fab2_lib.baseboard_fab2(sch_1):page40_i23:vss(631)" )
			)
			( pin "U5D1.BE66"
				( objectStatus "@baseboard_fab2_lib.baseboard_fab2(sch_1):page40_i23:vss(632)" )
			)
			( pin "U5D1.BE64"
				( objectStatus "@baseboard_fab2_lib.baseboard_fab2(sch_1):page40_i23:vss(633)" )
			)
			( pin "U5D1.BE26"
				( objectStatus "@baseboard_fab2_lib.baseboard_fab2(sch_1):page40_i23:vss(634)" )
			)
			( pin "U5D1.BE10"
				( objectStatus "@baseboard_fab2_lib.baseboard_fab2(sch_1):page40_i23:vss(635)" )
			)
			( pin "U5D1.BE8"
				( objectStatus "@baseboard_fab2_lib.baseboard_fab2(sch_1):page40_i23:vss(636)" )
			)
			( pin "U5D1.BE6"
				( objectStatus "@baseboard_fab2_lib.baseboard_fab2(sch_1):page40_i23:vss(637)" )
			)
			( pin "U5D1.BE4"
				( objectStatus "@baseboard_fab2_lib.baseboard_fab2(sch_1):page40_i23:vss(638)" )
			)
			( pin "U5D1.BD71"
				( objectStatus "@baseboard_fab2_lib.baseboard_fab2(sch_1):page40_i23:vss(639)" )
			)
			( pin "U5D1.BD63"
				( objectStatus "@baseboard_fab2_lib.baseboard_fab2(sch_1):page40_i23:vss(640)" )
			)
			( pin "U5D1.BD27"
				( objectStatus "@baseboard_fab2_lib.baseboard_fab2(sch_1):page40_i23:vss(641)" )
			)
			( pin "U5D1.BD21"
				( objectStatus "@baseboard_fab2_lib.baseboard_fab2(sch_1):page40_i23:vss(642)" )
			)
			( pin "U5D1.BD15"
				( objectStatus "@baseboard_fab2_lib.baseboard_fab2(sch_1):page40_i23:vss(643)" )
			)
			( pin "U5D1.BD11"
				( objectStatus "@baseboard_fab2_lib.baseboard_fab2(sch_1):page40_i23:vss(644)" )
			)
			( pin "U5D1.BD5"
				( objectStatus "@baseboard_fab2_lib.baseboard_fab2(sch_1):page40_i23:vss(645)" )
			)
			( pin "U5D1.BC82"
				( objectStatus "@baseboard_fab2_lib.baseboard_fab2(sch_1):page40_i23:vss(646)" )
			)
			( pin "U5D1.BC80"
				( objectStatus "@baseboard_fab2_lib.baseboard_fab2(sch_1):page40_i23:vss(647)" )
			)
			( pin "U5D1.BC78"
				( objectStatus "@baseboard_fab2_lib.baseboard_fab2(sch_1):page40_i23:vss(648)" )
			)
			( pin "U5D1.BC76"
				( objectStatus "@baseboard_fab2_lib.baseboard_fab2(sch_1):page40_i23:vss(649)" )
			)
			( pin "U5D1.BC74"
				( objectStatus "@baseboard_fab2_lib.baseboard_fab2(sch_1):page40_i23:vss(650)" )
			)
			( pin "U5D1.BC72"
				( objectStatus "@baseboard_fab2_lib.baseboard_fab2(sch_1):page40_i23:vss(651)" )
			)
			( pin "U5D1.BC70"
				( objectStatus "@baseboard_fab2_lib.baseboard_fab2(sch_1):page40_i23:vss(652)" )
			)
			( pin "U5D1.BC16"
				( objectStatus "@baseboard_fab2_lib.baseboard_fab2(sch_1):page40_i23:vss(653)" )
			)
			( pin "U5D1.BC12"
				( objectStatus "@baseboard_fab2_lib.baseboard_fab2(sch_1):page40_i23:vss(654)" )
			)
			( pin "U5D1.BC8"
				( objectStatus "@baseboard_fab2_lib.baseboard_fab2(sch_1):page40_i23:vss(655)" )
			)
			( pin "U5D1.BC4"
				( objectStatus "@baseboard_fab2_lib.baseboard_fab2(sch_1):page40_i23:vss(656)" )
			)
			( pin "U5D1.BB83"
				( objectStatus "@baseboard_fab2_lib.baseboard_fab2(sch_1):page40_i23:vss(657)" )
			)
			( pin "U5D1.BB81"
				( objectStatus "@baseboard_fab2_lib.baseboard_fab2(sch_1):page40_i23:vss(658)" )
			)
			( pin "U5D1.BB79"
				( objectStatus "@baseboard_fab2_lib.baseboard_fab2(sch_1):page40_i23:vss(659)" )
			)
			( pin "U5D1.BB77"
				( objectStatus "@baseboard_fab2_lib.baseboard_fab2(sch_1):page40_i23:vss(660)" )
			)
			( pin "U5D1.BB75"
				( objectStatus "@baseboard_fab2_lib.baseboard_fab2(sch_1):page40_i23:vss(661)" )
			)
			( pin "U5D1.BB73"
				( objectStatus "@baseboard_fab2_lib.baseboard_fab2(sch_1):page40_i23:vss(662)" )
			)
			( pin "U5D1.BB69"
				( objectStatus "@baseboard_fab2_lib.baseboard_fab2(sch_1):page40_i23:vss(663)" )
			)
			( pin "U5D1.BB63"
				( objectStatus "@baseboard_fab2_lib.baseboard_fab2(sch_1):page40_i23:vss(664)" )
			)
			( pin "U5D1.BB23"
				( objectStatus "@baseboard_fab2_lib.baseboard_fab2(sch_1):page40_i23:vss(665)" )
			)
			( pin "U5D1.BB19"
				( objectStatus "@baseboard_fab2_lib.baseboard_fab2(sch_1):page40_i23:vss(666)" )
			)
			( pin "U5D1.BA84"
				( objectStatus "@baseboard_fab2_lib.baseboard_fab2(sch_1):page40_i23:vss(667)" )
			)
			( pin "U5D1.BA80"
				( objectStatus "@baseboard_fab2_lib.baseboard_fab2(sch_1):page40_i23:vss(668)" )
			)
			( pin "U5D1.BA74"
				( objectStatus "@baseboard_fab2_lib.baseboard_fab2(sch_1):page40_i23:vss(669)" )
			)
			( pin "U5D1.BA68"
				( objectStatus "@baseboard_fab2_lib.baseboard_fab2(sch_1):page40_i23:vss(670)" )
			)
			( pin "U5D1.BA62"
				( objectStatus "@baseboard_fab2_lib.baseboard_fab2(sch_1):page40_i23:vss(671)" )
			)
			( pin "U5D1.BA12"
				( objectStatus "@baseboard_fab2_lib.baseboard_fab2(sch_1):page40_i23:vss(672)" )
			)
			( pin "U5D1.BA6"
				( objectStatus "@baseboard_fab2_lib.baseboard_fab2(sch_1):page40_i23:vss(673)" )
			)
			( pin "U5D1.BA2"
				( objectStatus "@baseboard_fab2_lib.baseboard_fab2(sch_1):page40_i23:vss(674)" )
			)
			( pin "U5D1.AY81"
				( objectStatus "@baseboard_fab2_lib.baseboard_fab2(sch_1):page40_i23:vss(675)" )
			)
			( pin "U5D1.AY79"
				( objectStatus "@baseboard_fab2_lib.baseboard_fab2(sch_1):page40_i23:vss(676)" )
			)
			( pin "U5D1.AY63"
				( objectStatus "@baseboard_fab2_lib.baseboard_fab2(sch_1):page40_i23:vss(677)" )
			)
			( pin "U5D1.AY25"
				( objectStatus "@baseboard_fab2_lib.baseboard_fab2(sch_1):page40_i23:vss(678)" )
			)
			( pin "U5D1.AY23"
				( objectStatus "@baseboard_fab2_lib.baseboard_fab2(sch_1):page40_i23:vss(679)" )
			)
			( pin "U5D1.AY21"
				( objectStatus "@baseboard_fab2_lib.baseboard_fab2(sch_1):page40_i23:vss(680)" )
			)
			( pin "U5D1.AY17"
				( objectStatus "@baseboard_fab2_lib.baseboard_fab2(sch_1):page40_i23:vss(681)" )
			)
			( pin "U5D1.AY15"
				( objectStatus "@baseboard_fab2_lib.baseboard_fab2(sch_1):page40_i23:vss(682)" )
			)
			( pin "U5D1.AY5"
				( objectStatus "@baseboard_fab2_lib.baseboard_fab2(sch_1):page40_i23:vss(683)" )
			)
			( pin "U5D1.AW84"
				( objectStatus "@baseboard_fab2_lib.baseboard_fab2(sch_1):page40_i23:vss(684)" )
			)
			( pin "U5D1.AW82"
				( objectStatus "@baseboard_fab2_lib.baseboard_fab2(sch_1):page40_i23:vss(685)" )
			)
			( pin "U5D1.AW78"
				( objectStatus "@baseboard_fab2_lib.baseboard_fab2(sch_1):page40_i23:vss(686)" )
			)
			( pin "U5D1.AW74"
				( objectStatus "@baseboard_fab2_lib.baseboard_fab2(sch_1):page40_i23:vss(687)" )
			)
			( pin "U5D1.AW72"
				( objectStatus "@baseboard_fab2_lib.baseboard_fab2(sch_1):page40_i23:vss(688)" )
			)
			( pin "U5D1.AW70"
				( objectStatus "@baseboard_fab2_lib.baseboard_fab2(sch_1):page40_i23:vss(689)" )
			)
			( pin "U5D1.AW68"
				( objectStatus "@baseboard_fab2_lib.baseboard_fab2(sch_1):page40_i23:vss(690)" )
			)
			( pin "U5D1.AW66"
				( objectStatus "@baseboard_fab2_lib.baseboard_fab2(sch_1):page40_i23:vss(691)" )
			)
			( pin "U5D1.AW62"
				( objectStatus "@baseboard_fab2_lib.baseboard_fab2(sch_1):page40_i23:vss(692)" )
			)
			( pin "U5D1.AW10"
				( objectStatus "@baseboard_fab2_lib.baseboard_fab2(sch_1):page40_i23:vss(693)" )
			)
			( pin "U5D1.AW2"
				( objectStatus "@baseboard_fab2_lib.baseboard_fab2(sch_1):page40_i23:vss(694)" )
			)
			( pin "U5D1.AV83"
				( objectStatus "@baseboard_fab2_lib.baseboard_fab2(sch_1):page40_i23:vss(695)" )
			)
			( pin "U5D1.AV75"
				( objectStatus "@baseboard_fab2_lib.baseboard_fab2(sch_1):page40_i23:vss(696)" )
			)
			( pin "U5D1.AV67"
				( objectStatus "@baseboard_fab2_lib.baseboard_fab2(sch_1):page40_i23:vss(697)" )
			)
			( pin "U5D1.AV65"
				( objectStatus "@baseboard_fab2_lib.baseboard_fab2(sch_1):page40_i23:vss(698)" )
			)
			( pin "U5D1.AV63"
				( objectStatus "@baseboard_fab2_lib.baseboard_fab2(sch_1):page40_i23:vss(699)" )
			)
			( pin "U5D1.AV25"
				( objectStatus "@baseboard_fab2_lib.baseboard_fab2(sch_1):page40_i23:vss(700)" )
			)
			( pin "U5D1.AV23"
				( objectStatus "@baseboard_fab2_lib.baseboard_fab2(sch_1):page40_i23:vss(701)" )
			)
			( pin "U5D1.AV19"
				( objectStatus "@baseboard_fab2_lib.baseboard_fab2(sch_1):page40_i23:vss(702)" )
			)
			( pin "U5D1.AV13"
				( objectStatus "@baseboard_fab2_lib.baseboard_fab2(sch_1):page40_i23:vss(703)" )
			)
			( pin "U5D1.AV11"
				( objectStatus "@baseboard_fab2_lib.baseboard_fab2(sch_1):page40_i23:vss(704)" )
			)
			( pin "U5D1.AV7"
				( objectStatus "@baseboard_fab2_lib.baseboard_fab2(sch_1):page40_i23:vss(705)" )
			)
			( pin "U5D1.AV3"
				( objectStatus "@baseboard_fab2_lib.baseboard_fab2(sch_1):page40_i23:vss(706)" )
			)
			( pin "U5D1.AV1"
				( objectStatus "@baseboard_fab2_lib.baseboard_fab2(sch_1):page40_i23:vss(707)" )
			)
			( pin "U5D1.AU86"
				( objectStatus "@baseboard_fab2_lib.baseboard_fab2(sch_1):page40_i23:vss(708)" )
			)
			( pin "U5D1.AU84"
				( objectStatus "@baseboard_fab2_lib.baseboard_fab2(sch_1):page40_i23:vss(709)" )
			)
			( pin "U5D1.AU80"
				( objectStatus "@baseboard_fab2_lib.baseboard_fab2(sch_1):page40_i23:vss(710)" )
			)
			( pin "U5D1.AU78"
				( objectStatus "@baseboard_fab2_lib.baseboard_fab2(sch_1):page40_i23:vss(711)" )
			)
			( pin "U5D1.AU76"
				( objectStatus "@baseboard_fab2_lib.baseboard_fab2(sch_1):page40_i23:vss(712)" )
			)
			( pin "U5D1.AU74"
				( objectStatus "@baseboard_fab2_lib.baseboard_fab2(sch_1):page40_i23:vss(713)" )
			)
			( pin "U5D1.AU68"
				( objectStatus "@baseboard_fab2_lib.baseboard_fab2(sch_1):page40_i23:vss(714)" )
			)
			( pin "U5D1.AU64"
				( objectStatus "@baseboard_fab2_lib.baseboard_fab2(sch_1):page40_i23:vss(715)" )
			)
			( pin "U5D1.AU62"
				( objectStatus "@baseboard_fab2_lib.baseboard_fab2(sch_1):page40_i23:vss(716)" )
			)
			( pin "U5D1.AU28"
				( objectStatus "@baseboard_fab2_lib.baseboard_fab2(sch_1):page40_i23:vss(717)" )
			)
			( pin "U5D1.AU26"
				( objectStatus "@baseboard_fab2_lib.baseboard_fab2(sch_1):page40_i23:vss(718)" )
			)
			( pin "U5D1.AU6"
				( objectStatus "@baseboard_fab2_lib.baseboard_fab2(sch_1):page40_i23:vss(719)" )
			)
			( pin "U5D1.AU2"
				( objectStatus "@baseboard_fab2_lib.baseboard_fab2(sch_1):page40_i23:vss(720)" )
			)
			( pin "U5D1.AT85"
				( objectStatus "@baseboard_fab2_lib.baseboard_fab2(sch_1):page40_i23:vss(721)" )
			)
			( pin "U5D1.AT83"
				( objectStatus "@baseboard_fab2_lib.baseboard_fab2(sch_1):page40_i23:vss(722)" )
			)
			( pin "U5D1.AT77"
				( objectStatus "@baseboard_fab2_lib.baseboard_fab2(sch_1):page40_i23:vss(723)" )
			)
			( pin "U5D1.AT73"
				( objectStatus "@baseboard_fab2_lib.baseboard_fab2(sch_1):page40_i23:vss(724)" )
			)
			( pin "U5D1.AT69"
				( objectStatus "@baseboard_fab2_lib.baseboard_fab2(sch_1):page40_i23:vss(725)" )
			)
			( pin "U5D1.AT63"
				( objectStatus "@baseboard_fab2_lib.baseboard_fab2(sch_1):page40_i23:vss(726)" )
			)
			( pin "U5D1.AT61"
				( objectStatus "@baseboard_fab2_lib.baseboard_fab2(sch_1):page40_i23:vss(727)" )
			)
			( pin "U5D1.AT27"
				( objectStatus "@baseboard_fab2_lib.baseboard_fab2(sch_1):page40_i23:vss(728)" )
			)
			( pin "U5D1.AT21"
				( objectStatus "@baseboard_fab2_lib.baseboard_fab2(sch_1):page40_i23:vss(729)" )
			)
			( pin "U5D1.AT17"
				( objectStatus "@baseboard_fab2_lib.baseboard_fab2(sch_1):page40_i23:vss(730)" )
			)
			( pin "U5D1.AT15"
				( objectStatus "@baseboard_fab2_lib.baseboard_fab2(sch_1):page40_i23:vss(731)" )
			)
			( pin "U5D1.P63"
				( objectStatus "@baseboard_fab2_lib.baseboard_fab2(sch_1):page40_i23:vss(732)" )
			)
			( pin "U5D1.AC48"
				( objectStatus "@baseboard_fab2_lib.baseboard_fab2(sch_1):page40_i23:vss(733)" )
			)
			( pin "U5D1.AR78"
				( objectStatus "@baseboard_fab2_lib.baseboard_fab2(sch_1):page40_i23:vss(734)" )
			)
			( pin "U5D1.AR72"
				( objectStatus "@baseboard_fab2_lib.baseboard_fab2(sch_1):page40_i23:vss(735)" )
			)
			( pin "U5D1.AR60"
				( objectStatus "@baseboard_fab2_lib.baseboard_fab2(sch_1):page40_i23:vss(736)" )
			)
			( pin "U5D1.AR30"
				( objectStatus "@baseboard_fab2_lib.baseboard_fab2(sch_1):page40_i23:vss(737)" )
			)
			( pin "U5D1.AR24"
				( objectStatus "@baseboard_fab2_lib.baseboard_fab2(sch_1):page40_i23:vss(738)" )
			)
			( pin "U5D1.AR10"
				( objectStatus "@baseboard_fab2_lib.baseboard_fab2(sch_1):page40_i23:vss(739)" )
			)
			( pin "U5D1.AP85"
				( objectStatus "@baseboard_fab2_lib.baseboard_fab2(sch_1):page40_i23:vss(740)" )
			)
			( pin "U5D1.AP83"
				( objectStatus "@baseboard_fab2_lib.baseboard_fab2(sch_1):page40_i23:vss(741)" )
			)
			( pin "U5D1.AP81"
				( objectStatus "@baseboard_fab2_lib.baseboard_fab2(sch_1):page40_i23:vss(742)" )
			)
			( pin "U5D1.AP75"
				( objectStatus "@baseboard_fab2_lib.baseboard_fab2(sch_1):page40_i23:vss(743)" )
			)
			( pin "U5D1.AP73"
				( objectStatus "@baseboard_fab2_lib.baseboard_fab2(sch_1):page40_i23:vss(744)" )
			)
			( pin "U5D1.AP69"
				( objectStatus "@baseboard_fab2_lib.baseboard_fab2(sch_1):page40_i23:vss(745)" )
			)
			( pin "U5D1.AP67"
				( objectStatus "@baseboard_fab2_lib.baseboard_fab2(sch_1):page40_i23:vss(746)" )
			)
			( pin "U5D1.AP65"
				( objectStatus "@baseboard_fab2_lib.baseboard_fab2(sch_1):page40_i23:vss(747)" )
			)
			( pin "U5D1.AP63"
				( objectStatus "@baseboard_fab2_lib.baseboard_fab2(sch_1):page40_i23:vss(748)" )
			)
			( pin "U5D1.AP59"
				( objectStatus "@baseboard_fab2_lib.baseboard_fab2(sch_1):page40_i23:vss(749)" )
			)
			( pin "U5D1.AP31"
				( objectStatus "@baseboard_fab2_lib.baseboard_fab2(sch_1):page40_i23:vss(750)" )
			)
			( pin "U5D1.AP19"
				( objectStatus "@baseboard_fab2_lib.baseboard_fab2(sch_1):page40_i23:vss(751)" )
			)
			( pin "U5D1.AP13"
				( objectStatus "@baseboard_fab2_lib.baseboard_fab2(sch_1):page40_i23:vss(752)" )
			)
			( pin "U5D1.AP9"
				( objectStatus "@baseboard_fab2_lib.baseboard_fab2(sch_1):page40_i23:vss(753)" )
			)
			( pin "U5D1.AP5"
				( objectStatus "@baseboard_fab2_lib.baseboard_fab2(sch_1):page40_i23:vss(754)" )
			)
			( pin "U5D1.AN78"
				( objectStatus "@baseboard_fab2_lib.baseboard_fab2(sch_1):page40_i23:vss(755)" )
			)
			( pin "U5D1.AN58"
				( objectStatus "@baseboard_fab2_lib.baseboard_fab2(sch_1):page40_i23:vss(756)" )
			)
			( pin "U5D1.AN28"
				( objectStatus "@baseboard_fab2_lib.baseboard_fab2(sch_1):page40_i23:vss(757)" )
			)
			( pin "U5D1.AN6"
				( objectStatus "@baseboard_fab2_lib.baseboard_fab2(sch_1):page40_i23:vss(758)" )
			)
			( pin "U5D1.AN2"
				( objectStatus "@baseboard_fab2_lib.baseboard_fab2(sch_1):page40_i23:vss(759)" )
			)
			( pin "U5D1.AM83"
				( objectStatus "@baseboard_fab2_lib.baseboard_fab2(sch_1):page40_i23:vss(760)" )
			)
			( pin "U5D1.AM79"
				( objectStatus "@baseboard_fab2_lib.baseboard_fab2(sch_1):page40_i23:vss(761)" )
			)
			( pin "U5D1.AM73"
				( objectStatus "@baseboard_fab2_lib.baseboard_fab2(sch_1):page40_i23:vss(762)" )
			)
			( pin "U5D1.AM69"
				( objectStatus "@baseboard_fab2_lib.baseboard_fab2(sch_1):page40_i23:vss(763)" )
			)
			( pin "U5D1.AM63"
				( objectStatus "@baseboard_fab2_lib.baseboard_fab2(sch_1):page40_i23:vss(764)" )
			)
			( pin "U5D1.AM57"
				( objectStatus "@baseboard_fab2_lib.baseboard_fab2(sch_1):page40_i23:vss(765)" )
			)
			( pin "U5D1.AM31"
				( objectStatus "@baseboard_fab2_lib.baseboard_fab2(sch_1):page40_i23:vss(766)" )
			)
			( pin "U5D1.AC50"
				( objectStatus "@baseboard_fab2_lib.baseboard_fab2(sch_1):page40_i23:vss(767)" )
			)
			( pin "U5D1.AM1"
				( objectStatus "@baseboard_fab2_lib.baseboard_fab2(sch_1):page40_i23:vss(768)" )
			)
			( pin "U5D1.AL86"
				( objectStatus "@baseboard_fab2_lib.baseboard_fab2(sch_1):page40_i23:vss(769)" )
			)
			( pin "U5D1.AL82"
				( objectStatus "@baseboard_fab2_lib.baseboard_fab2(sch_1):page40_i23:vss(770)" )
			)
			( pin "U5D1.AL80"
				( objectStatus "@baseboard_fab2_lib.baseboard_fab2(sch_1):page40_i23:vss(771)" )
			)
			( pin "U5D1.AL78"
				( objectStatus "@baseboard_fab2_lib.baseboard_fab2(sch_1):page40_i23:vss(772)" )
			)
			( pin "U5D1.AL76"
				( objectStatus "@baseboard_fab2_lib.baseboard_fab2(sch_1):page40_i23:vss(773)" )
			)
			( pin "U5D1.P49"
				( objectStatus "@baseboard_fab2_lib.baseboard_fab2(sch_1):page41_i283:vss(454)" )
			)
			( pin "U5D1.CJ12"
				( objectStatus "@baseboard_fab2_lib.baseboard_fab2(sch_1):page41_i283:vss(455)" )
			)
			( pin "U5D1.CJ10"
				( objectStatus "@baseboard_fab2_lib.baseboard_fab2(sch_1):page41_i283:vss(456)" )
			)
			( pin "U5D1.CJ8"
				( objectStatus "@baseboard_fab2_lib.baseboard_fab2(sch_1):page41_i283:vss(457)" )
			)
			( pin "U5D1.CJ6"
				( objectStatus "@baseboard_fab2_lib.baseboard_fab2(sch_1):page41_i283:vss(458)" )
			)
			( pin "U5D1.CJ2"
				( objectStatus "@baseboard_fab2_lib.baseboard_fab2(sch_1):page41_i283:vss(459)" )
			)
			( pin "U5D1.CH83"
				( objectStatus "@baseboard_fab2_lib.baseboard_fab2(sch_1):page41_i283:vss(460)" )
			)
			( pin "U5D1.CH81"
				( objectStatus "@baseboard_fab2_lib.baseboard_fab2(sch_1):page41_i283:vss(461)" )
			)
			( pin "U5D1.CH79"
				( objectStatus "@baseboard_fab2_lib.baseboard_fab2(sch_1):page41_i283:vss(462)" )
			)
			( pin "U5D1.CH73"
				( objectStatus "@baseboard_fab2_lib.baseboard_fab2(sch_1):page41_i283:vss(463)" )
			)
			( pin "U5D1.CH67"
				( objectStatus "@baseboard_fab2_lib.baseboard_fab2(sch_1):page41_i283:vss(464)" )
			)
			( pin "U5D1.CH63"
				( objectStatus "@baseboard_fab2_lib.baseboard_fab2(sch_1):page41_i283:vss(465)" )
			)
			( pin "U5D1.CH19"
				( objectStatus "@baseboard_fab2_lib.baseboard_fab2(sch_1):page41_i283:vss(466)" )
			)
			( pin "U5D1.CH15"
				( objectStatus "@baseboard_fab2_lib.baseboard_fab2(sch_1):page41_i283:vss(467)" )
			)
			( pin "U5D1.CH3"
				( objectStatus "@baseboard_fab2_lib.baseboard_fab2(sch_1):page41_i283:vss(468)" )
			)
			( pin "U5D1.CH1"
				( objectStatus "@baseboard_fab2_lib.baseboard_fab2(sch_1):page41_i283:vss(469)" )
			)
			( pin "U5D1.CG80"
				( objectStatus "@baseboard_fab2_lib.baseboard_fab2(sch_1):page41_i283:vss(470)" )
			)
			( pin "U5D1.CG72"
				( objectStatus "@baseboard_fab2_lib.baseboard_fab2(sch_1):page41_i283:vss(471)" )
			)
			( pin "U5D1.CG68"
				( objectStatus "@baseboard_fab2_lib.baseboard_fab2(sch_1):page41_i283:vss(472)" )
			)
			( pin "U5D1.CG62"
				( objectStatus "@baseboard_fab2_lib.baseboard_fab2(sch_1):page41_i283:vss(473)" )
			)
			( pin "U5D1.CG22"
				( objectStatus "@baseboard_fab2_lib.baseboard_fab2(sch_1):page41_i283:vss(474)" )
			)
			( pin "U5D1.CG18"
				( objectStatus "@baseboard_fab2_lib.baseboard_fab2(sch_1):page41_i283:vss(475)" )
			)
			( pin "U5D1.P51"
				( objectStatus "@baseboard_fab2_lib.baseboard_fab2(sch_1):page41_i283:vss(476)" )
			)
			( pin "U5D1.CF83"
				( objectStatus "@baseboard_fab2_lib.baseboard_fab2(sch_1):page41_i283:vss(477)" )
			)
			( pin "U5D1.CF77"
				( objectStatus "@baseboard_fab2_lib.baseboard_fab2(sch_1):page41_i283:vss(478)" )
			)
			( pin "U5D1.CF71"
				( objectStatus "@baseboard_fab2_lib.baseboard_fab2(sch_1):page41_i283:vss(479)" )
			)
			( pin "U5D1.CF69"
				( objectStatus "@baseboard_fab2_lib.baseboard_fab2(sch_1):page41_i283:vss(480)" )
			)
			( pin "U5D1.CF63"
				( objectStatus "@baseboard_fab2_lib.baseboard_fab2(sch_1):page41_i283:vss(481)" )
			)
			( pin "U5D1.CF9"
				( objectStatus "@baseboard_fab2_lib.baseboard_fab2(sch_1):page41_i283:vss(482)" )
			)
			( pin "U5D1.P53"
				( objectStatus "@baseboard_fab2_lib.baseboard_fab2(sch_1):page41_i283:vss(483)" )
			)
			( pin "U5D1.CE82"
				( objectStatus "@baseboard_fab2_lib.baseboard_fab2(sch_1):page41_i283:vss(484)" )
			)
			( pin "U5D1.CE70"
				( objectStatus "@baseboard_fab2_lib.baseboard_fab2(sch_1):page41_i283:vss(485)" )
			)
			( pin "U5D1.CE62"
				( objectStatus "@baseboard_fab2_lib.baseboard_fab2(sch_1):page41_i283:vss(486)" )
			)
			( pin "U5D1.CE26"
				( objectStatus "@baseboard_fab2_lib.baseboard_fab2(sch_1):page41_i283:vss(487)" )
			)
			( pin "U5D1.CE20"
				( objectStatus "@baseboard_fab2_lib.baseboard_fab2(sch_1):page41_i283:vss(488)" )
			)
			( pin "U5D1.CE14"
				( objectStatus "@baseboard_fab2_lib.baseboard_fab2(sch_1):page41_i283:vss(489)" )
			)
			( pin "U5D1.CE10"
				( objectStatus "@baseboard_fab2_lib.baseboard_fab2(sch_1):page41_i283:vss(490)" )
			)
			( pin "U5D1.CD81"
				( objectStatus "@baseboard_fab2_lib.baseboard_fab2(sch_1):page41_i283:vss(491)" )
			)
			( pin "U5D1.CD79"
				( objectStatus "@baseboard_fab2_lib.baseboard_fab2(sch_1):page41_i283:vss(492)" )
			)
			( pin "U5D1.CD77"
				( objectStatus "@baseboard_fab2_lib.baseboard_fab2(sch_1):page41_i283:vss(493)" )
			)
			( pin "U5D1.CD75"
				( objectStatus "@baseboard_fab2_lib.baseboard_fab2(sch_1):page41_i283:vss(494)" )
			)
			( pin "U5D1.CD73"
				( objectStatus "@baseboard_fab2_lib.baseboard_fab2(sch_1):page41_i283:vss(495)" )
			)
			( pin "U5D1.CD63"
				( objectStatus "@baseboard_fab2_lib.baseboard_fab2(sch_1):page41_i283:vss(496)" )
			)
			( pin "U5D1.CD13"
				( objectStatus "@baseboard_fab2_lib.baseboard_fab2(sch_1):page41_i283:vss(497)" )
			)
			( pin "U5D1.CD5"
				( objectStatus "@baseboard_fab2_lib.baseboard_fab2(sch_1):page41_i283:vss(498)" )
			)
			( pin "U5D1.CC82"
				( objectStatus "@baseboard_fab2_lib.baseboard_fab2(sch_1):page41_i283:vss(499)" )
			)
			( pin "U5D1.CC80"
				( objectStatus "@baseboard_fab2_lib.baseboard_fab2(sch_1):page41_i283:vss(500)" )
			)
			( pin "U5D1.CC78"
				( objectStatus "@baseboard_fab2_lib.baseboard_fab2(sch_1):page41_i283:vss(501)" )
			)
			( pin "U5D1.CC76"
				( objectStatus "@baseboard_fab2_lib.baseboard_fab2(sch_1):page41_i283:vss(502)" )
			)
			( pin "U5D1.CC74"
				( objectStatus "@baseboard_fab2_lib.baseboard_fab2(sch_1):page41_i283:vss(503)" )
			)
			( pin "U5D1.CC72"
				( objectStatus "@baseboard_fab2_lib.baseboard_fab2(sch_1):page41_i283:vss(504)" )
			)
			( pin "U5D1.CC64"
				( objectStatus "@baseboard_fab2_lib.baseboard_fab2(sch_1):page41_i283:vss(505)" )
			)
			( pin "U5D1.CC24"
				( objectStatus "@baseboard_fab2_lib.baseboard_fab2(sch_1):page41_i283:vss(506)" )
			)
			( pin "U5D1.CC18"
				( objectStatus "@baseboard_fab2_lib.baseboard_fab2(sch_1):page41_i283:vss(507)" )
			)
			( pin "U5D1.CC16"
				( objectStatus "@baseboard_fab2_lib.baseboard_fab2(sch_1):page41_i283:vss(508)" )
			)
			( pin "U5D1.CC4"
				( objectStatus "@baseboard_fab2_lib.baseboard_fab2(sch_1):page41_i283:vss(509)" )
			)
			( pin "U5D1.CB71"
				( objectStatus "@baseboard_fab2_lib.baseboard_fab2(sch_1):page41_i283:vss(510)" )
			)
			( pin "U5D1.CB63"
				( objectStatus "@baseboard_fab2_lib.baseboard_fab2(sch_1):page41_i283:vss(511)" )
			)
			( pin "U5D1.CB27"
				( objectStatus "@baseboard_fab2_lib.baseboard_fab2(sch_1):page41_i283:vss(512)" )
			)
			( pin "U5D1.CB9"
				( objectStatus "@baseboard_fab2_lib.baseboard_fab2(sch_1):page41_i283:vss(513)" )
			)
			( pin "U5D1.CB7"
				( objectStatus "@baseboard_fab2_lib.baseboard_fab2(sch_1):page41_i283:vss(514)" )
			)
			( pin "U5D1.CA70"
				( objectStatus "@baseboard_fab2_lib.baseboard_fab2(sch_1):page41_i283:vss(515)" )
			)
			( pin "U5D1.CA68"
				( objectStatus "@baseboard_fab2_lib.baseboard_fab2(sch_1):page41_i283:vss(516)" )
			)
			( pin "U5D1.CA66"
				( objectStatus "@baseboard_fab2_lib.baseboard_fab2(sch_1):page41_i283:vss(517)" )
			)
			( pin "U5D1.CA64"
				( objectStatus "@baseboard_fab2_lib.baseboard_fab2(sch_1):page41_i283:vss(518)" )
			)
			( pin "U5D1.CA26"
				( objectStatus "@baseboard_fab2_lib.baseboard_fab2(sch_1):page41_i283:vss(519)" )
			)
			( pin "U5D1.CA18"
				( objectStatus "@baseboard_fab2_lib.baseboard_fab2(sch_1):page41_i283:vss(520)" )
			)
			( pin "U5D1.CA14"
				( objectStatus "@baseboard_fab2_lib.baseboard_fab2(sch_1):page41_i283:vss(521)" )
			)
			( pin "U5D1.CA10"
				( objectStatus "@baseboard_fab2_lib.baseboard_fab2(sch_1):page41_i283:vss(522)" )
			)
			( pin "U5D1.CA8"
				( objectStatus "@baseboard_fab2_lib.baseboard_fab2(sch_1):page41_i283:vss(523)" )
			)
			( pin "U5D1.CA6"
				( objectStatus "@baseboard_fab2_lib.baseboard_fab2(sch_1):page41_i283:vss(524)" )
			)
			( pin "U5D1.CA2"
				( objectStatus "@baseboard_fab2_lib.baseboard_fab2(sch_1):page41_i283:vss(525)" )
			)
			( pin "U5D1.BY71"
				( objectStatus "@baseboard_fab2_lib.baseboard_fab2(sch_1):page41_i283:vss(526)" )
			)
			( pin "U5D1.BY69"
				( objectStatus "@baseboard_fab2_lib.baseboard_fab2(sch_1):page41_i283:vss(527)" )
			)
			( pin "U5D1.BY67"
				( objectStatus "@baseboard_fab2_lib.baseboard_fab2(sch_1):page41_i283:vss(528)" )
			)
			( pin "U5D1.BY65"
				( objectStatus "@baseboard_fab2_lib.baseboard_fab2(sch_1):page41_i283:vss(529)" )
			)
			( pin "U5D1.BY63"
				( objectStatus "@baseboard_fab2_lib.baseboard_fab2(sch_1):page41_i283:vss(530)" )
			)
			( pin "U5D1.BY23"
				( objectStatus "@baseboard_fab2_lib.baseboard_fab2(sch_1):page41_i283:vss(531)" )
			)
			( pin "U5D1.BY13"
				( objectStatus "@baseboard_fab2_lib.baseboard_fab2(sch_1):page41_i283:vss(532)" )
			)
			( pin "U5D1.BY11"
				( objectStatus "@baseboard_fab2_lib.baseboard_fab2(sch_1):page41_i283:vss(533)" )
			)
			( pin "U5D1.BW82"
				( objectStatus "@baseboard_fab2_lib.baseboard_fab2(sch_1):page41_i283:vss(534)" )
			)
			( pin "U5D1.BW80"
				( objectStatus "@baseboard_fab2_lib.baseboard_fab2(sch_1):page41_i283:vss(535)" )
			)
			( pin "U5D1.BW78"
				( objectStatus "@baseboard_fab2_lib.baseboard_fab2(sch_1):page41_i283:vss(536)" )
			)
			( pin "U5D1.BW76"
				( objectStatus "@baseboard_fab2_lib.baseboard_fab2(sch_1):page41_i283:vss(537)" )
			)
			( pin "U5D1.BW74"
				( objectStatus "@baseboard_fab2_lib.baseboard_fab2(sch_1):page41_i283:vss(538)" )
			)
			( pin "U5D1.BW72"
				( objectStatus "@baseboard_fab2_lib.baseboard_fab2(sch_1):page41_i283:vss(539)" )
			)
			( pin "U5D1.BW26"
				( objectStatus "@baseboard_fab2_lib.baseboard_fab2(sch_1):page41_i283:vss(540)" )
			)
			( pin "U5D1.BW18"
				( objectStatus "@baseboard_fab2_lib.baseboard_fab2(sch_1):page41_i283:vss(541)" )
			)
			( pin "U5D1.BW16"
				( objectStatus "@baseboard_fab2_lib.baseboard_fab2(sch_1):page41_i283:vss(542)" )
			)
			( pin "U5D1.BW14"
				( objectStatus "@baseboard_fab2_lib.baseboard_fab2(sch_1):page41_i283:vss(543)" )
			)
			( pin "U5D1.BW12"
				( objectStatus "@baseboard_fab2_lib.baseboard_fab2(sch_1):page41_i283:vss(544)" )
			)
			( pin "U5D1.P55"
				( objectStatus "@baseboard_fab2_lib.baseboard_fab2(sch_1):page41_i283:vss(545)" )
			)
			( pin "U5D1.BW6"
				( objectStatus "@baseboard_fab2_lib.baseboard_fab2(sch_1):page41_i283:vss(546)" )
			)
			( pin "U5D1.BV25"
				( objectStatus "@baseboard_fab2_lib.baseboard_fab2(sch_1):page41_i283:vss(547)" )
			)
			( pin "U5D1.BV17"
				( objectStatus "@baseboard_fab2_lib.baseboard_fab2(sch_1):page41_i283:vss(548)" )
			)
			( pin "U5D1.BU10"
				( objectStatus "@baseboard_fab2_lib.baseboard_fab2(sch_1):page41_i283:vss(549)" )
			)
			( pin "U5D1.BV5"
				( objectStatus "@baseboard_fab2_lib.baseboard_fab2(sch_1):page41_i283:vss(550)" )
			)
			( pin "U5D1.BU8"
				( objectStatus "@baseboard_fab2_lib.baseboard_fab2(sch_1):page41_i283:vss(551)" )
			)
			( pin "U5D1.BT25"
				( objectStatus "@baseboard_fab2_lib.baseboard_fab2(sch_1):page41_i283:vss(552)" )
			)
			( pin "U5D1.BT23"
				( objectStatus "@baseboard_fab2_lib.baseboard_fab2(sch_1):page41_i283:vss(553)" )
			)
			( pin "U5D1.BT21"
				( objectStatus "@baseboard_fab2_lib.baseboard_fab2(sch_1):page41_i283:vss(554)" )
			)
			( pin "U5D1.BT5"
				( objectStatus "@baseboard_fab2_lib.baseboard_fab2(sch_1):page41_i283:vss(555)" )
			)
			( pin "U5D1.BT3"
				( objectStatus "@baseboard_fab2_lib.baseboard_fab2(sch_1):page41_i283:vss(556)" )
			)
			( pin "U5D1.BR82"
				( objectStatus "@baseboard_fab2_lib.baseboard_fab2(sch_1):page41_i283:vss(557)" )
			)
			( pin "U5D1.BR80"
				( objectStatus "@baseboard_fab2_lib.baseboard_fab2(sch_1):page41_i283:vss(558)" )
			)
			( pin "U5D1.BR78"
				( objectStatus "@baseboard_fab2_lib.baseboard_fab2(sch_1):page41_i283:vss(559)" )
			)
			( pin "U5D1.BR76"
				( objectStatus "@baseboard_fab2_lib.baseboard_fab2(sch_1):page41_i283:vss(560)" )
			)
			( pin "U5D1.BR74"
				( objectStatus "@baseboard_fab2_lib.baseboard_fab2(sch_1):page41_i283:vss(561)" )
			)
			( pin "U5D1.BR72"
				( objectStatus "@baseboard_fab2_lib.baseboard_fab2(sch_1):page41_i283:vss(562)" )
			)
			( pin "U5D1.BR70"
				( objectStatus "@baseboard_fab2_lib.baseboard_fab2(sch_1):page41_i283:vss(563)" )
			)
			( pin "U5D1.BR68"
				( objectStatus "@baseboard_fab2_lib.baseboard_fab2(sch_1):page41_i283:vss(564)" )
			)
			( pin "U5D1.BR66"
				( objectStatus "@baseboard_fab2_lib.baseboard_fab2(sch_1):page41_i283:vss(565)" )
			)
			( pin "U5D1.BR64"
				( objectStatus "@baseboard_fab2_lib.baseboard_fab2(sch_1):page41_i283:vss(566)" )
			)
			( pin "U5D1.P57"
				( objectStatus "@baseboard_fab2_lib.baseboard_fab2(sch_1):page41_i283:vss(567)" )
			)
			( pin "U5D1.BR16"
				( objectStatus "@baseboard_fab2_lib.baseboard_fab2(sch_1):page41_i283:vss(568)" )
			)
			( pin "U5D1.BR10"
				( objectStatus "@baseboard_fab2_lib.baseboard_fab2(sch_1):page41_i283:vss(569)" )
			)
			( pin "U5D1.BR6"
				( objectStatus "@baseboard_fab2_lib.baseboard_fab2(sch_1):page41_i283:vss(570)" )
			)
			( pin "U5D1.BP27"
				( objectStatus "@baseboard_fab2_lib.baseboard_fab2(sch_1):page41_i283:vss(571)" )
			)
			( pin "U5D1.BP3"
				( objectStatus "@baseboard_fab2_lib.baseboard_fab2(sch_1):page41_i283:vss(572)" )
			)
			( pin "U5D1.BN26"
				( objectStatus "@baseboard_fab2_lib.baseboard_fab2(sch_1):page41_i283:vss(573)" )
			)
			( pin "U5D1.BN20"
				( objectStatus "@baseboard_fab2_lib.baseboard_fab2(sch_1):page41_i283:vss(574)" )
			)
			( pin "U5D1.BN10"
				( objectStatus "@baseboard_fab2_lib.baseboard_fab2(sch_1):page41_i283:vss(575)" )
			)
			( pin "U5D1.BN6"
				( objectStatus "@baseboard_fab2_lib.baseboard_fab2(sch_1):page41_i283:vss(576)" )
			)
			( pin "U5D1.BM25"
				( objectStatus "@baseboard_fab2_lib.baseboard_fab2(sch_1):page41_i283:vss(577)" )
			)
			( pin "U5D1.P59"
				( objectStatus "@baseboard_fab2_lib.baseboard_fab2(sch_1):page41_i283:vss(578)" )
			)
			( pin "U5D1.BM15"
				( objectStatus "@baseboard_fab2_lib.baseboard_fab2(sch_1):page41_i283:vss(579)" )
			)
			( pin "U5D1.BM13"
				( objectStatus "@baseboard_fab2_lib.baseboard_fab2(sch_1):page41_i283:vss(580)" )
			)
			( pin "U5D1.BM9"
				( objectStatus "@baseboard_fab2_lib.baseboard_fab2(sch_1):page41_i283:vss(581)" )
			)
			( pin "U5D1.BL82"
				( objectStatus "@baseboard_fab2_lib.baseboard_fab2(sch_1):page41_i283:vss(582)" )
			)
			( pin "U5D1.BL80"
				( objectStatus "@baseboard_fab2_lib.baseboard_fab2(sch_1):page41_i283:vss(583)" )
			)
			( pin "U5D1.BL78"
				( objectStatus "@baseboard_fab2_lib.baseboard_fab2(sch_1):page41_i283:vss(584)" )
			)
			( pin "U5D1.BL76"
				( objectStatus "@baseboard_fab2_lib.baseboard_fab2(sch_1):page41_i283:vss(585)" )
			)
			( pin "U5D1.BL74"
				( objectStatus "@baseboard_fab2_lib.baseboard_fab2(sch_1):page41_i283:vss(586)" )
			)
			( pin "U5D1.BL72"
				( objectStatus "@baseboard_fab2_lib.baseboard_fab2(sch_1):page41_i283:vss(587)" )
			)
			( pin "U5D1.BL70"
				( objectStatus "@baseboard_fab2_lib.baseboard_fab2(sch_1):page41_i283:vss(588)" )
			)
			( pin "U5D1.BL68"
				( objectStatus "@baseboard_fab2_lib.baseboard_fab2(sch_1):page41_i283:vss(589)" )
			)
			( pin "U5D1.BL66"
				( objectStatus "@baseboard_fab2_lib.baseboard_fab2(sch_1):page41_i283:vss(590)" )
			)
			( pin "U5D1.BL64"
				( objectStatus "@baseboard_fab2_lib.baseboard_fab2(sch_1):page41_i283:vss(591)" )
			)
			( pin "U5D1.BL24"
				( objectStatus "@baseboard_fab2_lib.baseboard_fab2(sch_1):page41_i283:vss(592)" )
			)
			( pin "U5D1.BL22"
				( objectStatus "@baseboard_fab2_lib.baseboard_fab2(sch_1):page41_i283:vss(593)" )
			)
			( pin "U5D1.P61"
				( objectStatus "@baseboard_fab2_lib.baseboard_fab2(sch_1):page41_i283:vss(594)" )
			)
			( pin "U5D1.BL12"
				( objectStatus "@baseboard_fab2_lib.baseboard_fab2(sch_1):page41_i283:vss(595)" )
			)
			( pin "U5D1.BL10"
				( objectStatus "@baseboard_fab2_lib.baseboard_fab2(sch_1):page41_i283:vss(596)" )
			)
			( pin "U5D1.BL6"
				( objectStatus "@baseboard_fab2_lib.baseboard_fab2(sch_1):page41_i283:vss(597)" )
			)
			( pin "U5D1.BK19"
				( objectStatus "@baseboard_fab2_lib.baseboard_fab2(sch_1):page41_i283:vss(598)" )
			)
			( pin "U5D1.BK11"
				( objectStatus "@baseboard_fab2_lib.baseboard_fab2(sch_1):page41_i283:vss(599)" )
			)
			( pin "U5D1.BK7"
				( objectStatus "@baseboard_fab2_lib.baseboard_fab2(sch_1):page41_i283:vss(600)" )
			)
			( pin "U5D1.BK3"
				( objectStatus "@baseboard_fab2_lib.baseboard_fab2(sch_1):page41_i283:vss(601)" )
			)
			( pin "U5D1.BJ6"
				( objectStatus "@baseboard_fab2_lib.baseboard_fab2(sch_1):page41_i283:vss(602)" )
			)
			( pin "U5D1.BJ4"
				( objectStatus "@baseboard_fab2_lib.baseboard_fab2(sch_1):page41_i283:vss(603)" )
			)
			( pin "U5D1.BH21"
				( objectStatus "@baseboard_fab2_lib.baseboard_fab2(sch_1):page41_i283:vss(604)" )
			)
			( pin "U5D1.BH15"
				( objectStatus "@baseboard_fab2_lib.baseboard_fab2(sch_1):page41_i283:vss(605)" )
			)
			( pin "U5D1.BH11"
				( objectStatus "@baseboard_fab2_lib.baseboard_fab2(sch_1):page41_i283:vss(606)" )
			)
			( pin "U5D1.BH9"
				( objectStatus "@baseboard_fab2_lib.baseboard_fab2(sch_1):page41_i283:vss(607)" )
			)
			( pin "U5D1.BH7"
				( objectStatus "@baseboard_fab2_lib.baseboard_fab2(sch_1):page41_i283:vss(608)" )
			)
			( pin "U5D1.BG82"
				( objectStatus "@baseboard_fab2_lib.baseboard_fab2(sch_1):page41_i283:vss(609)" )
			)
			( pin "U5D1.BG80"
				( objectStatus "@baseboard_fab2_lib.baseboard_fab2(sch_1):page41_i283:vss(610)" )
			)
			( pin "U5D1.BG78"
				( objectStatus "@baseboard_fab2_lib.baseboard_fab2(sch_1):page41_i283:vss(611)" )
			)
			( pin "U5D1.BG76"
				( objectStatus "@baseboard_fab2_lib.baseboard_fab2(sch_1):page41_i283:vss(612)" )
			)
			( pin "U5D1.BG74"
				( objectStatus "@baseboard_fab2_lib.baseboard_fab2(sch_1):page41_i283:vss(613)" )
			)
			( pin "U5D1.DA46"
				( objectStatus "@baseboard_fab2_lib.baseboard_fab2(sch_1):page41_i284:vss(294)" )
			)
			( pin "U5D1.DA44"
				( objectStatus "@baseboard_fab2_lib.baseboard_fab2(sch_1):page41_i284:vss(295)" )
			)
			( pin "U5D1.DA38"
				( objectStatus "@baseboard_fab2_lib.baseboard_fab2(sch_1):page41_i284:vss(296)" )
			)
			( pin "U5D1.DA36"
				( objectStatus "@baseboard_fab2_lib.baseboard_fab2(sch_1):page41_i284:vss(297)" )
			)
			( pin "U5D1.DA34"
				( objectStatus "@baseboard_fab2_lib.baseboard_fab2(sch_1):page41_i284:vss(298)" )
			)
			( pin "U5D1.DA32"
				( objectStatus "@baseboard_fab2_lib.baseboard_fab2(sch_1):page41_i284:vss(299)" )
			)
			( pin "U5D1.DA30"
				( objectStatus "@baseboard_fab2_lib.baseboard_fab2(sch_1):page41_i284:vss(300)" )
			)
			( pin "U5D1.DA28"
				( objectStatus "@baseboard_fab2_lib.baseboard_fab2(sch_1):page41_i284:vss(301)" )
			)
			( pin "U5D1.DA26"
				( objectStatus "@baseboard_fab2_lib.baseboard_fab2(sch_1):page41_i284:vss(302)" )
			)
			( pin "U5D1.DA18"
				( objectStatus "@baseboard_fab2_lib.baseboard_fab2(sch_1):page41_i284:vss(303)" )
			)
			( pin "U5D1.H53"
				( objectStatus "@baseboard_fab2_lib.baseboard_fab2(sch_1):page41_i284:vss(304)" )
			)
			( pin "U5D1.DA6"
				( objectStatus "@baseboard_fab2_lib.baseboard_fab2(sch_1):page41_i284:vss(305)" )
			)
			( pin "U5D1.CY85"
				( objectStatus "@baseboard_fab2_lib.baseboard_fab2(sch_1):page41_i284:vss(306)" )
			)
			( pin "U5D1.CY83"
				( objectStatus "@baseboard_fab2_lib.baseboard_fab2(sch_1):page41_i284:vss(307)" )
			)
			( pin "U5D1.CY77"
				( objectStatus "@baseboard_fab2_lib.baseboard_fab2(sch_1):page41_i284:vss(308)" )
			)
			( pin "U5D1.CY75"
				( objectStatus "@baseboard_fab2_lib.baseboard_fab2(sch_1):page41_i284:vss(309)" )
			)
			( pin "U5D1.CY69"
				( objectStatus "@baseboard_fab2_lib.baseboard_fab2(sch_1):page41_i284:vss(310)" )
			)
			( pin "U5D1.CY65"
				( objectStatus "@baseboard_fab2_lib.baseboard_fab2(sch_1):page41_i284:vss(311)" )
			)
			( pin "U5D1.CY61"
				( objectStatus "@baseboard_fab2_lib.baseboard_fab2(sch_1):page41_i284:vss(312)" )
			)
			( pin "U5D1.CY59"
				( objectStatus "@baseboard_fab2_lib.baseboard_fab2(sch_1):page41_i284:vss(313)" )
			)
			( pin "U5D1.CY51"
				( objectStatus "@baseboard_fab2_lib.baseboard_fab2(sch_1):page41_i284:vss(314)" )
			)
			( pin "U5D1.CY45"
				( objectStatus "@baseboard_fab2_lib.baseboard_fab2(sch_1):page41_i284:vss(315)" )
			)
			( pin "U5D1.CY41"
				( objectStatus "@baseboard_fab2_lib.baseboard_fab2(sch_1):page41_i284:vss(316)" )
			)
			( pin "U5D1.CY21"
				( objectStatus "@baseboard_fab2_lib.baseboard_fab2(sch_1):page41_i284:vss(317)" )
			)
			( pin "U5D1.CY15"
				( objectStatus "@baseboard_fab2_lib.baseboard_fab2(sch_1):page41_i284:vss(318)" )
			)
			( pin "U5D1.CY13"
				( objectStatus "@baseboard_fab2_lib.baseboard_fab2(sch_1):page41_i284:vss(319)" )
			)
			( pin "U5D1.CY9"
				( objectStatus "@baseboard_fab2_lib.baseboard_fab2(sch_1):page41_i284:vss(320)" )
			)
			( pin "U5D1.CY1"
				( objectStatus "@baseboard_fab2_lib.baseboard_fab2(sch_1):page41_i284:vss(321)" )
			)
			( pin "U5D1.CW82"
				( objectStatus "@baseboard_fab2_lib.baseboard_fab2(sch_1):page41_i284:vss(322)" )
			)
			( pin "U5D1.CW78"
				( objectStatus "@baseboard_fab2_lib.baseboard_fab2(sch_1):page41_i284:vss(323)" )
			)
			( pin "U5D1.CW74"
				( objectStatus "@baseboard_fab2_lib.baseboard_fab2(sch_1):page41_i284:vss(324)" )
			)
			( pin "U5D1.CW68"
				( objectStatus "@baseboard_fab2_lib.baseboard_fab2(sch_1):page41_i284:vss(325)" )
			)
			( pin "U5D1.CW66"
				( objectStatus "@baseboard_fab2_lib.baseboard_fab2(sch_1):page41_i284:vss(326)" )
			)
			( pin "U5D1.CW64"
				( objectStatus "@baseboard_fab2_lib.baseboard_fab2(sch_1):page41_i284:vss(327)" )
			)
			( pin "U5D1.CW54"
				( objectStatus "@baseboard_fab2_lib.baseboard_fab2(sch_1):page41_i284:vss(328)" )
			)
			( pin "U5D1.CW52"
				( objectStatus "@baseboard_fab2_lib.baseboard_fab2(sch_1):page41_i284:vss(329)" )
			)
			( pin "U5D1.CW42"
				( objectStatus "@baseboard_fab2_lib.baseboard_fab2(sch_1):page41_i284:vss(330)" )
			)
			( pin "U5D1.CW40"
				( objectStatus "@baseboard_fab2_lib.baseboard_fab2(sch_1):page41_i284:vss(331)" )
			)
			( pin "U5D1.CW38"
				( objectStatus "@baseboard_fab2_lib.baseboard_fab2(sch_1):page41_i284:vss(332)" )
			)
			( pin "U5D1.CW32"
				( objectStatus "@baseboard_fab2_lib.baseboard_fab2(sch_1):page41_i284:vss(333)" )
			)
			( pin "U5D1.CW26"
				( objectStatus "@baseboard_fab2_lib.baseboard_fab2(sch_1):page41_i284:vss(334)" )
			)
			( pin "U5D1.CW12"
				( objectStatus "@baseboard_fab2_lib.baseboard_fab2(sch_1):page41_i284:vss(335)" )
			)
			( pin "U5D1.CV83"
				( objectStatus "@baseboard_fab2_lib.baseboard_fab2(sch_1):page41_i284:vss(336)" )
			)
			( pin "U5D1.CV81"
				( objectStatus "@baseboard_fab2_lib.baseboard_fab2(sch_1):page41_i284:vss(337)" )
			)
			( pin "U5D1.CV79"
				( objectStatus "@baseboard_fab2_lib.baseboard_fab2(sch_1):page41_i284:vss(338)" )
			)
			( pin "U5D1.CV73"
				( objectStatus "@baseboard_fab2_lib.baseboard_fab2(sch_1):page41_i284:vss(339)" )
			)
			( pin "U5D1.CV67"
				( objectStatus "@baseboard_fab2_lib.baseboard_fab2(sch_1):page41_i284:vss(340)" )
			)
			( pin "U5D1.CV63"
				( objectStatus "@baseboard_fab2_lib.baseboard_fab2(sch_1):page41_i284:vss(341)" )
			)
			( pin "U5D1.CV55"
				( objectStatus "@baseboard_fab2_lib.baseboard_fab2(sch_1):page41_i284:vss(342)" )
			)
			( pin "U5D1.CV53"
				( objectStatus "@baseboard_fab2_lib.baseboard_fab2(sch_1):page41_i284:vss(343)" )
			)
			( pin "U5D1.CV41"
				( objectStatus "@baseboard_fab2_lib.baseboard_fab2(sch_1):page41_i284:vss(344)" )
			)
			( pin "U5D1.CV39"
				( objectStatus "@baseboard_fab2_lib.baseboard_fab2(sch_1):page41_i284:vss(345)" )
			)
			( pin "U5D1.CV37"
				( objectStatus "@baseboard_fab2_lib.baseboard_fab2(sch_1):page41_i284:vss(346)" )
			)
			( pin "U5D1.CV33"
				( objectStatus "@baseboard_fab2_lib.baseboard_fab2(sch_1):page41_i284:vss(347)" )
			)
			( pin "U5D1.CV31"
				( objectStatus "@baseboard_fab2_lib.baseboard_fab2(sch_1):page41_i284:vss(348)" )
			)
			( pin "U5D1.CV27"
				( objectStatus "@baseboard_fab2_lib.baseboard_fab2(sch_1):page41_i284:vss(349)" )
			)
			( pin "U5D1.CV25"
				( objectStatus "@baseboard_fab2_lib.baseboard_fab2(sch_1):page41_i284:vss(350)" )
			)
			( pin "U5D1.CV17"
				( objectStatus "@baseboard_fab2_lib.baseboard_fab2(sch_1):page41_i284:vss(351)" )
			)
			( pin "U5D1.H55"
				( objectStatus "@baseboard_fab2_lib.baseboard_fab2(sch_1):page41_i284:vss(352)" )
			)
			( pin "U5D1.CV1"
				( objectStatus "@baseboard_fab2_lib.baseboard_fab2(sch_1):page41_i284:vss(353)" )
			)
			( pin "U5D1.CU86"
				( objectStatus "@baseboard_fab2_lib.baseboard_fab2(sch_1):page41_i284:vss(354)" )
			)
			( pin "U5D1.CU82"
				( objectStatus "@baseboard_fab2_lib.baseboard_fab2(sch_1):page41_i284:vss(355)" )
			)
			( pin "U5D1.CU80"
				( objectStatus "@baseboard_fab2_lib.baseboard_fab2(sch_1):page41_i284:vss(356)" )
			)
			( pin "U5D1.CU78"
				( objectStatus "@baseboard_fab2_lib.baseboard_fab2(sch_1):page41_i284:vss(357)" )
			)
			( pin "U5D1.CU76"
				( objectStatus "@baseboard_fab2_lib.baseboard_fab2(sch_1):page41_i284:vss(358)" )
			)
			( pin "U5D1.CU68"
				( objectStatus "@baseboard_fab2_lib.baseboard_fab2(sch_1):page41_i284:vss(359)" )
			)
			( pin "U5D1.CU62"
				( objectStatus "@baseboard_fab2_lib.baseboard_fab2(sch_1):page41_i284:vss(360)" )
			)
			( pin "U5D1.CU56"
				( objectStatus "@baseboard_fab2_lib.baseboard_fab2(sch_1):page41_i284:vss(361)" )
			)
			( pin "U5D1.CU36"
				( objectStatus "@baseboard_fab2_lib.baseboard_fab2(sch_1):page41_i284:vss(362)" )
			)
			( pin "U5D1.CU34"
				( objectStatus "@baseboard_fab2_lib.baseboard_fab2(sch_1):page41_i284:vss(363)" )
			)
			( pin "U5D1.CU30"
				( objectStatus "@baseboard_fab2_lib.baseboard_fab2(sch_1):page41_i284:vss(364)" )
			)
			( pin "U5D1.CU28"
				( objectStatus "@baseboard_fab2_lib.baseboard_fab2(sch_1):page41_i284:vss(365)" )
			)
			( pin "U5D1.CU22"
				( objectStatus "@baseboard_fab2_lib.baseboard_fab2(sch_1):page41_i284:vss(366)" )
			)
			( pin "U5D1.CU4"
				( objectStatus "@baseboard_fab2_lib.baseboard_fab2(sch_1):page41_i284:vss(367)" )
			)
			( pin "U5D1.CT85"
				( objectStatus "@baseboard_fab2_lib.baseboard_fab2(sch_1):page41_i284:vss(368)" )
			)
			( pin "U5D1.CT83"
				( objectStatus "@baseboard_fab2_lib.baseboard_fab2(sch_1):page41_i284:vss(369)" )
			)
			( pin "U5D1.CT79"
				( objectStatus "@baseboard_fab2_lib.baseboard_fab2(sch_1):page41_i284:vss(370)" )
			)
			( pin "U5D1.CT73"
				( objectStatus "@baseboard_fab2_lib.baseboard_fab2(sch_1):page41_i284:vss(371)" )
			)
			( pin "U5D1.CT57"
				( objectStatus "@baseboard_fab2_lib.baseboard_fab2(sch_1):page41_i284:vss(372)" )
			)
			( pin "U5D1.CT35"
				( objectStatus "@baseboard_fab2_lib.baseboard_fab2(sch_1):page41_i284:vss(373)" )
			)
			( pin "U5D1.CT33"
				( objectStatus "@baseboard_fab2_lib.baseboard_fab2(sch_1):page41_i284:vss(374)" )
			)
			( pin "U5D1.CT29"
				( objectStatus "@baseboard_fab2_lib.baseboard_fab2(sch_1):page41_i284:vss(375)" )
			)
			( pin "U5D1.CT27"
				( objectStatus "@baseboard_fab2_lib.baseboard_fab2(sch_1):page41_i284:vss(376)" )
			)
			( pin "U5D1.CT19"
				( objectStatus "@baseboard_fab2_lib.baseboard_fab2(sch_1):page41_i284:vss(377)" )
			)
			( pin "U5D1.CT13"
				( objectStatus "@baseboard_fab2_lib.baseboard_fab2(sch_1):page41_i284:vss(378)" )
			)
			( pin "U5D1.H57"
				( objectStatus "@baseboard_fab2_lib.baseboard_fab2(sch_1):page41_i284:vss(379)" )
			)
			( pin "U5D1.CR86"
				( objectStatus "@baseboard_fab2_lib.baseboard_fab2(sch_1):page41_i284:vss(380)" )
			)
			( pin "U5D1.CR78"
				( objectStatus "@baseboard_fab2_lib.baseboard_fab2(sch_1):page41_i284:vss(381)" )
			)
			( pin "U5D1.CR68"
				( objectStatus "@baseboard_fab2_lib.baseboard_fab2(sch_1):page41_i284:vss(382)" )
			)
			( pin "U5D1.CR66"
				( objectStatus "@baseboard_fab2_lib.baseboard_fab2(sch_1):page41_i284:vss(383)" )
			)
			( pin "U5D1.CR64"
				( objectStatus "@baseboard_fab2_lib.baseboard_fab2(sch_1):page41_i284:vss(384)" )
			)
			( pin "U5D1.CR62"
				( objectStatus "@baseboard_fab2_lib.baseboard_fab2(sch_1):page41_i284:vss(385)" )
			)
			( pin "U5D1.CR58"
				( objectStatus "@baseboard_fab2_lib.baseboard_fab2(sch_1):page41_i284:vss(386)" )
			)
			( pin "U5D1.CR32"
				( objectStatus "@baseboard_fab2_lib.baseboard_fab2(sch_1):page41_i284:vss(387)" )
			)
			( pin "U5D1.CR24"
				( objectStatus "@baseboard_fab2_lib.baseboard_fab2(sch_1):page41_i284:vss(388)" )
			)
			( pin "U5D1.CR22"
				( objectStatus "@baseboard_fab2_lib.baseboard_fab2(sch_1):page41_i284:vss(389)" )
			)
			( pin "U5D1.CR10"
				( objectStatus "@baseboard_fab2_lib.baseboard_fab2(sch_1):page41_i284:vss(390)" )
			)
			( pin "U5D1.CR6"
				( objectStatus "@baseboard_fab2_lib.baseboard_fab2(sch_1):page41_i284:vss(391)" )
			)
			( pin "U5D1.CP83"
				( objectStatus "@baseboard_fab2_lib.baseboard_fab2(sch_1):page41_i284:vss(392)" )
			)
			( pin "U5D1.CP81"
				( objectStatus "@baseboard_fab2_lib.baseboard_fab2(sch_1):page41_i284:vss(393)" )
			)
			( pin "U5D1.CP75"
				( objectStatus "@baseboard_fab2_lib.baseboard_fab2(sch_1):page41_i284:vss(394)" )
			)
			( pin "U5D1.CP73"
				( objectStatus "@baseboard_fab2_lib.baseboard_fab2(sch_1):page41_i284:vss(395)" )
			)
			( pin "U5D1.CP69"
				( objectStatus "@baseboard_fab2_lib.baseboard_fab2(sch_1):page41_i284:vss(396)" )
			)
			( pin "U5D1.CP59"
				( objectStatus "@baseboard_fab2_lib.baseboard_fab2(sch_1):page41_i284:vss(397)" )
			)
			( pin "U5D1.CP25"
				( objectStatus "@baseboard_fab2_lib.baseboard_fab2(sch_1):page41_i284:vss(398)" )
			)
			( pin "U5D1.H59"
				( objectStatus "@baseboard_fab2_lib.baseboard_fab2(sch_1):page41_i284:vss(399)" )
			)
			( pin "U5D1.CP1"
				( objectStatus "@baseboard_fab2_lib.baseboard_fab2(sch_1):page41_i284:vss(400)" )
			)
			( pin "U5D1.CN78"
				( objectStatus "@baseboard_fab2_lib.baseboard_fab2(sch_1):page41_i284:vss(401)" )
			)
			( pin "U5D1.CN68"
				( objectStatus "@baseboard_fab2_lib.baseboard_fab2(sch_1):page41_i284:vss(402)" )
			)
			( pin "U5D1.CN62"
				( objectStatus "@baseboard_fab2_lib.baseboard_fab2(sch_1):page41_i284:vss(403)" )
			)
			( pin "U5D1.CN60"
				( objectStatus "@baseboard_fab2_lib.baseboard_fab2(sch_1):page41_i284:vss(404)" )
			)
			( pin "U5D1.CN32"
				( objectStatus "@baseboard_fab2_lib.baseboard_fab2(sch_1):page41_i284:vss(405)" )
			)
			( pin "U5D1.CN26"
				( objectStatus "@baseboard_fab2_lib.baseboard_fab2(sch_1):page41_i284:vss(406)" )
			)
			( pin "U5D1.H61"
				( objectStatus "@baseboard_fab2_lib.baseboard_fab2(sch_1):page41_i284:vss(407)" )
			)
			( pin "U5D1.CN12"
				( objectStatus "@baseboard_fab2_lib.baseboard_fab2(sch_1):page41_i284:vss(408)" )
			)
			( pin "U5D1.CN2"
				( objectStatus "@baseboard_fab2_lib.baseboard_fab2(sch_1):page41_i284:vss(409)" )
			)
			( pin "U5D1.CM85"
				( objectStatus "@baseboard_fab2_lib.baseboard_fab2(sch_1):page41_i284:vss(410)" )
			)
			( pin "U5D1.CM83"
				( objectStatus "@baseboard_fab2_lib.baseboard_fab2(sch_1):page41_i284:vss(411)" )
			)
			( pin "U5D1.CM77"
				( objectStatus "@baseboard_fab2_lib.baseboard_fab2(sch_1):page41_i284:vss(412)" )
			)
			( pin "U5D1.CM73"
				( objectStatus "@baseboard_fab2_lib.baseboard_fab2(sch_1):page41_i284:vss(413)" )
			)
			( pin "U5D1.CM67"
				( objectStatus "@baseboard_fab2_lib.baseboard_fab2(sch_1):page41_i284:vss(414)" )
			)
			( pin "U5D1.CM63"
				( objectStatus "@baseboard_fab2_lib.baseboard_fab2(sch_1):page41_i284:vss(415)" )
			)
			( pin "U5D1.CM61"
				( objectStatus "@baseboard_fab2_lib.baseboard_fab2(sch_1):page41_i284:vss(416)" )
			)
			( pin "U5D1.CM31"
				( objectStatus "@baseboard_fab2_lib.baseboard_fab2(sch_1):page41_i284:vss(417)" )
			)
			( pin "U5D1.CM5"
				( objectStatus "@baseboard_fab2_lib.baseboard_fab2(sch_1):page41_i284:vss(418)" )
			)
			( pin "U5D1.CM29"
				( objectStatus "@baseboard_fab2_lib.baseboard_fab2(sch_1):page41_i284:vss(419)" )
			)
			( pin "U5D1.CM19"
				( objectStatus "@baseboard_fab2_lib.baseboard_fab2(sch_1):page41_i284:vss(420)" )
			)
			( pin "U5D1.CL80"
				( objectStatus "@baseboard_fab2_lib.baseboard_fab2(sch_1):page41_i284:vss(421)" )
			)
			( pin "U5D1.CL78"
				( objectStatus "@baseboard_fab2_lib.baseboard_fab2(sch_1):page41_i284:vss(422)" )
			)
			( pin "U5D1.CL76"
				( objectStatus "@baseboard_fab2_lib.baseboard_fab2(sch_1):page41_i284:vss(423)" )
			)
			( pin "U5D1.CL74"
				( objectStatus "@baseboard_fab2_lib.baseboard_fab2(sch_1):page41_i284:vss(424)" )
			)
			( pin "U5D1.CL66"
				( objectStatus "@baseboard_fab2_lib.baseboard_fab2(sch_1):page41_i284:vss(425)" )
			)
			( pin "U5D1.CL64"
				( objectStatus "@baseboard_fab2_lib.baseboard_fab2(sch_1):page41_i284:vss(426)" )
			)
			( pin "U5D1.CL62"
				( objectStatus "@baseboard_fab2_lib.baseboard_fab2(sch_1):page41_i284:vss(427)" )
			)
			( pin "U5D1.H63"
				( objectStatus "@baseboard_fab2_lib.baseboard_fab2(sch_1):page41_i284:vss(428)" )
			)
			( pin "U5D1.P45"
				( objectStatus "@baseboard_fab2_lib.baseboard_fab2(sch_1):page41_i284:vss(429)" )
			)
			( pin "U5D1.CL18"
				( objectStatus "@baseboard_fab2_lib.baseboard_fab2(sch_1):page41_i284:vss(430)" )
			)
			( pin "U5D1.CL14"
				( objectStatus "@baseboard_fab2_lib.baseboard_fab2(sch_1):page41_i284:vss(431)" )
			)
			( pin "U5D1.CL8"
				( objectStatus "@baseboard_fab2_lib.baseboard_fab2(sch_1):page41_i284:vss(432)" )
			)
			( pin "U5D1.CK85"
				( objectStatus "@baseboard_fab2_lib.baseboard_fab2(sch_1):page41_i284:vss(433)" )
			)
			( pin "U5D1.CK83"
				( objectStatus "@baseboard_fab2_lib.baseboard_fab2(sch_1):page41_i284:vss(434)" )
			)
			( pin "U5D1.CK75"
				( objectStatus "@baseboard_fab2_lib.baseboard_fab2(sch_1):page41_i284:vss(435)" )
			)
			( pin "U5D1.CK73"
				( objectStatus "@baseboard_fab2_lib.baseboard_fab2(sch_1):page41_i284:vss(436)" )
			)
			( pin "U5D1.CK71"
				( objectStatus "@baseboard_fab2_lib.baseboard_fab2(sch_1):page41_i284:vss(437)" )
			)
			( pin "U5D1.CK69"
				( objectStatus "@baseboard_fab2_lib.baseboard_fab2(sch_1):page41_i284:vss(438)" )
			)
			( pin "U5D1.CK67"
				( objectStatus "@baseboard_fab2_lib.baseboard_fab2(sch_1):page41_i284:vss(439)" )
			)
			( pin "U5D1.CK65"
				( objectStatus "@baseboard_fab2_lib.baseboard_fab2(sch_1):page41_i284:vss(440)" )
			)
			( pin "U5D1.CK63"
				( objectStatus "@baseboard_fab2_lib.baseboard_fab2(sch_1):page41_i284:vss(441)" )
			)
			( pin "U5D1.CK27"
				( objectStatus "@baseboard_fab2_lib.baseboard_fab2(sch_1):page41_i284:vss(442)" )
			)
			( pin "U5D1.CK21"
				( objectStatus "@baseboard_fab2_lib.baseboard_fab2(sch_1):page41_i284:vss(443)" )
			)
			( pin "U5D1.CK15"
				( objectStatus "@baseboard_fab2_lib.baseboard_fab2(sch_1):page41_i284:vss(444)" )
			)
			( pin "U5D1.CK11"
				( objectStatus "@baseboard_fab2_lib.baseboard_fab2(sch_1):page41_i284:vss(445)" )
			)
			( pin "U5D1.CJ86"
				( objectStatus "@baseboard_fab2_lib.baseboard_fab2(sch_1):page41_i284:vss(446)" )
			)
			( pin "U5D1.CJ84"
				( objectStatus "@baseboard_fab2_lib.baseboard_fab2(sch_1):page41_i284:vss(447)" )
			)
			( pin "U5D1.CJ82"
				( objectStatus "@baseboard_fab2_lib.baseboard_fab2(sch_1):page41_i284:vss(448)" )
			)
			( pin "U5D1.CJ78"
				( objectStatus "@baseboard_fab2_lib.baseboard_fab2(sch_1):page41_i284:vss(449)" )
			)
			( pin "U5D1.CJ76"
				( objectStatus "@baseboard_fab2_lib.baseboard_fab2(sch_1):page41_i284:vss(450)" )
			)
			( pin "U5D1.CJ74"
				( objectStatus "@baseboard_fab2_lib.baseboard_fab2(sch_1):page41_i284:vss(451)" )
			)
			( pin "U5D1.CJ62"
				( objectStatus "@baseboard_fab2_lib.baseboard_fab2(sch_1):page41_i284:vss(452)" )
			)
			( pin "U5D1.P47"
				( objectStatus "@baseboard_fab2_lib.baseboard_fab2(sch_1):page41_i284:vss(453)" )
			)
			( pin "U5D1.DN72"
				( objectStatus "@baseboard_fab2_lib.baseboard_fab2(sch_1):page41_i285:vss(134)" )
			)
			( pin "U5D1.DN68"
				( objectStatus "@baseboard_fab2_lib.baseboard_fab2(sch_1):page41_i285:vss(135)" )
			)
			( pin "U5D1.DN38"
				( objectStatus "@baseboard_fab2_lib.baseboard_fab2(sch_1):page41_i285:vss(136)" )
			)
			( pin "U5D1.DN32"
				( objectStatus "@baseboard_fab2_lib.baseboard_fab2(sch_1):page41_i285:vss(137)" )
			)
			( pin "U5D1.DN26"
				( objectStatus "@baseboard_fab2_lib.baseboard_fab2(sch_1):page41_i285:vss(138)" )
			)
			( pin "U5D1.DN22"
				( objectStatus "@baseboard_fab2_lib.baseboard_fab2(sch_1):page41_i285:vss(139)" )
			)
			( pin "U5D1.DN12"
				( objectStatus "@baseboard_fab2_lib.baseboard_fab2(sch_1):page41_i285:vss(140)" )
			)
			( pin "U5D1.BH17"
				( objectStatus "@baseboard_fab2_lib.baseboard_fab2(sch_1):page41_i285:vss(141)" )
			)
			( pin "U5D1.DN2"
				( objectStatus "@baseboard_fab2_lib.baseboard_fab2(sch_1):page41_i285:vss(142)" )
			)
			( pin "U5D1.DM83"
				( objectStatus "@baseboard_fab2_lib.baseboard_fab2(sch_1):page41_i285:vss(143)" )
			)
			( pin "U5D1.DM77"
				( objectStatus "@baseboard_fab2_lib.baseboard_fab2(sch_1):page41_i285:vss(144)" )
			)
			( pin "U5D1.DM73"
				( objectStatus "@baseboard_fab2_lib.baseboard_fab2(sch_1):page41_i285:vss(145)" )
			)
			( pin "U5D1.DM65"
				( objectStatus "@baseboard_fab2_lib.baseboard_fab2(sch_1):page41_i285:vss(146)" )
			)
			( pin "U5D1.DM39"
				( objectStatus "@baseboard_fab2_lib.baseboard_fab2(sch_1):page41_i285:vss(147)" )
			)
			( pin "U5D1.DM37"
				( objectStatus "@baseboard_fab2_lib.baseboard_fab2(sch_1):page41_i285:vss(148)" )
			)
			( pin "U5D1.DM33"
				( objectStatus "@baseboard_fab2_lib.baseboard_fab2(sch_1):page41_i285:vss(149)" )
			)
			( pin "U5D1.DM31"
				( objectStatus "@baseboard_fab2_lib.baseboard_fab2(sch_1):page41_i285:vss(150)" )
			)
			( pin "U5D1.DM27"
				( objectStatus "@baseboard_fab2_lib.baseboard_fab2(sch_1):page41_i285:vss(151)" )
			)
			( pin "U5D1.DM25"
				( objectStatus "@baseboard_fab2_lib.baseboard_fab2(sch_1):page41_i285:vss(152)" )
			)
			( pin "U5D1.H45"
				( objectStatus "@baseboard_fab2_lib.baseboard_fab2(sch_1):page41_i285:vss(153)" )
			)
			( pin "U5D1.DM15"
				( objectStatus "@baseboard_fab2_lib.baseboard_fab2(sch_1):page41_i285:vss(154)" )
			)
			( pin "U5D1.DL80"
				( objectStatus "@baseboard_fab2_lib.baseboard_fab2(sch_1):page41_i285:vss(155)" )
			)
			( pin "U5D1.DL78"
				( objectStatus "@baseboard_fab2_lib.baseboard_fab2(sch_1):page41_i285:vss(156)" )
			)
			( pin "U5D1.DL76"
				( objectStatus "@baseboard_fab2_lib.baseboard_fab2(sch_1):page41_i285:vss(157)" )
			)
			( pin "U5D1.DL74"
				( objectStatus "@baseboard_fab2_lib.baseboard_fab2(sch_1):page41_i285:vss(158)" )
			)
			( pin "U5D1.DL70"
				( objectStatus "@baseboard_fab2_lib.baseboard_fab2(sch_1):page41_i285:vss(159)" )
			)
			( pin "U5D1.DL68"
				( objectStatus "@baseboard_fab2_lib.baseboard_fab2(sch_1):page41_i285:vss(160)" )
			)
			( pin "U5D1.DL40"
				( objectStatus "@baseboard_fab2_lib.baseboard_fab2(sch_1):page41_i285:vss(161)" )
			)
			( pin "U5D1.DL36"
				( objectStatus "@baseboard_fab2_lib.baseboard_fab2(sch_1):page41_i285:vss(162)" )
			)
			( pin "U5D1.DL34"
				( objectStatus "@baseboard_fab2_lib.baseboard_fab2(sch_1):page41_i285:vss(163)" )
			)
			( pin "U5D1.DL30"
				( objectStatus "@baseboard_fab2_lib.baseboard_fab2(sch_1):page41_i285:vss(164)" )
			)
			( pin "U5D1.DL28"
				( objectStatus "@baseboard_fab2_lib.baseboard_fab2(sch_1):page41_i285:vss(165)" )
			)
			( pin "U5D1.DL24"
				( objectStatus "@baseboard_fab2_lib.baseboard_fab2(sch_1):page41_i285:vss(166)" )
			)
			( pin "U5D1.DL22"
				( objectStatus "@baseboard_fab2_lib.baseboard_fab2(sch_1):page41_i285:vss(167)" )
			)
			( pin "U5D1.DL4"
				( objectStatus "@baseboard_fab2_lib.baseboard_fab2(sch_1):page41_i285:vss(168)" )
			)
			( pin "U5D1.DL18"
				( objectStatus "@baseboard_fab2_lib.baseboard_fab2(sch_1):page41_i285:vss(169)" )
			)
			( pin "U5D1.DL16"
				( objectStatus "@baseboard_fab2_lib.baseboard_fab2(sch_1):page41_i285:vss(170)" )
			)
			( pin "U5D1.DK85"
				( objectStatus "@baseboard_fab2_lib.baseboard_fab2(sch_1):page41_i285:vss(171)" )
			)
			( pin "U5D1.DK83"
				( objectStatus "@baseboard_fab2_lib.baseboard_fab2(sch_1):page41_i285:vss(172)" )
			)
			( pin "U5D1.DK77"
				( objectStatus "@baseboard_fab2_lib.baseboard_fab2(sch_1):page41_i285:vss(173)" )
			)
			( pin "U5D1.DK75"
				( objectStatus "@baseboard_fab2_lib.baseboard_fab2(sch_1):page41_i285:vss(174)" )
			)
			( pin "U5D1.DK73"
				( objectStatus "@baseboard_fab2_lib.baseboard_fab2(sch_1):page41_i285:vss(175)" )
			)
			( pin "U5D1.DK41"
				( objectStatus "@baseboard_fab2_lib.baseboard_fab2(sch_1):page41_i285:vss(176)" )
			)
			( pin "U5D1.DK39"
				( objectStatus "@baseboard_fab2_lib.baseboard_fab2(sch_1):page41_i285:vss(177)" )
			)
			( pin "U5D1.DK35"
				( objectStatus "@baseboard_fab2_lib.baseboard_fab2(sch_1):page41_i285:vss(178)" )
			)
			( pin "U5D1.DK29"
				( objectStatus "@baseboard_fab2_lib.baseboard_fab2(sch_1):page41_i285:vss(179)" )
			)
			( pin "U5D1.DK23"
				( objectStatus "@baseboard_fab2_lib.baseboard_fab2(sch_1):page41_i285:vss(180)" )
			)
			( pin "U5D1.DK7"
				( objectStatus "@baseboard_fab2_lib.baseboard_fab2(sch_1):page41_i285:vss(181)" )
			)
			( pin "U5D1.DJ84"
				( objectStatus "@baseboard_fab2_lib.baseboard_fab2(sch_1):page41_i285:vss(182)" )
			)
			( pin "U5D1.DJ82"
				( objectStatus "@baseboard_fab2_lib.baseboard_fab2(sch_1):page41_i285:vss(183)" )
			)
			( pin "U5D1.DJ78"
				( objectStatus "@baseboard_fab2_lib.baseboard_fab2(sch_1):page41_i285:vss(184)" )
			)
			( pin "U5D1.DJ74"
				( objectStatus "@baseboard_fab2_lib.baseboard_fab2(sch_1):page41_i285:vss(185)" )
			)
			( pin "U5D1.DJ68"
				( objectStatus "@baseboard_fab2_lib.baseboard_fab2(sch_1):page41_i285:vss(186)" )
			)
			( pin "U5D1.DJ42"
				( objectStatus "@baseboard_fab2_lib.baseboard_fab2(sch_1):page41_i285:vss(187)" )
			)
			( pin "U5D1.DJ38"
				( objectStatus "@baseboard_fab2_lib.baseboard_fab2(sch_1):page41_i285:vss(188)" )
			)
			( pin "U5D1.DJ22"
				( objectStatus "@baseboard_fab2_lib.baseboard_fab2(sch_1):page41_i285:vss(189)" )
			)
			( pin "U5D1.H47"
				( objectStatus "@baseboard_fab2_lib.baseboard_fab2(sch_1):page41_i285:vss(190)" )
			)
			( pin "U5D1.DJ10"
				( objectStatus "@baseboard_fab2_lib.baseboard_fab2(sch_1):page41_i285:vss(191)" )
			)
			( pin "U5D1.DJ2"
				( objectStatus "@baseboard_fab2_lib.baseboard_fab2(sch_1):page41_i285:vss(192)" )
			)
			( pin "U5D1.DH83"
				( objectStatus "@baseboard_fab2_lib.baseboard_fab2(sch_1):page41_i285:vss(193)" )
			)
			( pin "U5D1.DH81"
				( objectStatus "@baseboard_fab2_lib.baseboard_fab2(sch_1):page41_i285:vss(194)" )
			)
			( pin "U5D1.DH79"
				( objectStatus "@baseboard_fab2_lib.baseboard_fab2(sch_1):page41_i285:vss(195)" )
			)
			( pin "U5D1.DH73"
				( objectStatus "@baseboard_fab2_lib.baseboard_fab2(sch_1):page41_i285:vss(196)" )
			)
			( pin "U5D1.DH71"
				( objectStatus "@baseboard_fab2_lib.baseboard_fab2(sch_1):page41_i285:vss(197)" )
			)
			( pin "U5D1.DH67"
				( objectStatus "@baseboard_fab2_lib.baseboard_fab2(sch_1):page41_i285:vss(198)" )
			)
			( pin "U5D1.DH41"
				( objectStatus "@baseboard_fab2_lib.baseboard_fab2(sch_1):page41_i285:vss(199)" )
			)
			( pin "U5D1.DH37"
				( objectStatus "@baseboard_fab2_lib.baseboard_fab2(sch_1):page41_i285:vss(200)" )
			)
			( pin "U5D1.DH35"
				( objectStatus "@baseboard_fab2_lib.baseboard_fab2(sch_1):page41_i285:vss(201)" )
			)
			( pin "U5D1.DH33"
				( objectStatus "@baseboard_fab2_lib.baseboard_fab2(sch_1):page41_i285:vss(202)" )
			)
			( pin "U5D1.DH31"
				( objectStatus "@baseboard_fab2_lib.baseboard_fab2(sch_1):page41_i285:vss(203)" )
			)
			( pin "U5D1.DH29"
				( objectStatus "@baseboard_fab2_lib.baseboard_fab2(sch_1):page41_i285:vss(204)" )
			)
			( pin "U5D1.DH27"
				( objectStatus "@baseboard_fab2_lib.baseboard_fab2(sch_1):page41_i285:vss(205)" )
			)
			( pin "U5D1.DH25"
				( objectStatus "@baseboard_fab2_lib.baseboard_fab2(sch_1):page41_i285:vss(206)" )
			)
			( pin "U5D1.DH23"
				( objectStatus "@baseboard_fab2_lib.baseboard_fab2(sch_1):page41_i285:vss(207)" )
			)
			( pin "U5D1.DH15"
				( objectStatus "@baseboard_fab2_lib.baseboard_fab2(sch_1):page41_i285:vss(208)" )
			)
			( pin "U5D1.DH13"
				( objectStatus "@baseboard_fab2_lib.baseboard_fab2(sch_1):page41_i285:vss(209)" )
			)
			( pin "U5D1.DG82"
				( objectStatus "@baseboard_fab2_lib.baseboard_fab2(sch_1):page41_i285:vss(210)" )
			)
			( pin "U5D1.DG80"
				( objectStatus "@baseboard_fab2_lib.baseboard_fab2(sch_1):page41_i285:vss(211)" )
			)
			( pin "U5D1.DG78"
				( objectStatus "@baseboard_fab2_lib.baseboard_fab2(sch_1):page41_i285:vss(212)" )
			)
			( pin "U5D1.DG76"
				( objectStatus "@baseboard_fab2_lib.baseboard_fab2(sch_1):page41_i285:vss(213)" )
			)
			( pin "U5D1.DG68"
				( objectStatus "@baseboard_fab2_lib.baseboard_fab2(sch_1):page41_i285:vss(214)" )
			)
			( pin "U5D1.DG66"
				( objectStatus "@baseboard_fab2_lib.baseboard_fab2(sch_1):page41_i285:vss(215)" )
			)
			( pin "U5D1.DG24"
				( objectStatus "@baseboard_fab2_lib.baseboard_fab2(sch_1):page41_i285:vss(216)" )
			)
			( pin "U5D1.DG16"
				( objectStatus "@baseboard_fab2_lib.baseboard_fab2(sch_1):page41_i285:vss(217)" )
			)
			( pin "U5D1.DG14"
				( objectStatus "@baseboard_fab2_lib.baseboard_fab2(sch_1):page41_i285:vss(218)" )
			)
			( pin "U5D1.H49"
				( objectStatus "@baseboard_fab2_lib.baseboard_fab2(sch_1):page41_i285:vss(219)" )
			)
			( pin "U5D1.DG2"
				( objectStatus "@baseboard_fab2_lib.baseboard_fab2(sch_1):page41_i285:vss(220)" )
			)
			( pin "U5D1.DF85"
				( objectStatus "@baseboard_fab2_lib.baseboard_fab2(sch_1):page41_i285:vss(221)" )
			)
			( pin "U5D1.DF83"
				( objectStatus "@baseboard_fab2_lib.baseboard_fab2(sch_1):page41_i285:vss(222)" )
			)
			( pin "U5D1.DF79"
				( objectStatus "@baseboard_fab2_lib.baseboard_fab2(sch_1):page41_i285:vss(223)" )
			)
			( pin "U5D1.DF73"
				( objectStatus "@baseboard_fab2_lib.baseboard_fab2(sch_1):page41_i285:vss(224)" )
			)
			( pin "U5D1.DF69"
				( objectStatus "@baseboard_fab2_lib.baseboard_fab2(sch_1):page41_i285:vss(225)" )
			)
			( pin "U5D1.DF65"
				( objectStatus "@baseboard_fab2_lib.baseboard_fab2(sch_1):page41_i285:vss(226)" )
			)
			( pin "U5D1.DF41"
				( objectStatus "@baseboard_fab2_lib.baseboard_fab2(sch_1):page41_i285:vss(227)" )
			)
			( pin "U5D1.DF39"
				( objectStatus "@baseboard_fab2_lib.baseboard_fab2(sch_1):page41_i285:vss(228)" )
			)
			( pin "U5D1.DF37"
				( objectStatus "@baseboard_fab2_lib.baseboard_fab2(sch_1):page41_i285:vss(229)" )
			)
			( pin "U5D1.DF35"
				( objectStatus "@baseboard_fab2_lib.baseboard_fab2(sch_1):page41_i285:vss(230)" )
			)
			( pin "U5D1.DF29"
				( objectStatus "@baseboard_fab2_lib.baseboard_fab2(sch_1):page41_i285:vss(231)" )
			)
			( pin "U5D1.DF19"
				( objectStatus "@baseboard_fab2_lib.baseboard_fab2(sch_1):page41_i285:vss(232)" )
			)
			( pin "U5D1.H51"
				( objectStatus "@baseboard_fab2_lib.baseboard_fab2(sch_1):page41_i285:vss(233)" )
			)
			( pin "U5D1.DF7"
				( objectStatus "@baseboard_fab2_lib.baseboard_fab2(sch_1):page41_i285:vss(234)" )
			)
			( pin "U5D1.DF5"
				( objectStatus "@baseboard_fab2_lib.baseboard_fab2(sch_1):page41_i285:vss(235)" )
			)
			( pin "U5D1.DE78"
				( objectStatus "@baseboard_fab2_lib.baseboard_fab2(sch_1):page41_i285:vss(236)" )
			)
			( pin "U5D1.DE72"
				( objectStatus "@baseboard_fab2_lib.baseboard_fab2(sch_1):page41_i285:vss(237)" )
			)
			( pin "U5D1.DE70"
				( objectStatus "@baseboard_fab2_lib.baseboard_fab2(sch_1):page41_i285:vss(238)" )
			)
			( pin "U5D1.DE64"
				( objectStatus "@baseboard_fab2_lib.baseboard_fab2(sch_1):page41_i285:vss(239)" )
			)
			( pin "U5D1.DE36"
				( objectStatus "@baseboard_fab2_lib.baseboard_fab2(sch_1):page41_i285:vss(240)" )
			)
			( pin "U5D1.DE34"
				( objectStatus "@baseboard_fab2_lib.baseboard_fab2(sch_1):page41_i285:vss(241)" )
			)
			( pin "U5D1.DE30"
				( objectStatus "@baseboard_fab2_lib.baseboard_fab2(sch_1):page41_i285:vss(242)" )
			)
			( pin "U5D1.DE28"
				( objectStatus "@baseboard_fab2_lib.baseboard_fab2(sch_1):page41_i285:vss(243)" )
			)
			( pin "U5D1.DE24"
				( objectStatus "@baseboard_fab2_lib.baseboard_fab2(sch_1):page41_i285:vss(244)" )
			)
			( pin "U5D1.DE20"
				( objectStatus "@baseboard_fab2_lib.baseboard_fab2(sch_1):page41_i285:vss(245)" )
			)
			( pin "U5D1.DE18"
				( objectStatus "@baseboard_fab2_lib.baseboard_fab2(sch_1):page41_i285:vss(246)" )
			)
			( pin "U5D1.DE8"
				( objectStatus "@baseboard_fab2_lib.baseboard_fab2(sch_1):page41_i285:vss(247)" )
			)
			( pin "U5D1.DE6"
				( objectStatus "@baseboard_fab2_lib.baseboard_fab2(sch_1):page41_i285:vss(248)" )
			)
			( pin "U5D1.DD83"
				( objectStatus "@baseboard_fab2_lib.baseboard_fab2(sch_1):page41_i285:vss(249)" )
			)
			( pin "U5D1.DD81"
				( objectStatus "@baseboard_fab2_lib.baseboard_fab2(sch_1):page41_i285:vss(250)" )
			)
			( pin "U5D1.DD75"
				( objectStatus "@baseboard_fab2_lib.baseboard_fab2(sch_1):page41_i285:vss(251)" )
			)
			( pin "U5D1.DD73"
				( objectStatus "@baseboard_fab2_lib.baseboard_fab2(sch_1):page41_i285:vss(252)" )
			)
			( pin "U5D1.DD71"
				( objectStatus "@baseboard_fab2_lib.baseboard_fab2(sch_1):page41_i285:vss(253)" )
			)
			( pin "U5D1.DD37"
				( objectStatus "@baseboard_fab2_lib.baseboard_fab2(sch_1):page41_i285:vss(254)" )
			)
			( pin "U5D1.DD33"
				( objectStatus "@baseboard_fab2_lib.baseboard_fab2(sch_1):page41_i285:vss(255)" )
			)
			( pin "U5D1.DD31"
				( objectStatus "@baseboard_fab2_lib.baseboard_fab2(sch_1):page41_i285:vss(256)" )
			)
			( pin "U5D1.DD27"
				( objectStatus "@baseboard_fab2_lib.baseboard_fab2(sch_1):page41_i285:vss(257)" )
			)
			( pin "U5D1.DD23"
				( objectStatus "@baseboard_fab2_lib.baseboard_fab2(sch_1):page41_i285:vss(258)" )
			)
			( pin "U5D1.DD11"
				( objectStatus "@baseboard_fab2_lib.baseboard_fab2(sch_1):page41_i285:vss(259)" )
			)
			( pin "U5D1.DC86"
				( objectStatus "@baseboard_fab2_lib.baseboard_fab2(sch_1):page41_i285:vss(260)" )
			)
			( pin "U5D1.DC84"
				( objectStatus "@baseboard_fab2_lib.baseboard_fab2(sch_1):page41_i285:vss(261)" )
			)
			( pin "U5D1.DC78"
				( objectStatus "@baseboard_fab2_lib.baseboard_fab2(sch_1):page41_i285:vss(262)" )
			)
			( pin "U5D1.DC70"
				( objectStatus "@baseboard_fab2_lib.baseboard_fab2(sch_1):page41_i285:vss(263)" )
			)
			( pin "U5D1.DC68"
				( objectStatus "@baseboard_fab2_lib.baseboard_fab2(sch_1):page41_i285:vss(264)" )
			)
			( pin "U5D1.DC66"
				( objectStatus "@baseboard_fab2_lib.baseboard_fab2(sch_1):page41_i285:vss(265)" )
			)
			( pin "U5D1.DC64"
				( objectStatus "@baseboard_fab2_lib.baseboard_fab2(sch_1):page41_i285:vss(266)" )
			)
			( pin "U5D1.DC42"
				( objectStatus "@baseboard_fab2_lib.baseboard_fab2(sch_1):page41_i285:vss(267)" )
			)
			( pin "U5D1.DC38"
				( objectStatus "@baseboard_fab2_lib.baseboard_fab2(sch_1):page41_i285:vss(268)" )
			)
			( pin "U5D1.DC32"
				( objectStatus "@baseboard_fab2_lib.baseboard_fab2(sch_1):page41_i285:vss(269)" )
			)
			( pin "U5D1.DC26"
				( objectStatus "@baseboard_fab2_lib.baseboard_fab2(sch_1):page41_i285:vss(270)" )
			)
			( pin "U5D1.DC24"
				( objectStatus "@baseboard_fab2_lib.baseboard_fab2(sch_1):page41_i285:vss(271)" )
			)
			( pin "U5D1.DC14"
				( objectStatus "@baseboard_fab2_lib.baseboard_fab2(sch_1):page41_i285:vss(272)" )
			)
			( pin "U5D1.DB85"
				( objectStatus "@baseboard_fab2_lib.baseboard_fab2(sch_1):page41_i285:vss(273)" )
			)
			( pin "U5D1.DB83"
				( objectStatus "@baseboard_fab2_lib.baseboard_fab2(sch_1):page41_i285:vss(274)" )
			)
			( pin "U5D1.DB77"
				( objectStatus "@baseboard_fab2_lib.baseboard_fab2(sch_1):page41_i285:vss(275)" )
			)
			( pin "U5D1.DB73"
				( objectStatus "@baseboard_fab2_lib.baseboard_fab2(sch_1):page41_i285:vss(276)" )
			)
			( pin "U5D1.DB49"
				( objectStatus "@baseboard_fab2_lib.baseboard_fab2(sch_1):page41_i285:vss(277)" )
			)
			( pin "U5D1.DB47"
				( objectStatus "@baseboard_fab2_lib.baseboard_fab2(sch_1):page41_i285:vss(278)" )
			)
			( pin "U5D1.DB41"
				( objectStatus "@baseboard_fab2_lib.baseboard_fab2(sch_1):page41_i285:vss(279)" )
			)
			( pin "U5D1.DB39"
				( objectStatus "@baseboard_fab2_lib.baseboard_fab2(sch_1):page41_i285:vss(280)" )
			)
			( pin "U5D1.DB25"
				( objectStatus "@baseboard_fab2_lib.baseboard_fab2(sch_1):page41_i285:vss(281)" )
			)
			( pin "U5D1.DB23"
				( objectStatus "@baseboard_fab2_lib.baseboard_fab2(sch_1):page41_i285:vss(282)" )
			)
			( pin "U5D1.DB17"
				( objectStatus "@baseboard_fab2_lib.baseboard_fab2(sch_1):page41_i285:vss(283)" )
			)
			( pin "U5D1.DB13"
				( objectStatus "@baseboard_fab2_lib.baseboard_fab2(sch_1):page41_i285:vss(284)" )
			)
			( pin "U5D1.DB3"
				( objectStatus "@baseboard_fab2_lib.baseboard_fab2(sch_1):page41_i285:vss(285)" )
			)
			( pin "U5D1.DA80"
				( objectStatus "@baseboard_fab2_lib.baseboard_fab2(sch_1):page41_i285:vss(286)" )
			)
			( pin "U5D1.DA78"
				( objectStatus "@baseboard_fab2_lib.baseboard_fab2(sch_1):page41_i285:vss(287)" )
			)
			( pin "U5D1.DA76"
				( objectStatus "@baseboard_fab2_lib.baseboard_fab2(sch_1):page41_i285:vss(288)" )
			)
			( pin "U5D1.DA74"
				( objectStatus "@baseboard_fab2_lib.baseboard_fab2(sch_1):page41_i285:vss(289)" )
			)
			( pin "U5D1.DA70"
				( objectStatus "@baseboard_fab2_lib.baseboard_fab2(sch_1):page41_i285:vss(290)" )
			)
			( pin "U5D1.DA64"
				( objectStatus "@baseboard_fab2_lib.baseboard_fab2(sch_1):page41_i285:vss(291)" )
			)
			( pin "U5D1.DA50"
				( objectStatus "@baseboard_fab2_lib.baseboard_fab2(sch_1):page41_i285:vss(292)" )
			)
			( pin "U5D1.DA48"
				( objectStatus "@baseboard_fab2_lib.baseboard_fab2(sch_1):page41_i285:vss(293)" )
			)
			( pin "U5D1.EF79"
				( objectStatus "@baseboard_fab2_lib.baseboard_fab2(sch_1):page41_i286:vss(0)" )
			)
			( pin "U5D1.EF75"
				( objectStatus "@baseboard_fab2_lib.baseboard_fab2(sch_1):page41_i286:vss(1)" )
			)
			( pin "U5D1.EF71"
				( objectStatus "@baseboard_fab2_lib.baseboard_fab2(sch_1):page41_i286:vss(2)" )
			)
			( pin "U5D1.EE78"
				( objectStatus "@baseboard_fab2_lib.baseboard_fab2(sch_1):page41_i286:vss(3)" )
			)
			( pin "U5D1.EE76"
				( objectStatus "@baseboard_fab2_lib.baseboard_fab2(sch_1):page41_i286:vss(4)" )
			)
			( pin "U5D1.EE70"
				( objectStatus "@baseboard_fab2_lib.baseboard_fab2(sch_1):page41_i286:vss(5)" )
			)
			( pin "U5D1.EE36"
				( objectStatus "@baseboard_fab2_lib.baseboard_fab2(sch_1):page41_i286:vss(6)" )
			)
			( pin "U5D1.EE34"
				( objectStatus "@baseboard_fab2_lib.baseboard_fab2(sch_1):page41_i286:vss(7)" )
			)
			( pin "U5D1.EE30"
				( objectStatus "@baseboard_fab2_lib.baseboard_fab2(sch_1):page41_i286:vss(8)" )
			)
			( pin "U5D1.EE28"
				( objectStatus "@baseboard_fab2_lib.baseboard_fab2(sch_1):page41_i286:vss(9)" )
			)
			( pin "U5D1.EE24"
				( objectStatus "@baseboard_fab2_lib.baseboard_fab2(sch_1):page41_i286:vss(10)" )
			)
			( pin "U5D1.ED77"
				( objectStatus "@baseboard_fab2_lib.baseboard_fab2(sch_1):page41_i286:vss(11)" )
			)
			( pin "U5D1.ED35"
				( objectStatus "@baseboard_fab2_lib.baseboard_fab2(sch_1):page41_i286:vss(12)" )
			)
			( pin "U5D1.ED29"
				( objectStatus "@baseboard_fab2_lib.baseboard_fab2(sch_1):page41_i286:vss(13)" )
			)
			( pin "U5D1.ED23"
				( objectStatus "@baseboard_fab2_lib.baseboard_fab2(sch_1):page41_i286:vss(14)" )
			)
			( pin "U5D1.ED15"
				( objectStatus "@baseboard_fab2_lib.baseboard_fab2(sch_1):page41_i286:vss(15)" )
			)
			( pin "U5D1.ED11"
				( objectStatus "@baseboard_fab2_lib.baseboard_fab2(sch_1):page41_i286:vss(16)" )
			)
			( pin "U5D1.EC76"
				( objectStatus "@baseboard_fab2_lib.baseboard_fab2(sch_1):page41_i286:vss(17)" )
			)
			( pin "U5D1.EC74"
				( objectStatus "@baseboard_fab2_lib.baseboard_fab2(sch_1):page41_i286:vss(18)" )
			)
			( pin "U5D1.EC72"
				( objectStatus "@baseboard_fab2_lib.baseboard_fab2(sch_1):page41_i286:vss(19)" )
			)
			( pin "U5D1.EC70"
				( objectStatus "@baseboard_fab2_lib.baseboard_fab2(sch_1):page41_i286:vss(20)" )
			)
			( pin "U5D1.EC10"
				( objectStatus "@baseboard_fab2_lib.baseboard_fab2(sch_1):page41_i286:vss(21)" )
			)
			( pin "U5D1.EB69"
				( objectStatus "@baseboard_fab2_lib.baseboard_fab2(sch_1):page41_i286:vss(22)" )
			)
			( pin "U5D1.EB65"
				( objectStatus "@baseboard_fab2_lib.baseboard_fab2(sch_1):page41_i286:vss(23)" )
			)
			( pin "U5D1.EB41"
				( objectStatus "@baseboard_fab2_lib.baseboard_fab2(sch_1):page41_i286:vss(24)" )
			)
			( pin "U5D1.EB39"
				( objectStatus "@baseboard_fab2_lib.baseboard_fab2(sch_1):page41_i286:vss(25)" )
			)
			( pin "U5D1.EB37"
				( objectStatus "@baseboard_fab2_lib.baseboard_fab2(sch_1):page41_i286:vss(26)" )
			)
			( pin "U5D1.EB35"
				( objectStatus "@baseboard_fab2_lib.baseboard_fab2(sch_1):page41_i286:vss(27)" )
			)
			( pin "U5D1.EB33"
				( objectStatus "@baseboard_fab2_lib.baseboard_fab2(sch_1):page41_i286:vss(28)" )
			)
			( pin "U5D1.EB31"
				( objectStatus "@baseboard_fab2_lib.baseboard_fab2(sch_1):page41_i286:vss(29)" )
			)
			( pin "U5D1.EB29"
				( objectStatus "@baseboard_fab2_lib.baseboard_fab2(sch_1):page41_i286:vss(30)" )
			)
			( pin "U5D1.EB27"
				( objectStatus "@baseboard_fab2_lib.baseboard_fab2(sch_1):page41_i286:vss(31)" )
			)
			( pin "U5D1.EB25"
				( objectStatus "@baseboard_fab2_lib.baseboard_fab2(sch_1):page41_i286:vss(32)" )
			)
			( pin "U5D1.EB23"
				( objectStatus "@baseboard_fab2_lib.baseboard_fab2(sch_1):page41_i286:vss(33)" )
			)
			( pin "U5D1.BR18"
				( objectStatus "@baseboard_fab2_lib.baseboard_fab2(sch_1):page41_i286:vss(34)" )
			)
			( pin "U5D1.EB13"
				( objectStatus "@baseboard_fab2_lib.baseboard_fab2(sch_1):page41_i286:vss(35)" )
			)
			( pin "U5D1.EA82"
				( objectStatus "@baseboard_fab2_lib.baseboard_fab2(sch_1):page41_i286:vss(36)" )
			)
			( pin "U5D1.EA80"
				( objectStatus "@baseboard_fab2_lib.baseboard_fab2(sch_1):page41_i286:vss(37)" )
			)
			( pin "U5D1.EA78"
				( objectStatus "@baseboard_fab2_lib.baseboard_fab2(sch_1):page41_i286:vss(38)" )
			)
			( pin "U5D1.EA76"
				( objectStatus "@baseboard_fab2_lib.baseboard_fab2(sch_1):page41_i286:vss(39)" )
			)
			( pin "U5D1.EA70"
				( objectStatus "@baseboard_fab2_lib.baseboard_fab2(sch_1):page41_i286:vss(40)" )
			)
			( pin "U5D1.EA64"
				( objectStatus "@baseboard_fab2_lib.baseboard_fab2(sch_1):page41_i286:vss(41)" )
			)
			( pin "U5D1.EA42"
				( objectStatus "@baseboard_fab2_lib.baseboard_fab2(sch_1):page41_i286:vss(42)" )
			)
			( pin "U5D1.EA22"
				( objectStatus "@baseboard_fab2_lib.baseboard_fab2(sch_1):page41_i286:vss(43)" )
			)
			( pin "U5D1.EA20"
				( objectStatus "@baseboard_fab2_lib.baseboard_fab2(sch_1):page41_i286:vss(44)" )
			)
			( pin "U5D1.EA16"
				( objectStatus "@baseboard_fab2_lib.baseboard_fab2(sch_1):page41_i286:vss(45)" )
			)
			( pin "U5D1.J16"
				( objectStatus "@baseboard_fab2_lib.baseboard_fab2(sch_1):page41_i286:vss(46)" )
			)
			( pin "U5D1.EA6"
				( objectStatus "@baseboard_fab2_lib.baseboard_fab2(sch_1):page41_i286:vss(47)" )
			)
			( pin "U5D1.DY75"
				( objectStatus "@baseboard_fab2_lib.baseboard_fab2(sch_1):page41_i286:vss(48)" )
			)
			( pin "U5D1.DY71"
				( objectStatus "@baseboard_fab2_lib.baseboard_fab2(sch_1):page41_i286:vss(49)" )
			)
			( pin "U5D1.DY41"
				( objectStatus "@baseboard_fab2_lib.baseboard_fab2(sch_1):page41_i286:vss(50)" )
			)
			( pin "U5D1.DY35"
				( objectStatus "@baseboard_fab2_lib.baseboard_fab2(sch_1):page41_i286:vss(51)" )
			)
			( pin "U5D1.DY29"
				( objectStatus "@baseboard_fab2_lib.baseboard_fab2(sch_1):page41_i286:vss(52)" )
			)
			( pin "U5D1.DY23"
				( objectStatus "@baseboard_fab2_lib.baseboard_fab2(sch_1):page41_i286:vss(53)" )
			)
			( pin "U5D1.DY19"
				( objectStatus "@baseboard_fab2_lib.baseboard_fab2(sch_1):page41_i286:vss(54)" )
			)
			( pin "U5D1.DY5"
				( objectStatus "@baseboard_fab2_lib.baseboard_fab2(sch_1):page41_i286:vss(55)" )
			)
			( pin "U5D1.DW84"
				( objectStatus "@baseboard_fab2_lib.baseboard_fab2(sch_1):page41_i286:vss(56)" )
			)
			( pin "U5D1.DW82"
				( objectStatus "@baseboard_fab2_lib.baseboard_fab2(sch_1):page41_i286:vss(57)" )
			)
			( pin "U5D1.DW8"
				( objectStatus "@baseboard_fab2_lib.baseboard_fab2(sch_1):page41_i286:vss(58)" )
			)
			( pin "U5D1.DW76"
				( objectStatus "@baseboard_fab2_lib.baseboard_fab2(sch_1):page41_i286:vss(59)" )
			)
			( pin "U5D1.DW74"
				( objectStatus "@baseboard_fab2_lib.baseboard_fab2(sch_1):page41_i286:vss(60)" )
			)
			( pin "U5D1.DW72"
				( objectStatus "@baseboard_fab2_lib.baseboard_fab2(sch_1):page41_i286:vss(61)" )
			)
			( pin "U5D1.DW70"
				( objectStatus "@baseboard_fab2_lib.baseboard_fab2(sch_1):page41_i286:vss(62)" )
			)
			( pin "U5D1.DW68"
				( objectStatus "@baseboard_fab2_lib.baseboard_fab2(sch_1):page41_i286:vss(63)" )
			)
			( pin "U5D1.DW66"
				( objectStatus "@baseboard_fab2_lib.baseboard_fab2(sch_1):page41_i286:vss(64)" )
			)
			( pin "U5D1.DW64"
				( objectStatus "@baseboard_fab2_lib.baseboard_fab2(sch_1):page41_i286:vss(65)" )
			)
			( pin "U5D1.DW40"
				( objectStatus "@baseboard_fab2_lib.baseboard_fab2(sch_1):page41_i286:vss(66)" )
			)
			( pin "U5D1.DW36"
				( objectStatus "@baseboard_fab2_lib.baseboard_fab2(sch_1):page41_i286:vss(67)" )
			)
			( pin "U5D1.DW34"
				( objectStatus "@baseboard_fab2_lib.baseboard_fab2(sch_1):page41_i286:vss(68)" )
			)
			( pin "U5D1.DW30"
				( objectStatus "@baseboard_fab2_lib.baseboard_fab2(sch_1):page41_i286:vss(69)" )
			)
			( pin "U5D1.DW28"
				( objectStatus "@baseboard_fab2_lib.baseboard_fab2(sch_1):page41_i286:vss(70)" )
			)
			( pin "U5D1.DW24"
				( objectStatus "@baseboard_fab2_lib.baseboard_fab2(sch_1):page41_i286:vss(71)" )
			)
			( pin "U5D1.DW20"
				( objectStatus "@baseboard_fab2_lib.baseboard_fab2(sch_1):page41_i286:vss(72)" )
			)
			( pin "U5D1.DW12"
				( objectStatus "@baseboard_fab2_lib.baseboard_fab2(sch_1):page41_i286:vss(73)" )
			)
			( pin "U5D1.DV81"
				( objectStatus "@baseboard_fab2_lib.baseboard_fab2(sch_1):page41_i286:vss(74)" )
			)
			( pin "U5D1.DV77"
				( objectStatus "@baseboard_fab2_lib.baseboard_fab2(sch_1):page41_i286:vss(75)" )
			)
			( pin "U5D1.DV73"
				( objectStatus "@baseboard_fab2_lib.baseboard_fab2(sch_1):page41_i286:vss(76)" )
			)
			( pin "U5D1.DV39"
				( objectStatus "@baseboard_fab2_lib.baseboard_fab2(sch_1):page41_i286:vss(77)" )
			)
			( pin "U5D1.DV37"
				( objectStatus "@baseboard_fab2_lib.baseboard_fab2(sch_1):page41_i286:vss(78)" )
			)
			( pin "U5D1.DV33"
				( objectStatus "@baseboard_fab2_lib.baseboard_fab2(sch_1):page41_i286:vss(79)" )
			)
			( pin "U5D1.DV31"
				( objectStatus "@baseboard_fab2_lib.baseboard_fab2(sch_1):page41_i286:vss(80)" )
			)
			( pin "U5D1.DV27"
				( objectStatus "@baseboard_fab2_lib.baseboard_fab2(sch_1):page41_i286:vss(81)" )
			)
			( pin "U5D1.DV25"
				( objectStatus "@baseboard_fab2_lib.baseboard_fab2(sch_1):page41_i286:vss(82)" )
			)
			( pin "U5D1.DV21"
				( objectStatus "@baseboard_fab2_lib.baseboard_fab2(sch_1):page41_i286:vss(83)" )
			)
			( pin "U5D1.DU84"
				( objectStatus "@baseboard_fab2_lib.baseboard_fab2(sch_1):page41_i286:vss(84)" )
			)
			( pin "U5D1.DU82"
				( objectStatus "@baseboard_fab2_lib.baseboard_fab2(sch_1):page41_i286:vss(85)" )
			)
			( pin "U5D1.DU80"
				( objectStatus "@baseboard_fab2_lib.baseboard_fab2(sch_1):page41_i286:vss(86)" )
			)
			( pin "U5D1.DU78"
				( objectStatus "@baseboard_fab2_lib.baseboard_fab2(sch_1):page41_i286:vss(87)" )
			)
			( pin "U5D1.DU72"
				( objectStatus "@baseboard_fab2_lib.baseboard_fab2(sch_1):page41_i286:vss(88)" )
			)
			( pin "U5D1.DU70"
				( objectStatus "@baseboard_fab2_lib.baseboard_fab2(sch_1):page41_i286:vss(89)" )
			)
			( pin "U5D1.DU38"
				( objectStatus "@baseboard_fab2_lib.baseboard_fab2(sch_1):page41_i286:vss(90)" )
			)
			( pin "U5D1.DU32"
				( objectStatus "@baseboard_fab2_lib.baseboard_fab2(sch_1):page41_i286:vss(91)" )
			)
			( pin "U5D1.DU26"
				( objectStatus "@baseboard_fab2_lib.baseboard_fab2(sch_1):page41_i286:vss(92)" )
			)
			( pin "U5D1.DU22"
				( objectStatus "@baseboard_fab2_lib.baseboard_fab2(sch_1):page41_i286:vss(93)" )
			)
			( pin "U5D1.CN14"
				( objectStatus "@baseboard_fab2_lib.baseboard_fab2(sch_1):page41_i286:vss(94)" )
			)
			( pin "U5D1.DU14"
				( objectStatus "@baseboard_fab2_lib.baseboard_fab2(sch_1):page41_i286:vss(95)" )
			)
			( pin "U5D1.DU10"
				( objectStatus "@baseboard_fab2_lib.baseboard_fab2(sch_1):page41_i286:vss(96)" )
			)
			( pin "U5D1.DT85"
				( objectStatus "@baseboard_fab2_lib.baseboard_fab2(sch_1):page41_i286:vss(97)" )
			)
			( pin "U5D1.DT83"
				( objectStatus "@baseboard_fab2_lib.baseboard_fab2(sch_1):page41_i286:vss(98)" )
			)
			( pin "U5D1.DT79"
				( objectStatus "@baseboard_fab2_lib.baseboard_fab2(sch_1):page41_i286:vss(99)" )
			)
			( pin "U5D1.DT69"
				( objectStatus "@baseboard_fab2_lib.baseboard_fab2(sch_1):page41_i286:vss(100)" )
			)
			( pin "U5D1.DT65"
				( objectStatus "@baseboard_fab2_lib.baseboard_fab2(sch_1):page41_i286:vss(101)" )
			)
			( pin "U5D1.DH21"
				( objectStatus "@baseboard_fab2_lib.baseboard_fab2(sch_1):page41_i286:vss(102)" )
			)
			( pin "U5D1.DT17"
				( objectStatus "@baseboard_fab2_lib.baseboard_fab2(sch_1):page41_i286:vss(103)" )
			)
			( pin "U5D1.DT3"
				( objectStatus "@baseboard_fab2_lib.baseboard_fab2(sch_1):page41_i286:vss(104)" )
			)
			( pin "U5D1.DR78"
				( objectStatus "@baseboard_fab2_lib.baseboard_fab2(sch_1):page41_i286:vss(105)" )
			)
			( pin "U5D1.DR76"
				( objectStatus "@baseboard_fab2_lib.baseboard_fab2(sch_1):page41_i286:vss(106)" )
			)
			( pin "U5D1.DR74"
				( objectStatus "@baseboard_fab2_lib.baseboard_fab2(sch_1):page41_i286:vss(107)" )
			)
			( pin "U5D1.DR72"
				( objectStatus "@baseboard_fab2_lib.baseboard_fab2(sch_1):page41_i286:vss(108)" )
			)
			( pin "U5D1.DR70"
				( objectStatus "@baseboard_fab2_lib.baseboard_fab2(sch_1):page41_i286:vss(109)" )
			)
			( pin "U5D1.DR68"
				( objectStatus "@baseboard_fab2_lib.baseboard_fab2(sch_1):page41_i286:vss(110)" )
			)
			( pin "U5D1.DR66"
				( objectStatus "@baseboard_fab2_lib.baseboard_fab2(sch_1):page41_i286:vss(111)" )
			)
			( pin "U5D1.DR42"
				( objectStatus "@baseboard_fab2_lib.baseboard_fab2(sch_1):page41_i286:vss(112)" )
			)
			( pin "U5D1.DR40"
				( objectStatus "@baseboard_fab2_lib.baseboard_fab2(sch_1):page41_i286:vss(113)" )
			)
			( pin "U5D1.DR38"
				( objectStatus "@baseboard_fab2_lib.baseboard_fab2(sch_1):page41_i286:vss(114)" )
			)
			( pin "U5D1.DR36"
				( objectStatus "@baseboard_fab2_lib.baseboard_fab2(sch_1):page41_i286:vss(115)" )
			)
			( pin "U5D1.DR34"
				( objectStatus "@baseboard_fab2_lib.baseboard_fab2(sch_1):page41_i286:vss(116)" )
			)
			( pin "U5D1.DR32"
				( objectStatus "@baseboard_fab2_lib.baseboard_fab2(sch_1):page41_i286:vss(117)" )
			)
			( pin "U5D1.DR30"
				( objectStatus "@baseboard_fab2_lib.baseboard_fab2(sch_1):page41_i286:vss(118)" )
			)
			( pin "U5D1.DR28"
				( objectStatus "@baseboard_fab2_lib.baseboard_fab2(sch_1):page41_i286:vss(119)" )
			)
			( pin "U5D1.DR26"
				( objectStatus "@baseboard_fab2_lib.baseboard_fab2(sch_1):page41_i286:vss(120)" )
			)
			( pin "U5D1.DR24"
				( objectStatus "@baseboard_fab2_lib.baseboard_fab2(sch_1):page41_i286:vss(121)" )
			)
			( pin "U5D1.DR22"
				( objectStatus "@baseboard_fab2_lib.baseboard_fab2(sch_1):page41_i286:vss(122)" )
			)
			( pin "U5D1.DR20"
				( objectStatus "@baseboard_fab2_lib.baseboard_fab2(sch_1):page41_i286:vss(123)" )
			)
			( pin "U5D1.CL22"
				( objectStatus "@baseboard_fab2_lib.baseboard_fab2(sch_1):page41_i286:vss(124)" )
			)
			( pin "U5D1.CA20"
				( objectStatus "@baseboard_fab2_lib.baseboard_fab2(sch_1):page41_i286:vss(125)" )
			)
			( pin "U5D1.DR6"
				( objectStatus "@baseboard_fab2_lib.baseboard_fab2(sch_1):page41_i286:vss(126)" )
			)
			( pin "U5D1.BR26"
				( objectStatus "@baseboard_fab2_lib.baseboard_fab2(sch_1):page41_i286:vss(127)" )
			)
			( pin "U5D1.DP83"
				( objectStatus "@baseboard_fab2_lib.baseboard_fab2(sch_1):page41_i286:vss(128)" )
			)
			( pin "U5D1.DP81"
				( objectStatus "@baseboard_fab2_lib.baseboard_fab2(sch_1):page41_i286:vss(129)" )
			)
			( pin "U5D1.DP71"
				( objectStatus "@baseboard_fab2_lib.baseboard_fab2(sch_1):page41_i286:vss(130)" )
			)
			( pin "U5D1.DP69"
				( objectStatus "@baseboard_fab2_lib.baseboard_fab2(sch_1):page41_i286:vss(131)" )
			)
			( pin "U5D1.DP67"
				( objectStatus "@baseboard_fab2_lib.baseboard_fab2(sch_1):page41_i286:vss(132)" )
			)
			( pin "U5D1.DN78"
				( objectStatus "@baseboard_fab2_lib.baseboard_fab2(sch_1):page41_i286:vss(133)" )
			)
			( pin "C5P18.1"
				( objectStatus "@baseboard_fab2_lib.baseboard_fab2(sch_1):page42_i2:a" )
			)
			( pin "C5P18.2"
				( objectStatus "@baseboard_fab2_lib.baseboard_fab2(sch_1):page42_i2:b" )
			)
			( pin "C5P28.1"
				( objectStatus "@baseboard_fab2_lib.baseboard_fab2(sch_1):page42_i3:a" )
			)
			( pin "C5P28.2"
				( objectStatus "@baseboard_fab2_lib.baseboard_fab2(sch_1):page42_i3:b" )
			)
			( pin "C5P11.1"
				( objectStatus "@baseboard_fab2_lib.baseboard_fab2(sch_1):page42_i4:a" )
			)
			( pin "C5P11.2"
				( objectStatus "@baseboard_fab2_lib.baseboard_fab2(sch_1):page42_i4:b" )
			)
			( pin "C5P10.1"
				( objectStatus "@baseboard_fab2_lib.baseboard_fab2(sch_1):page42_i6:a" )
			)
			( pin "C5P10.2"
				( objectStatus "@baseboard_fab2_lib.baseboard_fab2(sch_1):page42_i6:b" )
			)
			( pin "C4P3.1"
				( objectStatus "@baseboard_fab2_lib.baseboard_fab2(sch_1):page42_i8:a" )
			)
			( pin "C4P3.2"
				( objectStatus "@baseboard_fab2_lib.baseboard_fab2(sch_1):page42_i8:b" )
			)
			( pin "C4P7.1"
				( objectStatus "@baseboard_fab2_lib.baseboard_fab2(sch_1):page42_i9:a" )
			)
			( pin "C4P7.2"
				( objectStatus "@baseboard_fab2_lib.baseboard_fab2(sch_1):page42_i9:b" )
			)
			( pin "C4P1.1"
				( objectStatus "@baseboard_fab2_lib.baseboard_fab2(sch_1):page42_i10:a" )
			)
			( pin "C4P1.2"
				( objectStatus "@baseboard_fab2_lib.baseboard_fab2(sch_1):page42_i10:b" )
			)
			( pin "C4P9.1"
				( objectStatus "@baseboard_fab2_lib.baseboard_fab2(sch_1):page42_i12:a" )
			)
			( pin "C4P9.2"
				( objectStatus "@baseboard_fab2_lib.baseboard_fab2(sch_1):page42_i12:b" )
			)
			( pin "C5P19.1"
				( objectStatus "@baseboard_fab2_lib.baseboard_fab2(sch_1):page42_i13:a" )
			)
			( pin "C5P19.2"
				( objectStatus "@baseboard_fab2_lib.baseboard_fab2(sch_1):page42_i13:b" )
			)
			( pin "C4P4.1"
				( objectStatus "@baseboard_fab2_lib.baseboard_fab2(sch_1):page42_i14:a" )
			)
			( pin "C4P4.2"
				( objectStatus "@baseboard_fab2_lib.baseboard_fab2(sch_1):page42_i14:b" )
			)
			( pin "C4P10.1"
				( objectStatus "@baseboard_fab2_lib.baseboard_fab2(sch_1):page42_i17:a" )
			)
			( pin "C4P10.2"
				( objectStatus "@baseboard_fab2_lib.baseboard_fab2(sch_1):page42_i17:b" )
			)
			( pin "C5P9.1"
				( objectStatus "@baseboard_fab2_lib.baseboard_fab2(sch_1):page42_i18:a" )
			)
			( pin "C5P9.2"
				( objectStatus "@baseboard_fab2_lib.baseboard_fab2(sch_1):page42_i18:b" )
			)
			( pin "C5P8.1"
				( objectStatus "@baseboard_fab2_lib.baseboard_fab2(sch_1):page42_i19:a" )
			)
			( pin "C5P8.2"
				( objectStatus "@baseboard_fab2_lib.baseboard_fab2(sch_1):page42_i19:b" )
			)
			( pin "C5P7.1"
				( objectStatus "@baseboard_fab2_lib.baseboard_fab2(sch_1):page42_i25:a" )
			)
			( pin "C5P7.2"
				( objectStatus "@baseboard_fab2_lib.baseboard_fab2(sch_1):page42_i25:b" )
			)
			( pin "C5P4.1"
				( objectStatus "@baseboard_fab2_lib.baseboard_fab2(sch_1):page42_i27:a" )
			)
			( pin "C5P4.2"
				( objectStatus "@baseboard_fab2_lib.baseboard_fab2(sch_1):page42_i27:b" )
			)
			( pin "C5P23.1"
				( objectStatus "@baseboard_fab2_lib.baseboard_fab2(sch_1):page42_i28:a" )
			)
			( pin "C5P23.2"
				( objectStatus "@baseboard_fab2_lib.baseboard_fab2(sch_1):page42_i28:b" )
			)
			( pin "C5P24.1"
				( objectStatus "@baseboard_fab2_lib.baseboard_fab2(sch_1):page42_i33:a" )
			)
			( pin "C5P24.2"
				( objectStatus "@baseboard_fab2_lib.baseboard_fab2(sch_1):page42_i33:b" )
			)
			( pin "C5P25.1"
				( objectStatus "@baseboard_fab2_lib.baseboard_fab2(sch_1):page42_i37:a" )
			)
			( pin "C5P25.2"
				( objectStatus "@baseboard_fab2_lib.baseboard_fab2(sch_1):page42_i37:b" )
			)
			( pin "C5P6.1"
				( objectStatus "@baseboard_fab2_lib.baseboard_fab2(sch_1):page42_i38:a" )
			)
			( pin "C5P6.2"
				( objectStatus "@baseboard_fab2_lib.baseboard_fab2(sch_1):page42_i38:b" )
			)
			( pin "C5P41.1"
				( objectStatus "@baseboard_fab2_lib.baseboard_fab2(sch_1):page42_i40:a" )
			)
			( pin "C5P41.2"
				( objectStatus "@baseboard_fab2_lib.baseboard_fab2(sch_1):page42_i40:b" )
			)
			( pin "C5P14.1"
				( objectStatus "@baseboard_fab2_lib.baseboard_fab2(sch_1):page42_i41:a" )
			)
			( pin "C5P14.2"
				( objectStatus "@baseboard_fab2_lib.baseboard_fab2(sch_1):page42_i41:b" )
			)
			( pin "C5P5.1"
				( objectStatus "@baseboard_fab2_lib.baseboard_fab2(sch_1):page42_i42:a" )
			)
			( pin "C5P5.2"
				( objectStatus "@baseboard_fab2_lib.baseboard_fab2(sch_1):page42_i42:b" )
			)
			( pin "C5P27.1"
				( objectStatus "@baseboard_fab2_lib.baseboard_fab2(sch_1):page42_i44:a" )
			)
			( pin "C5P27.2"
				( objectStatus "@baseboard_fab2_lib.baseboard_fab2(sch_1):page42_i44:b" )
			)
			( pin "C5P33.1"
				( objectStatus "@baseboard_fab2_lib.baseboard_fab2(sch_1):page42_i50:a" )
			)
			( pin "C5P33.2"
				( objectStatus "@baseboard_fab2_lib.baseboard_fab2(sch_1):page42_i50:b" )
			)
			( pin "C5P35.1"
				( objectStatus "@baseboard_fab2_lib.baseboard_fab2(sch_1):page42_i51:a" )
			)
			( pin "C5P35.2"
				( objectStatus "@baseboard_fab2_lib.baseboard_fab2(sch_1):page42_i51:b" )
			)
			( pin "C5P32.1"
				( objectStatus "@baseboard_fab2_lib.baseboard_fab2(sch_1):page42_i53:a" )
			)
			( pin "C5P32.2"
				( objectStatus "@baseboard_fab2_lib.baseboard_fab2(sch_1):page42_i53:b" )
			)
			( pin "C5P34.1"
				( objectStatus "@baseboard_fab2_lib.baseboard_fab2(sch_1):page42_i54:a" )
			)
			( pin "C5P34.2"
				( objectStatus "@baseboard_fab2_lib.baseboard_fab2(sch_1):page42_i54:b" )
			)
			( pin "C5P22.1"
				( objectStatus "@baseboard_fab2_lib.baseboard_fab2(sch_1):page42_i55:a" )
			)
			( pin "C5P22.2"
				( objectStatus "@baseboard_fab2_lib.baseboard_fab2(sch_1):page42_i55:b" )
			)
			( pin "C5P26.1"
				( objectStatus "@baseboard_fab2_lib.baseboard_fab2(sch_1):page42_i56:a" )
			)
			( pin "C5P26.2"
				( objectStatus "@baseboard_fab2_lib.baseboard_fab2(sch_1):page42_i56:b" )
			)
			( pin "C5P40.1"
				( objectStatus "@baseboard_fab2_lib.baseboard_fab2(sch_1):page42_i57:a" )
			)
			( pin "C5P40.2"
				( objectStatus "@baseboard_fab2_lib.baseboard_fab2(sch_1):page42_i57:b" )
			)
			( pin "C5P42.1"
				( objectStatus "@baseboard_fab2_lib.baseboard_fab2(sch_1):page42_i59:a" )
			)
			( pin "C5P42.2"
				( objectStatus "@baseboard_fab2_lib.baseboard_fab2(sch_1):page42_i59:b" )
			)
			( pin "C5P43.1"
				( objectStatus "@baseboard_fab2_lib.baseboard_fab2(sch_1):page42_i60:a" )
			)
			( pin "C5P43.2"
				( objectStatus "@baseboard_fab2_lib.baseboard_fab2(sch_1):page42_i60:b" )
			)
			( pin "C5P44.1"
				( objectStatus "@baseboard_fab2_lib.baseboard_fab2(sch_1):page42_i61:a" )
			)
			( pin "C5P44.2"
				( objectStatus "@baseboard_fab2_lib.baseboard_fab2(sch_1):page42_i61:b" )
			)
			( pin "C5P37.1"
				( objectStatus "@baseboard_fab2_lib.baseboard_fab2(sch_1):page42_i63:a" )
			)
			( pin "C5P37.2"
				( objectStatus "@baseboard_fab2_lib.baseboard_fab2(sch_1):page42_i63:b" )
			)
			( pin "C5P36.1"
				( objectStatus "@baseboard_fab2_lib.baseboard_fab2(sch_1):page42_i65:a" )
			)
			( pin "C5P36.2"
				( objectStatus "@baseboard_fab2_lib.baseboard_fab2(sch_1):page42_i65:b" )
			)
			( pin "C6D8.1"
				( objectStatus "@baseboard_fab2_lib.baseboard_fab2(sch_1):page42_i68:a" )
			)
			( pin "C6D8.2"
				( objectStatus "@baseboard_fab2_lib.baseboard_fab2(sch_1):page42_i68:b" )
			)
			( pin "C5D38.1"
				( objectStatus "@baseboard_fab2_lib.baseboard_fab2(sch_1):page42_i69:a" )
			)
			( pin "C5D38.2"
				( objectStatus "@baseboard_fab2_lib.baseboard_fab2(sch_1):page42_i69:b" )
			)
			( pin "C5D37.1"
				( objectStatus "@baseboard_fab2_lib.baseboard_fab2(sch_1):page42_i70:a" )
			)
			( pin "C5D37.2"
				( objectStatus "@baseboard_fab2_lib.baseboard_fab2(sch_1):page42_i70:b" )
			)
			( pin "C6D7.1"
				( objectStatus "@baseboard_fab2_lib.baseboard_fab2(sch_1):page42_i72:a" )
			)
			( pin "C6D7.2"
				( objectStatus "@baseboard_fab2_lib.baseboard_fab2(sch_1):page42_i72:b" )
			)
			( pin "C6D4.1"
				( objectStatus "@baseboard_fab2_lib.baseboard_fab2(sch_1):page42_i74:a" )
			)
			( pin "C6D4.2"
				( objectStatus "@baseboard_fab2_lib.baseboard_fab2(sch_1):page42_i74:b" )
			)
			( pin "C6D5.1"
				( objectStatus "@baseboard_fab2_lib.baseboard_fab2(sch_1):page42_i75:a" )
			)
			( pin "C6D5.2"
				( objectStatus "@baseboard_fab2_lib.baseboard_fab2(sch_1):page42_i75:b" )
			)
			( pin "C6D2.1"
				( objectStatus "@baseboard_fab2_lib.baseboard_fab2(sch_1):page42_i77:a" )
			)
			( pin "C6D2.2"
				( objectStatus "@baseboard_fab2_lib.baseboard_fab2(sch_1):page42_i77:b" )
			)
			( pin "C6D3.1"
				( objectStatus "@baseboard_fab2_lib.baseboard_fab2(sch_1):page42_i80:a" )
			)
			( pin "C6D3.2"
				( objectStatus "@baseboard_fab2_lib.baseboard_fab2(sch_1):page42_i80:b" )
			)
			( pin "C6D6.1"
				( objectStatus "@baseboard_fab2_lib.baseboard_fab2(sch_1):page42_i81:a" )
			)
			( pin "C6D6.2"
				( objectStatus "@baseboard_fab2_lib.baseboard_fab2(sch_1):page42_i81:b" )
			)
			( pin "C5D51.1"
				( objectStatus "@baseboard_fab2_lib.baseboard_fab2(sch_1):page42_i83:a" )
			)
			( pin "C5D51.2"
				( objectStatus "@baseboard_fab2_lib.baseboard_fab2(sch_1):page42_i83:b" )
			)
			( pin "C5D21.1"
				( objectStatus "@baseboard_fab2_lib.baseboard_fab2(sch_1):page42_i88:a" )
			)
			( pin "C5D21.2"
				( objectStatus "@baseboard_fab2_lib.baseboard_fab2(sch_1):page42_i88:b" )
			)
			( pin "C5D50.1"
				( objectStatus "@baseboard_fab2_lib.baseboard_fab2(sch_1):page42_i89:a" )
			)
			( pin "C5D50.2"
				( objectStatus "@baseboard_fab2_lib.baseboard_fab2(sch_1):page42_i89:b" )
			)
			( pin "C5D48.1"
				( objectStatus "@baseboard_fab2_lib.baseboard_fab2(sch_1):page42_i90:a" )
			)
			( pin "C5D48.2"
				( objectStatus "@baseboard_fab2_lib.baseboard_fab2(sch_1):page42_i90:b" )
			)
			( pin "C5D13.1"
				( objectStatus "@baseboard_fab2_lib.baseboard_fab2(sch_1):page42_i91:a" )
			)
			( pin "C5D13.2"
				( objectStatus "@baseboard_fab2_lib.baseboard_fab2(sch_1):page42_i91:b" )
			)
			( pin "C5D11.1"
				( objectStatus "@baseboard_fab2_lib.baseboard_fab2(sch_1):page42_i93:a" )
			)
			( pin "C5D11.2"
				( objectStatus "@baseboard_fab2_lib.baseboard_fab2(sch_1):page42_i93:b" )
			)
			( pin "C5D12.1"
				( objectStatus "@baseboard_fab2_lib.baseboard_fab2(sch_1):page42_i94:a" )
			)
			( pin "C5D12.2"
				( objectStatus "@baseboard_fab2_lib.baseboard_fab2(sch_1):page42_i94:b" )
			)
			( pin "C5D23.1"
				( objectStatus "@baseboard_fab2_lib.baseboard_fab2(sch_1):page42_i98:a" )
			)
			( pin "C5D23.2"
				( objectStatus "@baseboard_fab2_lib.baseboard_fab2(sch_1):page42_i98:b" )
			)
			( pin "C5D28.1"
				( objectStatus "@baseboard_fab2_lib.baseboard_fab2(sch_1):page42_i100:a" )
			)
			( pin "C5D28.2"
				( objectStatus "@baseboard_fab2_lib.baseboard_fab2(sch_1):page42_i100:b" )
			)
			( pin "C5D29.1"
				( objectStatus "@baseboard_fab2_lib.baseboard_fab2(sch_1):page42_i102:a" )
			)
			( pin "C5D29.2"
				( objectStatus "@baseboard_fab2_lib.baseboard_fab2(sch_1):page42_i102:b" )
			)
			( pin "C5D32.1"
				( objectStatus "@baseboard_fab2_lib.baseboard_fab2(sch_1):page42_i103:a" )
			)
			( pin "C5D32.2"
				( objectStatus "@baseboard_fab2_lib.baseboard_fab2(sch_1):page42_i103:b" )
			)
			( pin "C5D47.1"
				( objectStatus "@baseboard_fab2_lib.baseboard_fab2(sch_1):page42_i104:a" )
			)
			( pin "C5D47.2"
				( objectStatus "@baseboard_fab2_lib.baseboard_fab2(sch_1):page42_i104:b" )
			)
			( pin "C5D31.1"
				( objectStatus "@baseboard_fab2_lib.baseboard_fab2(sch_1):page42_i106:a" )
			)
			( pin "C5D31.2"
				( objectStatus "@baseboard_fab2_lib.baseboard_fab2(sch_1):page42_i106:b" )
			)
			( pin "C5D46.1"
				( objectStatus "@baseboard_fab2_lib.baseboard_fab2(sch_1):page42_i107:a" )
			)
			( pin "C5D46.2"
				( objectStatus "@baseboard_fab2_lib.baseboard_fab2(sch_1):page42_i107:b" )
			)
			( pin "C5D10.1"
				( objectStatus "@baseboard_fab2_lib.baseboard_fab2(sch_1):page42_i108:a" )
			)
			( pin "C5D10.2"
				( objectStatus "@baseboard_fab2_lib.baseboard_fab2(sch_1):page42_i108:b" )
			)
			( pin "C5D27.1"
				( objectStatus "@baseboard_fab2_lib.baseboard_fab2(sch_1):page42_i109:a" )
			)
			( pin "C5D27.2"
				( objectStatus "@baseboard_fab2_lib.baseboard_fab2(sch_1):page42_i109:b" )
			)
			( pin "C5D30.1"
				( objectStatus "@baseboard_fab2_lib.baseboard_fab2(sch_1):page42_i111:a" )
			)
			( pin "C5D30.2"
				( objectStatus "@baseboard_fab2_lib.baseboard_fab2(sch_1):page42_i111:b" )
			)
			( pin "C5D60.1"
				( objectStatus "@baseboard_fab2_lib.baseboard_fab2(sch_1):page42_i112:a" )
			)
			( pin "C5D60.2"
				( objectStatus "@baseboard_fab2_lib.baseboard_fab2(sch_1):page42_i112:b" )
			)
			( pin "C5D61.1"
				( objectStatus "@baseboard_fab2_lib.baseboard_fab2(sch_1):page42_i113:a" )
			)
			( pin "C5D61.2"
				( objectStatus "@baseboard_fab2_lib.baseboard_fab2(sch_1):page42_i113:b" )
			)
			( pin "C5D41.1"
				( objectStatus "@baseboard_fab2_lib.baseboard_fab2(sch_1):page42_i114:a" )
			)
			( pin "C5D41.2"
				( objectStatus "@baseboard_fab2_lib.baseboard_fab2(sch_1):page42_i114:b" )
			)
			( pin "C5D40.1"
				( objectStatus "@baseboard_fab2_lib.baseboard_fab2(sch_1):page42_i115:a" )
			)
			( pin "C5D40.2"
				( objectStatus "@baseboard_fab2_lib.baseboard_fab2(sch_1):page42_i115:b" )
			)
			( pin "C5D14.1"
				( objectStatus "@baseboard_fab2_lib.baseboard_fab2(sch_1):page42_i117:a" )
			)
			( pin "C5D14.2"
				( objectStatus "@baseboard_fab2_lib.baseboard_fab2(sch_1):page42_i117:b" )
			)
			( pin "C5D17.1"
				( objectStatus "@baseboard_fab2_lib.baseboard_fab2(sch_1):page42_i118:a" )
			)
			( pin "C5D17.2"
				( objectStatus "@baseboard_fab2_lib.baseboard_fab2(sch_1):page42_i118:b" )
			)
			( pin "C5D58.1"
				( objectStatus "@baseboard_fab2_lib.baseboard_fab2(sch_1):page42_i120:a" )
			)
			( pin "C5D58.2"
				( objectStatus "@baseboard_fab2_lib.baseboard_fab2(sch_1):page42_i120:b" )
			)
			( pin "C5D16.1"
				( objectStatus "@baseboard_fab2_lib.baseboard_fab2(sch_1):page42_i123:a" )
			)
			( pin "C5D16.2"
				( objectStatus "@baseboard_fab2_lib.baseboard_fab2(sch_1):page42_i123:b" )
			)
			( pin "C5D5.1"
				( objectStatus "@baseboard_fab2_lib.baseboard_fab2(sch_1):page42_i125:a" )
			)
			( pin "C5D5.2"
				( objectStatus "@baseboard_fab2_lib.baseboard_fab2(sch_1):page42_i125:b" )
			)
			( pin "C5D1.1"
				( objectStatus "@baseboard_fab2_lib.baseboard_fab2(sch_1):page42_i126:a" )
			)
			( pin "C5D1.2"
				( objectStatus "@baseboard_fab2_lib.baseboard_fab2(sch_1):page42_i126:b" )
			)
			( pin "C5D4.1"
				( objectStatus "@baseboard_fab2_lib.baseboard_fab2(sch_1):page42_i127:a" )
			)
			( pin "C5D4.2"
				( objectStatus "@baseboard_fab2_lib.baseboard_fab2(sch_1):page42_i127:b" )
			)
			( pin "C5D19.1"
				( objectStatus "@baseboard_fab2_lib.baseboard_fab2(sch_1):page42_i128:a" )
			)
			( pin "C5D19.2"
				( objectStatus "@baseboard_fab2_lib.baseboard_fab2(sch_1):page42_i128:b" )
			)
			( pin "C5D59.1"
				( objectStatus "@baseboard_fab2_lib.baseboard_fab2(sch_1):page42_i129:a" )
			)
			( pin "C5D59.2"
				( objectStatus "@baseboard_fab2_lib.baseboard_fab2(sch_1):page42_i129:b" )
			)
			( pin "C5D3.1"
				( objectStatus "@baseboard_fab2_lib.baseboard_fab2(sch_1):page42_i130:a" )
			)
			( pin "C5D3.2"
				( objectStatus "@baseboard_fab2_lib.baseboard_fab2(sch_1):page42_i130:b" )
			)
			( pin "C5D43.1"
				( objectStatus "@baseboard_fab2_lib.baseboard_fab2(sch_1):page42_i131:a" )
			)
			( pin "C5D43.2"
				( objectStatus "@baseboard_fab2_lib.baseboard_fab2(sch_1):page42_i131:b" )
			)
			( pin "C5D15.1"
				( objectStatus "@baseboard_fab2_lib.baseboard_fab2(sch_1):page42_i132:a" )
			)
			( pin "C5D15.2"
				( objectStatus "@baseboard_fab2_lib.baseboard_fab2(sch_1):page42_i132:b" )
			)
			( pin "C5D18.1"
				( objectStatus "@baseboard_fab2_lib.baseboard_fab2(sch_1):page42_i134:a" )
			)
			( pin "C5D18.2"
				( objectStatus "@baseboard_fab2_lib.baseboard_fab2(sch_1):page42_i134:b" )
			)
			( pin "C5D42.1"
				( objectStatus "@baseboard_fab2_lib.baseboard_fab2(sch_1):page42_i135:a" )
			)
			( pin "C5D42.2"
				( objectStatus "@baseboard_fab2_lib.baseboard_fab2(sch_1):page42_i135:b" )
			)
			( pin "C5D2.1"
				( objectStatus "@baseboard_fab2_lib.baseboard_fab2(sch_1):page42_i136:a" )
			)
			( pin "C5D2.2"
				( objectStatus "@baseboard_fab2_lib.baseboard_fab2(sch_1):page42_i136:b" )
			)
			( pin "C5D24.1"
				( objectStatus "@baseboard_fab2_lib.baseboard_fab2(sch_1):page42_i138:a" )
			)
			( pin "C5D24.2"
				( objectStatus "@baseboard_fab2_lib.baseboard_fab2(sch_1):page42_i138:b" )
			)
			( pin "C5D39.1"
				( objectStatus "@baseboard_fab2_lib.baseboard_fab2(sch_1):page42_i140:a" )
			)
			( pin "C5D39.2"
				( objectStatus "@baseboard_fab2_lib.baseboard_fab2(sch_1):page42_i140:b" )
			)
			( pin "C5D44.1"
				( objectStatus "@baseboard_fab2_lib.baseboard_fab2(sch_1):page42_i142:a" )
			)
			( pin "C5D44.2"
				( objectStatus "@baseboard_fab2_lib.baseboard_fab2(sch_1):page42_i142:b" )
			)
			( pin "C6D9.1"
				( objectStatus "@baseboard_fab2_lib.baseboard_fab2(sch_1):page42_i145:a" )
			)
			( pin "C6D9.2"
				( objectStatus "@baseboard_fab2_lib.baseboard_fab2(sch_1):page42_i145:b" )
			)
			( pin "C6D10.1"
				( objectStatus "@baseboard_fab2_lib.baseboard_fab2(sch_1):page42_i147:a" )
			)
			( pin "C6D10.2"
				( objectStatus "@baseboard_fab2_lib.baseboard_fab2(sch_1):page42_i147:b" )
			)
			( pin "C5P30.1"
				( objectStatus "@baseboard_fab2_lib.baseboard_fab2(sch_1):page42_i148:a" )
			)
			( pin "C5P30.2"
				( objectStatus "@baseboard_fab2_lib.baseboard_fab2(sch_1):page42_i148:b" )
			)
			( pin "C5P29.1"
				( objectStatus "@baseboard_fab2_lib.baseboard_fab2(sch_1):page42_i149:a" )
			)
			( pin "C5P29.2"
				( objectStatus "@baseboard_fab2_lib.baseboard_fab2(sch_1):page42_i149:b" )
			)
			( pin "C5D36.1"
				( objectStatus "@baseboard_fab2_lib.baseboard_fab2(sch_1):page42_i151:a" )
			)
			( pin "C5D36.2"
				( objectStatus "@baseboard_fab2_lib.baseboard_fab2(sch_1):page42_i151:b" )
			)
			( pin "C5D49.1"
				( objectStatus "@baseboard_fab2_lib.baseboard_fab2(sch_1):page42_i152:a" )
			)
			( pin "C5D49.2"
				( objectStatus "@baseboard_fab2_lib.baseboard_fab2(sch_1):page42_i152:b" )
			)
			( pin "C5D22.1"
				( objectStatus "@baseboard_fab2_lib.baseboard_fab2(sch_1):page42_i153:a" )
			)
			( pin "C5D22.2"
				( objectStatus "@baseboard_fab2_lib.baseboard_fab2(sch_1):page42_i153:b" )
			)
			( pin "C5D26.1"
				( objectStatus "@baseboard_fab2_lib.baseboard_fab2(sch_1):page42_i154:a" )
			)
			( pin "C5D26.2"
				( objectStatus "@baseboard_fab2_lib.baseboard_fab2(sch_1):page42_i154:b" )
			)
			( pin "C5D25.1"
				( objectStatus "@baseboard_fab2_lib.baseboard_fab2(sch_1):page42_i155:a" )
			)
			( pin "C5D25.2"
				( objectStatus "@baseboard_fab2_lib.baseboard_fab2(sch_1):page42_i155:b" )
			)
			( pin "C5D45.1"
				( objectStatus "@baseboard_fab2_lib.baseboard_fab2(sch_1):page42_i156:a" )
			)
			( pin "C5D45.2"
				( objectStatus "@baseboard_fab2_lib.baseboard_fab2(sch_1):page42_i156:b" )
			)
			( pin "C5P31.1"
				( objectStatus "@baseboard_fab2_lib.baseboard_fab2(sch_1):page42_i162:a" )
			)
			( pin "C5P31.2"
				( objectStatus "@baseboard_fab2_lib.baseboard_fab2(sch_1):page42_i162:b" )
			)
			( pin "C4P2.1"
				( objectStatus "@baseboard_fab2_lib.baseboard_fab2(sch_1):page42_i163:a" )
			)
			( pin "C4P2.2"
				( objectStatus "@baseboard_fab2_lib.baseboard_fab2(sch_1):page42_i163:b" )
			)
			( pin "C4P6.1"
				( objectStatus "@baseboard_fab2_lib.baseboard_fab2(sch_1):page42_i164:a" )
			)
			( pin "C4P6.2"
				( objectStatus "@baseboard_fab2_lib.baseboard_fab2(sch_1):page42_i164:b" )
			)
			( pin "C4P5.1"
				( objectStatus "@baseboard_fab2_lib.baseboard_fab2(sch_1):page42_i172:a" )
			)
			( pin "C4P5.2"
				( objectStatus "@baseboard_fab2_lib.baseboard_fab2(sch_1):page42_i172:b" )
			)
			( pin "C5D20.1"
				( objectStatus "@baseboard_fab2_lib.baseboard_fab2(sch_1):page42_i173:a" )
			)
			( pin "C5D20.2"
				( objectStatus "@baseboard_fab2_lib.baseboard_fab2(sch_1):page42_i173:b" )
			)
			( pin "C5D33.1"
				( objectStatus "@baseboard_fab2_lib.baseboard_fab2(sch_1):page42_i174:a" )
			)
			( pin "C5D33.2"
				( objectStatus "@baseboard_fab2_lib.baseboard_fab2(sch_1):page42_i174:b" )
			)
			( pin "C5D34.1"
				( objectStatus "@baseboard_fab2_lib.baseboard_fab2(sch_1):page42_i175:a" )
			)
			( pin "C5D34.2"
				( objectStatus "@baseboard_fab2_lib.baseboard_fab2(sch_1):page42_i175:b" )
			)
			( pin "C5D35.1"
				( objectStatus "@baseboard_fab2_lib.baseboard_fab2(sch_1):page42_i176:a" )
			)
			( pin "C5D35.2"
				( objectStatus "@baseboard_fab2_lib.baseboard_fab2(sch_1):page42_i176:b" )
			)
			( pin "C4P8.1"
				( objectStatus "@baseboard_fab2_lib.baseboard_fab2(sch_1):page42_i178:a" )
			)
			( pin "C4P8.2"
				( objectStatus "@baseboard_fab2_lib.baseboard_fab2(sch_1):page42_i178:b" )
			)
			( pin "C5D53.1"
				( objectStatus "@baseboard_fab2_lib.baseboard_fab2(sch_1):page42_i179:a" )
			)
			( pin "C5D53.2"
				( objectStatus "@baseboard_fab2_lib.baseboard_fab2(sch_1):page42_i179:b" )
			)
			( pin "C5D52.1"
				( objectStatus "@baseboard_fab2_lib.baseboard_fab2(sch_1):page42_i180:a" )
			)
			( pin "C5D52.2"
				( objectStatus "@baseboard_fab2_lib.baseboard_fab2(sch_1):page42_i180:b" )
			)
			( pin "C5P12.1"
				( objectStatus "@baseboard_fab2_lib.baseboard_fab2(sch_1):page42_i183:a" )
			)
			( pin "C5P12.2"
				( objectStatus "@baseboard_fab2_lib.baseboard_fab2(sch_1):page42_i183:b" )
			)
			( pin "C5P21.1"
				( objectStatus "@baseboard_fab2_lib.baseboard_fab2(sch_1):page42_i184:a" )
			)
			( pin "C5P21.2"
				( objectStatus "@baseboard_fab2_lib.baseboard_fab2(sch_1):page42_i184:b" )
			)
			( pin "C5P20.1"
				( objectStatus "@baseboard_fab2_lib.baseboard_fab2(sch_1):page42_i185:a" )
			)
			( pin "C5P20.2"
				( objectStatus "@baseboard_fab2_lib.baseboard_fab2(sch_1):page42_i185:b" )
			)
			( pin "C5P13.1"
				( objectStatus "@baseboard_fab2_lib.baseboard_fab2(sch_1):page42_i186:a" )
			)
			( pin "C5P13.2"
				( objectStatus "@baseboard_fab2_lib.baseboard_fab2(sch_1):page42_i186:b" )
			)
			( pin "C5P15.1"
				( objectStatus "@baseboard_fab2_lib.baseboard_fab2(sch_1):page42_i187:a" )
			)
			( pin "C5P15.2"
				( objectStatus "@baseboard_fab2_lib.baseboard_fab2(sch_1):page42_i187:b" )
			)
			( pin "C5P16.1"
				( objectStatus "@baseboard_fab2_lib.baseboard_fab2(sch_1):page42_i188:a" )
			)
			( pin "C5P16.2"
				( objectStatus "@baseboard_fab2_lib.baseboard_fab2(sch_1):page42_i188:b" )
			)
			( pin "C5P3.1"
				( objectStatus "@baseboard_fab2_lib.baseboard_fab2(sch_1):page42_i189:a" )
			)
			( pin "C5P3.2"
				( objectStatus "@baseboard_fab2_lib.baseboard_fab2(sch_1):page42_i189:b" )
			)
			( pin "C5P17.1"
				( objectStatus "@baseboard_fab2_lib.baseboard_fab2(sch_1):page42_i190:a" )
			)
			( pin "C5P17.2"
				( objectStatus "@baseboard_fab2_lib.baseboard_fab2(sch_1):page42_i190:b" )
			)
			( pin "J4G1.79"
				( objectStatus "@baseboard_fab2_lib.baseboard_fab2(sch_1):page43_i1:a0" )
			)
			( pin "J4G1.72"
				( objectStatus "@baseboard_fab2_lib.baseboard_fab2(sch_1):page43_i1:a1" )
			)
			( pin "J4G1.216"
				( objectStatus "@baseboard_fab2_lib.baseboard_fab2(sch_1):page43_i1:a2" )
			)
			( pin "J4G1.71"
				( objectStatus "@baseboard_fab2_lib.baseboard_fab2(sch_1):page43_i1:a3" )
			)
			( pin "J4G1.214"
				( objectStatus "@baseboard_fab2_lib.baseboard_fab2(sch_1):page43_i1:a4" )
			)
			( pin "J4G1.213"
				( objectStatus "@baseboard_fab2_lib.baseboard_fab2(sch_1):page43_i1:a5" )
			)
			( pin "J4G1.69"
				( objectStatus "@baseboard_fab2_lib.baseboard_fab2(sch_1):page43_i1:a6" )
			)
			( pin "J4G1.211"
				( objectStatus "@baseboard_fab2_lib.baseboard_fab2(sch_1):page43_i1:a7" )
			)
			( pin "J4G1.68"
				( objectStatus "@baseboard_fab2_lib.baseboard_fab2(sch_1):page43_i1:a8" )
			)
			( pin "J4G1.66"
				( objectStatus "@baseboard_fab2_lib.baseboard_fab2(sch_1):page43_i1:a9" )
			)
			( pin "J4G1.225"
				( objectStatus "@baseboard_fab2_lib.baseboard_fab2(sch_1):page43_i1:a10" )
			)
			( pin "J4G1.210"
				( objectStatus "@baseboard_fab2_lib.baseboard_fab2(sch_1):page43_i1:a11" )
			)
			( pin "J4G1.65"
				( objectStatus "@baseboard_fab2_lib.baseboard_fab2(sch_1):page43_i1:a12" )
			)
			( pin "J4G1.232"
				( objectStatus "@baseboard_fab2_lib.baseboard_fab2(sch_1):page43_i1:a13" )
			)
			( pin "J4G1.228"
				( objectStatus "@baseboard_fab2_lib.baseboard_fab2(sch_1):page43_i1:a14_we_n" )
			)
			( pin "J4G1.86"
				( objectStatus "@baseboard_fab2_lib.baseboard_fab2(sch_1):page43_i1:a15_cas_n" )
			)
			( pin "J4G1.82"
				( objectStatus "@baseboard_fab2_lib.baseboard_fab2(sch_1):page43_i1:a16_ras_n" )
			)
			( pin "J4G1.234"
				( objectStatus "@baseboard_fab2_lib.baseboard_fab2(sch_1):page43_i1:a17" )
			)
			( pin "J4G1.62"
				( objectStatus "@baseboard_fab2_lib.baseboard_fab2(sch_1):page43_i1:act_n" )
			)
			( pin "J4G1.208"
				( objectStatus "@baseboard_fab2_lib.baseboard_fab2(sch_1):page43_i1:alert_n" )
			)
			( pin "J4G1.81"
				( objectStatus "@baseboard_fab2_lib.baseboard_fab2(sch_1):page43_i1:ba(0)" )
			)
			( pin "J4G1.224"
				( objectStatus "@baseboard_fab2_lib.baseboard_fab2(sch_1):page43_i1:ba(1)" )
			)
			( pin "J4G1.63"
				( objectStatus "@baseboard_fab2_lib.baseboard_fab2(sch_1):page43_i1:bg(0)" )
			)
			( pin "J4G1.207"
				( objectStatus "@baseboard_fab2_lib.baseboard_fab2(sch_1):page43_i1:bg(1)" )
			)
			( pin "J4G1.235"
				( objectStatus "@baseboard_fab2_lib.baseboard_fab2(sch_1):page43_i1:c(2)" )
			)
			( pin "J4G1.49"
				( objectStatus "@baseboard_fab2_lib.baseboard_fab2(sch_1):page43_i1:cb(0)" )
			)
			( pin "J4G1.194"
				( objectStatus "@baseboard_fab2_lib.baseboard_fab2(sch_1):page43_i1:cb(1)" )
			)
			( pin "J4G1.56"
				( objectStatus "@baseboard_fab2_lib.baseboard_fab2(sch_1):page43_i1:cb(2)" )
			)
			( pin "J4G1.201"
				( objectStatus "@baseboard_fab2_lib.baseboard_fab2(sch_1):page43_i1:cb(3)" )
			)
			( pin "J4G1.47"
				( objectStatus "@baseboard_fab2_lib.baseboard_fab2(sch_1):page43_i1:cb(4)" )
			)
			( pin "J4G1.192"
				( objectStatus "@baseboard_fab2_lib.baseboard_fab2(sch_1):page43_i1:cb(5)" )
			)
			( pin "J4G1.54"
				( objectStatus "@baseboard_fab2_lib.baseboard_fab2(sch_1):page43_i1:cb(6)" )
			)
			( pin "J4G1.199"
				( objectStatus "@baseboard_fab2_lib.baseboard_fab2(sch_1):page43_i1:cb(7)" )
			)
			( pin "J4G1.75"
				( objectStatus "@baseboard_fab2_lib.baseboard_fab2(sch_1):page43_i1:ck0n" )
			)
			( pin "J4G1.74"
				( objectStatus "@baseboard_fab2_lib.baseboard_fab2(sch_1):page43_i1:ck0p" )
			)
			( pin "J4G1.219"
				( objectStatus "@baseboard_fab2_lib.baseboard_fab2(sch_1):page43_i1:ck1n" )
			)
			( pin "J4G1.218"
				( objectStatus "@baseboard_fab2_lib.baseboard_fab2(sch_1):page43_i1:ck1p" )
			)
			( pin "J4G1.60"
				( objectStatus "@baseboard_fab2_lib.baseboard_fab2(sch_1):page43_i1:cke(0)" )
			)
			( pin "J4G1.203"
				( objectStatus "@baseboard_fab2_lib.baseboard_fab2(sch_1):page43_i1:cke(1)" )
			)
			( pin "J4G1.5"
				( objectStatus "@baseboard_fab2_lib.baseboard_fab2(sch_1):page43_i1:dq(0)" )
			)
			( pin "J4G1.150"
				( objectStatus "@baseboard_fab2_lib.baseboard_fab2(sch_1):page43_i1:dq(1)" )
			)
			( pin "J4G1.12"
				( objectStatus "@baseboard_fab2_lib.baseboard_fab2(sch_1):page43_i1:dq(2)" )
			)
			( pin "J4G1.157"
				( objectStatus "@baseboard_fab2_lib.baseboard_fab2(sch_1):page43_i1:dq(3)" )
			)
			( pin "J4G1.3"
				( objectStatus "@baseboard_fab2_lib.baseboard_fab2(sch_1):page43_i1:dq(4)" )
			)
			( pin "J4G1.148"
				( objectStatus "@baseboard_fab2_lib.baseboard_fab2(sch_1):page43_i1:dq(5)" )
			)
			( pin "J4G1.10"
				( objectStatus "@baseboard_fab2_lib.baseboard_fab2(sch_1):page43_i1:dq(6)" )
			)
			( pin "J4G1.155"
				( objectStatus "@baseboard_fab2_lib.baseboard_fab2(sch_1):page43_i1:dq(7)" )
			)
			( pin "J4G1.16"
				( objectStatus "@baseboard_fab2_lib.baseboard_fab2(sch_1):page43_i1:dq(8)" )
			)
			( pin "J4G1.161"
				( objectStatus "@baseboard_fab2_lib.baseboard_fab2(sch_1):page43_i1:dq(9)" )
			)
			( pin "J4G1.23"
				( objectStatus "@baseboard_fab2_lib.baseboard_fab2(sch_1):page43_i1:dq(10)" )
			)
			( pin "J4G1.168"
				( objectStatus "@baseboard_fab2_lib.baseboard_fab2(sch_1):page43_i1:dq(11)" )
			)
			( pin "J4G1.14"
				( objectStatus "@baseboard_fab2_lib.baseboard_fab2(sch_1):page43_i1:dq(12)" )
			)
			( pin "J4G1.159"
				( objectStatus "@baseboard_fab2_lib.baseboard_fab2(sch_1):page43_i1:dq(13)" )
			)
			( pin "J4G1.21"
				( objectStatus "@baseboard_fab2_lib.baseboard_fab2(sch_1):page43_i1:dq(14)" )
			)
			( pin "J4G1.166"
				( objectStatus "@baseboard_fab2_lib.baseboard_fab2(sch_1):page43_i1:dq(15)" )
			)
			( pin "J4G1.27"
				( objectStatus "@baseboard_fab2_lib.baseboard_fab2(sch_1):page43_i1:dq(16)" )
			)
			( pin "J4G1.172"
				( objectStatus "@baseboard_fab2_lib.baseboard_fab2(sch_1):page43_i1:dq(17)" )
			)
			( pin "J4G1.34"
				( objectStatus "@baseboard_fab2_lib.baseboard_fab2(sch_1):page43_i1:dq(18)" )
			)
			( pin "J4G1.179"
				( objectStatus "@baseboard_fab2_lib.baseboard_fab2(sch_1):page43_i1:dq(19)" )
			)
			( pin "J4G1.25"
				( objectStatus "@baseboard_fab2_lib.baseboard_fab2(sch_1):page43_i1:dq(20)" )
			)
			( pin "J4G1.170"
				( objectStatus "@baseboard_fab2_lib.baseboard_fab2(sch_1):page43_i1:dq(21)" )
			)
			( pin "J4G1.32"
				( objectStatus "@baseboard_fab2_lib.baseboard_fab2(sch_1):page43_i1:dq(22)" )
			)
			( pin "J4G1.177"
				( objectStatus "@baseboard_fab2_lib.baseboard_fab2(sch_1):page43_i1:dq(23)" )
			)
			( pin "J4G1.38"
				( objectStatus "@baseboard_fab2_lib.baseboard_fab2(sch_1):page43_i1:dq(24)" )
			)
			( pin "J4G1.183"
				( objectStatus "@baseboard_fab2_lib.baseboard_fab2(sch_1):page43_i1:dq(25)" )
			)
			( pin "J4G1.45"
				( objectStatus "@baseboard_fab2_lib.baseboard_fab2(sch_1):page43_i1:dq(26)" )
			)
			( pin "J4G1.190"
				( objectStatus "@baseboard_fab2_lib.baseboard_fab2(sch_1):page43_i1:dq(27)" )
			)
			( pin "J4G1.36"
				( objectStatus "@baseboard_fab2_lib.baseboard_fab2(sch_1):page43_i1:dq(28)" )
			)
			( pin "J4G1.181"
				( objectStatus "@baseboard_fab2_lib.baseboard_fab2(sch_1):page43_i1:dq(29)" )
			)
			( pin "J4G1.43"
				( objectStatus "@baseboard_fab2_lib.baseboard_fab2(sch_1):page43_i1:dq(30)" )
			)
			( pin "J4G1.188"
				( objectStatus "@baseboard_fab2_lib.baseboard_fab2(sch_1):page43_i1:dq(31)" )
			)
			( pin "J4G1.97"
				( objectStatus "@baseboard_fab2_lib.baseboard_fab2(sch_1):page43_i1:dq(32)" )
			)
			( pin "J4G1.242"
				( objectStatus "@baseboard_fab2_lib.baseboard_fab2(sch_1):page43_i1:dq(33)" )
			)
			( pin "J4G1.104"
				( objectStatus "@baseboard_fab2_lib.baseboard_fab2(sch_1):page43_i1:dq(34)" )
			)
			( pin "J4G1.249"
				( objectStatus "@baseboard_fab2_lib.baseboard_fab2(sch_1):page43_i1:dq(35)" )
			)
			( pin "J4G1.95"
				( objectStatus "@baseboard_fab2_lib.baseboard_fab2(sch_1):page43_i1:dq(36)" )
			)
			( pin "J4G1.240"
				( objectStatus "@baseboard_fab2_lib.baseboard_fab2(sch_1):page43_i1:dq(37)" )
			)
			( pin "J4G1.102"
				( objectStatus "@baseboard_fab2_lib.baseboard_fab2(sch_1):page43_i1:dq(38)" )
			)
			( pin "J4G1.247"
				( objectStatus "@baseboard_fab2_lib.baseboard_fab2(sch_1):page43_i1:dq(39)" )
			)
			( pin "J4G1.108"
				( objectStatus "@baseboard_fab2_lib.baseboard_fab2(sch_1):page43_i1:dq(40)" )
			)
			( pin "J4G1.253"
				( objectStatus "@baseboard_fab2_lib.baseboard_fab2(sch_1):page43_i1:dq(41)" )
			)
			( pin "J4G1.115"
				( objectStatus "@baseboard_fab2_lib.baseboard_fab2(sch_1):page43_i1:dq(42)" )
			)
			( pin "J4G1.260"
				( objectStatus "@baseboard_fab2_lib.baseboard_fab2(sch_1):page43_i1:dq(43)" )
			)
			( pin "J4G1.106"
				( objectStatus "@baseboard_fab2_lib.baseboard_fab2(sch_1):page43_i1:dq(44)" )
			)
			( pin "J4G1.251"
				( objectStatus "@baseboard_fab2_lib.baseboard_fab2(sch_1):page43_i1:dq(45)" )
			)
			( pin "J4G1.113"
				( objectStatus "@baseboard_fab2_lib.baseboard_fab2(sch_1):page43_i1:dq(46)" )
			)
			( pin "J4G1.258"
				( objectStatus "@baseboard_fab2_lib.baseboard_fab2(sch_1):page43_i1:dq(47)" )
			)
			( pin "J4G1.119"
				( objectStatus "@baseboard_fab2_lib.baseboard_fab2(sch_1):page43_i1:dq(48)" )
			)
			( pin "J4G1.264"
				( objectStatus "@baseboard_fab2_lib.baseboard_fab2(sch_1):page43_i1:dq(49)" )
			)
			( pin "J4G1.126"
				( objectStatus "@baseboard_fab2_lib.baseboard_fab2(sch_1):page43_i1:dq(50)" )
			)
			( pin "J4G1.271"
				( objectStatus "@baseboard_fab2_lib.baseboard_fab2(sch_1):page43_i1:dq(51)" )
			)
			( pin "J4G1.117"
				( objectStatus "@baseboard_fab2_lib.baseboard_fab2(sch_1):page43_i1:dq(52)" )
			)
			( pin "J4G1.262"
				( objectStatus "@baseboard_fab2_lib.baseboard_fab2(sch_1):page43_i1:dq(53)" )
			)
			( pin "J4G1.124"
				( objectStatus "@baseboard_fab2_lib.baseboard_fab2(sch_1):page43_i1:dq(54)" )
			)
			( pin "J4G1.269"
				( objectStatus "@baseboard_fab2_lib.baseboard_fab2(sch_1):page43_i1:dq(55)" )
			)
			( pin "J4G1.130"
				( objectStatus "@baseboard_fab2_lib.baseboard_fab2(sch_1):page43_i1:dq(56)" )
			)
			( pin "J4G1.275"
				( objectStatus "@baseboard_fab2_lib.baseboard_fab2(sch_1):page43_i1:dq(57)" )
			)
			( pin "J4G1.137"
				( objectStatus "@baseboard_fab2_lib.baseboard_fab2(sch_1):page43_i1:dq(58)" )
			)
			( pin "J4G1.282"
				( objectStatus "@baseboard_fab2_lib.baseboard_fab2(sch_1):page43_i1:dq(59)" )
			)
			( pin "J4G1.128"
				( objectStatus "@baseboard_fab2_lib.baseboard_fab2(sch_1):page43_i1:dq(60)" )
			)
			( pin "J4G1.273"
				( objectStatus "@baseboard_fab2_lib.baseboard_fab2(sch_1):page43_i1:dq(61)" )
			)
			( pin "J4G1.135"
				( objectStatus "@baseboard_fab2_lib.baseboard_fab2(sch_1):page43_i1:dq(62)" )
			)
			( pin "J4G1.280"
				( objectStatus "@baseboard_fab2_lib.baseboard_fab2(sch_1):page43_i1:dq(63)" )
			)
			( pin "J4G1.78"
				( objectStatus "@baseboard_fab2_lib.baseboard_fab2(sch_1):page43_i1:event_n" )
			)
			( pin "J4G1.87"
				( objectStatus "@baseboard_fab2_lib.baseboard_fab2(sch_1):page43_i1:odt(0)" )
			)
			( pin "J4G1.91"
				( objectStatus "@baseboard_fab2_lib.baseboard_fab2(sch_1):page43_i1:odt(1)" )
			)
			( pin "J4G1.222"
				( objectStatus "@baseboard_fab2_lib.baseboard_fab2(sch_1):page43_i1:par" )
			)
			( pin "J4G1.58"
				( objectStatus "@baseboard_fab2_lib.baseboard_fab2(sch_1):page43_i1:reset_n" )
			)
			( pin "J4G1.205"
				( objectStatus "@baseboard_fab2_lib.baseboard_fab2(sch_1):page43_i1:rfu(0)" )
			)
			( pin "J4G1.227"
				( objectStatus "@baseboard_fab2_lib.baseboard_fab2(sch_1):page43_i1:rfu(1)" )
			)
			( pin "J4G1.144"
				( objectStatus "@baseboard_fab2_lib.baseboard_fab2(sch_1):page43_i1:rfu(2)" )
			)
			( pin "J4G1.84"
				( objectStatus "@baseboard_fab2_lib.baseboard_fab2(sch_1):page43_i1:s0_n" )
			)
			( pin "J4G1.89"
				( objectStatus "@baseboard_fab2_lib.baseboard_fab2(sch_1):page43_i1:s1_n" )
			)
			( pin "J4G1.93"
				( objectStatus "@baseboard_fab2_lib.baseboard_fab2(sch_1):page43_i1:s2_n_c(0)" )
			)
			( pin "J4G1.237"
				( objectStatus "@baseboard_fab2_lib.baseboard_fab2(sch_1):page43_i1:s3_n_c(1)" )
			)
			( pin "J4G1.139"
				( objectStatus "@baseboard_fab2_lib.baseboard_fab2(sch_1):page43_i1:sa(0)" )
			)
			( pin "J4G1.140"
				( objectStatus "@baseboard_fab2_lib.baseboard_fab2(sch_1):page43_i1:sa(1)" )
			)
			( pin "J4G1.238"
				( objectStatus "@baseboard_fab2_lib.baseboard_fab2(sch_1):page43_i1:sa(2)" )
			)
			( pin "J4G1.230"
				( objectStatus "@baseboard_fab2_lib.baseboard_fab2(sch_1):page43_i1:save_n_nc" )
			)
			( pin "J4G1.141"
				( objectStatus "@baseboard_fab2_lib.baseboard_fab2(sch_1):page43_i1:scl" )
			)
			( pin "J4G1.285"
				( objectStatus "@baseboard_fab2_lib.baseboard_fab2(sch_1):page43_i1:sda" )
			)
			( pin "J4G1.284"
				( objectStatus "@baseboard_fab2_lib.baseboard_fab2(sch_1):page43_i1:vddspd" )
			)
			( pin "J4G1.146"
				( objectStatus "@baseboard_fab2_lib.baseboard_fab2(sch_1):page43_i1:vrefca" )
			)
			( pin "J4G1.152"
				( objectStatus "@baseboard_fab2_lib.baseboard_fab2(sch_1):page43_i2:dqs0n" )
			)
			( pin "J4G1.153"
				( objectStatus "@baseboard_fab2_lib.baseboard_fab2(sch_1):page43_i2:dqs0p" )
			)
			( pin "J4G1.163"
				( objectStatus "@baseboard_fab2_lib.baseboard_fab2(sch_1):page43_i2:dqs1n" )
			)
			( pin "J4G1.164"
				( objectStatus "@baseboard_fab2_lib.baseboard_fab2(sch_1):page43_i2:dqs1p" )
			)
			( pin "J4G1.174"
				( objectStatus "@baseboard_fab2_lib.baseboard_fab2(sch_1):page43_i2:dqs2n" )
			)
			( pin "J4G1.175"
				( objectStatus "@baseboard_fab2_lib.baseboard_fab2(sch_1):page43_i2:dqs2p" )
			)
			( pin "J4G1.185"
				( objectStatus "@baseboard_fab2_lib.baseboard_fab2(sch_1):page43_i2:dqs3n" )
			)
			( pin "J4G1.186"
				( objectStatus "@baseboard_fab2_lib.baseboard_fab2(sch_1):page43_i2:dqs3p" )
			)
			( pin "J4G1.244"
				( objectStatus "@baseboard_fab2_lib.baseboard_fab2(sch_1):page43_i2:dqs4n" )
			)
			( pin "J4G1.245"
				( objectStatus "@baseboard_fab2_lib.baseboard_fab2(sch_1):page43_i2:dqs4p" )
			)
			( pin "J4G1.255"
				( objectStatus "@baseboard_fab2_lib.baseboard_fab2(sch_1):page43_i2:dqs5n" )
			)
			( pin "J4G1.256"
				( objectStatus "@baseboard_fab2_lib.baseboard_fab2(sch_1):page43_i2:dqs5p" )
			)
			( pin "J4G1.266"
				( objectStatus "@baseboard_fab2_lib.baseboard_fab2(sch_1):page43_i2:dqs6n" )
			)
			( pin "J4G1.267"
				( objectStatus "@baseboard_fab2_lib.baseboard_fab2(sch_1):page43_i2:dqs6p" )
			)
			( pin "J4G1.277"
				( objectStatus "@baseboard_fab2_lib.baseboard_fab2(sch_1):page43_i2:dqs7n" )
			)
			( pin "J4G1.278"
				( objectStatus "@baseboard_fab2_lib.baseboard_fab2(sch_1):page43_i2:dqs7p" )
			)
			( pin "J4G1.196"
				( objectStatus "@baseboard_fab2_lib.baseboard_fab2(sch_1):page43_i2:dqs8n" )
			)
			( pin "J4G1.197"
				( objectStatus "@baseboard_fab2_lib.baseboard_fab2(sch_1):page43_i2:dqs8p" )
			)
			( pin "J4G1.8"
				( objectStatus "@baseboard_fab2_lib.baseboard_fab2(sch_1):page43_i2:dqs9n" )
			)
			( pin "J4G1.7"
				( objectStatus "@baseboard_fab2_lib.baseboard_fab2(sch_1):page43_i2:dqs9p" )
			)
			( pin "J4G1.19"
				( objectStatus "@baseboard_fab2_lib.baseboard_fab2(sch_1):page43_i2:dqs10n" )
			)
			( pin "J4G1.18"
				( objectStatus "@baseboard_fab2_lib.baseboard_fab2(sch_1):page43_i2:dqs10p" )
			)
			( pin "J4G1.30"
				( objectStatus "@baseboard_fab2_lib.baseboard_fab2(sch_1):page43_i2:dqs11n" )
			)
			( pin "J4G1.29"
				( objectStatus "@baseboard_fab2_lib.baseboard_fab2(sch_1):page43_i2:dqs11p" )
			)
			( pin "J4G1.41"
				( objectStatus "@baseboard_fab2_lib.baseboard_fab2(sch_1):page43_i2:dqs12n" )
			)
			( pin "J4G1.40"
				( objectStatus "@baseboard_fab2_lib.baseboard_fab2(sch_1):page43_i2:dqs12p" )
			)
			( pin "J4G1.100"
				( objectStatus "@baseboard_fab2_lib.baseboard_fab2(sch_1):page43_i2:dqs13n" )
			)
			( pin "J4G1.99"
				( objectStatus "@baseboard_fab2_lib.baseboard_fab2(sch_1):page43_i2:dqs13p" )
			)
			( pin "J4G1.111"
				( objectStatus "@baseboard_fab2_lib.baseboard_fab2(sch_1):page43_i2:dqs14n" )
			)
			( pin "J4G1.110"
				( objectStatus "@baseboard_fab2_lib.baseboard_fab2(sch_1):page43_i2:dqs14p" )
			)
			( pin "J4G1.122"
				( objectStatus "@baseboard_fab2_lib.baseboard_fab2(sch_1):page43_i2:dqs15n" )
			)
			( pin "J4G1.121"
				( objectStatus "@baseboard_fab2_lib.baseboard_fab2(sch_1):page43_i2:dqs15p" )
			)
			( pin "J4G1.133"
				( objectStatus "@baseboard_fab2_lib.baseboard_fab2(sch_1):page43_i2:dqs16n" )
			)
			( pin "J4G1.132"
				( objectStatus "@baseboard_fab2_lib.baseboard_fab2(sch_1):page43_i2:dqs16p" )
			)
			( pin "J4G1.52"
				( objectStatus "@baseboard_fab2_lib.baseboard_fab2(sch_1):page43_i2:dqs17n" )
			)
			( pin "J4G1.51"
				( objectStatus "@baseboard_fab2_lib.baseboard_fab2(sch_1):page43_i2:dqs17p" )
			)
			( pin "J4G1.283"
				( objectStatus "@baseboard_fab2_lib.baseboard_fab2(sch_1):page43_i259:vss(0)" )
			)
			( pin "J4G1.281"
				( objectStatus "@baseboard_fab2_lib.baseboard_fab2(sch_1):page43_i259:vss(1)" )
			)
			( pin "J4G1.279"
				( objectStatus "@baseboard_fab2_lib.baseboard_fab2(sch_1):page43_i259:vss(2)" )
			)
			( pin "J4G1.276"
				( objectStatus "@baseboard_fab2_lib.baseboard_fab2(sch_1):page43_i259:vss(3)" )
			)
			( pin "J4G1.274"
				( objectStatus "@baseboard_fab2_lib.baseboard_fab2(sch_1):page43_i259:vss(4)" )
			)
			( pin "J4G1.272"
				( objectStatus "@baseboard_fab2_lib.baseboard_fab2(sch_1):page43_i259:vss(5)" )
			)
			( pin "J4G1.270"
				( objectStatus "@baseboard_fab2_lib.baseboard_fab2(sch_1):page43_i259:vss(6)" )
			)
			( pin "J4G1.268"
				( objectStatus "@baseboard_fab2_lib.baseboard_fab2(sch_1):page43_i259:vss(7)" )
			)
			( pin "J4G1.265"
				( objectStatus "@baseboard_fab2_lib.baseboard_fab2(sch_1):page43_i259:vss(8)" )
			)
			( pin "J4G1.263"
				( objectStatus "@baseboard_fab2_lib.baseboard_fab2(sch_1):page43_i259:vss(9)" )
			)
			( pin "J4G1.261"
				( objectStatus "@baseboard_fab2_lib.baseboard_fab2(sch_1):page43_i259:vss(10)" )
			)
			( pin "J4G1.259"
				( objectStatus "@baseboard_fab2_lib.baseboard_fab2(sch_1):page43_i259:vss(11)" )
			)
			( pin "J4G1.257"
				( objectStatus "@baseboard_fab2_lib.baseboard_fab2(sch_1):page43_i259:vss(12)" )
			)
			( pin "J4G1.254"
				( objectStatus "@baseboard_fab2_lib.baseboard_fab2(sch_1):page43_i259:vss(13)" )
			)
			( pin "J4G1.252"
				( objectStatus "@baseboard_fab2_lib.baseboard_fab2(sch_1):page43_i259:vss(14)" )
			)
			( pin "J4G1.250"
				( objectStatus "@baseboard_fab2_lib.baseboard_fab2(sch_1):page43_i259:vss(15)" )
			)
			( pin "J4G1.248"
				( objectStatus "@baseboard_fab2_lib.baseboard_fab2(sch_1):page43_i259:vss(16)" )
			)
			( pin "J4G1.246"
				( objectStatus "@baseboard_fab2_lib.baseboard_fab2(sch_1):page43_i259:vss(17)" )
			)
			( pin "J4G1.243"
				( objectStatus "@baseboard_fab2_lib.baseboard_fab2(sch_1):page43_i259:vss(18)" )
			)
			( pin "J4G1.241"
				( objectStatus "@baseboard_fab2_lib.baseboard_fab2(sch_1):page43_i259:vss(19)" )
			)
			( pin "J4G1.239"
				( objectStatus "@baseboard_fab2_lib.baseboard_fab2(sch_1):page43_i259:vss(20)" )
			)
			( pin "J4G1.202"
				( objectStatus "@baseboard_fab2_lib.baseboard_fab2(sch_1):page43_i259:vss(21)" )
			)
			( pin "J4G1.200"
				( objectStatus "@baseboard_fab2_lib.baseboard_fab2(sch_1):page43_i259:vss(22)" )
			)
			( pin "J4G1.198"
				( objectStatus "@baseboard_fab2_lib.baseboard_fab2(sch_1):page43_i259:vss(23)" )
			)
			( pin "J4G1.195"
				( objectStatus "@baseboard_fab2_lib.baseboard_fab2(sch_1):page43_i259:vss(24)" )
			)
			( pin "J4G1.193"
				( objectStatus "@baseboard_fab2_lib.baseboard_fab2(sch_1):page43_i259:vss(25)" )
			)
			( pin "J4G1.191"
				( objectStatus "@baseboard_fab2_lib.baseboard_fab2(sch_1):page43_i259:vss(26)" )
			)
			( pin "J4G1.189"
				( objectStatus "@baseboard_fab2_lib.baseboard_fab2(sch_1):page43_i259:vss(27)" )
			)
			( pin "J4G1.187"
				( objectStatus "@baseboard_fab2_lib.baseboard_fab2(sch_1):page43_i259:vss(28)" )
			)
			( pin "J4G1.184"
				( objectStatus "@baseboard_fab2_lib.baseboard_fab2(sch_1):page43_i259:vss(29)" )
			)
			( pin "J4G1.182"
				( objectStatus "@baseboard_fab2_lib.baseboard_fab2(sch_1):page43_i259:vss(30)" )
			)
			( pin "J4G1.180"
				( objectStatus "@baseboard_fab2_lib.baseboard_fab2(sch_1):page43_i259:vss(31)" )
			)
			( pin "J4G1.178"
				( objectStatus "@baseboard_fab2_lib.baseboard_fab2(sch_1):page43_i259:vss(32)" )
			)
			( pin "J4G1.176"
				( objectStatus "@baseboard_fab2_lib.baseboard_fab2(sch_1):page43_i259:vss(33)" )
			)
			( pin "J4G1.173"
				( objectStatus "@baseboard_fab2_lib.baseboard_fab2(sch_1):page43_i259:vss(34)" )
			)
			( pin "J4G1.171"
				( objectStatus "@baseboard_fab2_lib.baseboard_fab2(sch_1):page43_i259:vss(35)" )
			)
			( pin "J4G1.169"
				( objectStatus "@baseboard_fab2_lib.baseboard_fab2(sch_1):page43_i259:vss(36)" )
			)
			( pin "J4G1.167"
				( objectStatus "@baseboard_fab2_lib.baseboard_fab2(sch_1):page43_i259:vss(37)" )
			)
			( pin "J4G1.165"
				( objectStatus "@baseboard_fab2_lib.baseboard_fab2(sch_1):page43_i259:vss(38)" )
			)
			( pin "J4G1.162"
				( objectStatus "@baseboard_fab2_lib.baseboard_fab2(sch_1):page43_i259:vss(39)" )
			)
			( pin "J4G1.160"
				( objectStatus "@baseboard_fab2_lib.baseboard_fab2(sch_1):page43_i259:vss(40)" )
			)
			( pin "J4G1.158"
				( objectStatus "@baseboard_fab2_lib.baseboard_fab2(sch_1):page43_i259:vss(41)" )
			)
			( pin "J4G1.156"
				( objectStatus "@baseboard_fab2_lib.baseboard_fab2(sch_1):page43_i259:vss(42)" )
			)
			( pin "J4G1.154"
				( objectStatus "@baseboard_fab2_lib.baseboard_fab2(sch_1):page43_i259:vss(43)" )
			)
			( pin "J4G1.151"
				( objectStatus "@baseboard_fab2_lib.baseboard_fab2(sch_1):page43_i259:vss(44)" )
			)
			( pin "J4G1.149"
				( objectStatus "@baseboard_fab2_lib.baseboard_fab2(sch_1):page43_i259:vss(45)" )
			)
			( pin "J4G1.147"
				( objectStatus "@baseboard_fab2_lib.baseboard_fab2(sch_1):page43_i259:vss(46)" )
			)
			( pin "J4G1.138"
				( objectStatus "@baseboard_fab2_lib.baseboard_fab2(sch_1):page43_i259:vss(47)" )
			)
			( pin "J4G1.136"
				( objectStatus "@baseboard_fab2_lib.baseboard_fab2(sch_1):page43_i259:vss(48)" )
			)
			( pin "J4G1.134"
				( objectStatus "@baseboard_fab2_lib.baseboard_fab2(sch_1):page43_i259:vss(49)" )
			)
			( pin "J4G1.131"
				( objectStatus "@baseboard_fab2_lib.baseboard_fab2(sch_1):page43_i259:vss(50)" )
			)
			( pin "J4G1.129"
				( objectStatus "@baseboard_fab2_lib.baseboard_fab2(sch_1):page43_i259:vss(51)" )
			)
			( pin "J4G1.127"
				( objectStatus "@baseboard_fab2_lib.baseboard_fab2(sch_1):page43_i259:vss(52)" )
			)
			( pin "J4G1.125"
				( objectStatus "@baseboard_fab2_lib.baseboard_fab2(sch_1):page43_i259:vss(53)" )
			)
			( pin "J4G1.123"
				( objectStatus "@baseboard_fab2_lib.baseboard_fab2(sch_1):page43_i259:vss(54)" )
			)
			( pin "J4G1.120"
				( objectStatus "@baseboard_fab2_lib.baseboard_fab2(sch_1):page43_i259:vss(55)" )
			)
			( pin "J4G1.118"
				( objectStatus "@baseboard_fab2_lib.baseboard_fab2(sch_1):page43_i259:vss(56)" )
			)
			( pin "J4G1.116"
				( objectStatus "@baseboard_fab2_lib.baseboard_fab2(sch_1):page43_i259:vss(57)" )
			)
			( pin "J4G1.114"
				( objectStatus "@baseboard_fab2_lib.baseboard_fab2(sch_1):page43_i259:vss(58)" )
			)
			( pin "J4G1.112"
				( objectStatus "@baseboard_fab2_lib.baseboard_fab2(sch_1):page43_i259:vss(59)" )
			)
			( pin "J4G1.109"
				( objectStatus "@baseboard_fab2_lib.baseboard_fab2(sch_1):page43_i259:vss(60)" )
			)
			( pin "J4G1.107"
				( objectStatus "@baseboard_fab2_lib.baseboard_fab2(sch_1):page43_i259:vss(61)" )
			)
			( pin "J4G1.105"
				( objectStatus "@baseboard_fab2_lib.baseboard_fab2(sch_1):page43_i259:vss(62)" )
			)
			( pin "J4G1.103"
				( objectStatus "@baseboard_fab2_lib.baseboard_fab2(sch_1):page43_i259:vss(63)" )
			)
			( pin "J4G1.101"
				( objectStatus "@baseboard_fab2_lib.baseboard_fab2(sch_1):page43_i259:vss(64)" )
			)
			( pin "J4G1.98"
				( objectStatus "@baseboard_fab2_lib.baseboard_fab2(sch_1):page43_i259:vss(65)" )
			)
			( pin "J4G1.96"
				( objectStatus "@baseboard_fab2_lib.baseboard_fab2(sch_1):page43_i259:vss(66)" )
			)
			( pin "J4G1.94"
				( objectStatus "@baseboard_fab2_lib.baseboard_fab2(sch_1):page43_i259:vss(67)" )
			)
			( pin "J4G1.57"
				( objectStatus "@baseboard_fab2_lib.baseboard_fab2(sch_1):page43_i259:vss(68)" )
			)
			( pin "J4G1.55"
				( objectStatus "@baseboard_fab2_lib.baseboard_fab2(sch_1):page43_i259:vss(69)" )
			)
			( pin "J4G1.53"
				( objectStatus "@baseboard_fab2_lib.baseboard_fab2(sch_1):page43_i259:vss(70)" )
			)
			( pin "J4G1.50"
				( objectStatus "@baseboard_fab2_lib.baseboard_fab2(sch_1):page43_i259:vss(71)" )
			)
			( pin "J4G1.48"
				( objectStatus "@baseboard_fab2_lib.baseboard_fab2(sch_1):page43_i259:vss(72)" )
			)
			( pin "J4G1.46"
				( objectStatus "@baseboard_fab2_lib.baseboard_fab2(sch_1):page43_i259:vss(73)" )
			)
			( pin "J4G1.44"
				( objectStatus "@baseboard_fab2_lib.baseboard_fab2(sch_1):page43_i259:vss(74)" )
			)
			( pin "J4G1.42"
				( objectStatus "@baseboard_fab2_lib.baseboard_fab2(sch_1):page43_i259:vss(75)" )
			)
			( pin "J4G1.39"
				( objectStatus "@baseboard_fab2_lib.baseboard_fab2(sch_1):page43_i259:vss(76)" )
			)
			( pin "J4G1.37"
				( objectStatus "@baseboard_fab2_lib.baseboard_fab2(sch_1):page43_i259:vss(77)" )
			)
			( pin "J4G1.35"
				( objectStatus "@baseboard_fab2_lib.baseboard_fab2(sch_1):page43_i259:vss(78)" )
			)
			( pin "J4G1.33"
				( objectStatus "@baseboard_fab2_lib.baseboard_fab2(sch_1):page43_i259:vss(79)" )
			)
			( pin "J4G1.31"
				( objectStatus "@baseboard_fab2_lib.baseboard_fab2(sch_1):page43_i259:vss(80)" )
			)
			( pin "J4G1.28"
				( objectStatus "@baseboard_fab2_lib.baseboard_fab2(sch_1):page43_i259:vss(81)" )
			)
			( pin "J4G1.26"
				( objectStatus "@baseboard_fab2_lib.baseboard_fab2(sch_1):page43_i259:vss(82)" )
			)
			( pin "J4G1.24"
				( objectStatus "@baseboard_fab2_lib.baseboard_fab2(sch_1):page43_i259:vss(83)" )
			)
			( pin "J4G1.22"
				( objectStatus "@baseboard_fab2_lib.baseboard_fab2(sch_1):page43_i259:vss(84)" )
			)
			( pin "J4G1.20"
				( objectStatus "@baseboard_fab2_lib.baseboard_fab2(sch_1):page43_i259:vss(85)" )
			)
			( pin "J4G1.17"
				( objectStatus "@baseboard_fab2_lib.baseboard_fab2(sch_1):page43_i259:vss(86)" )
			)
			( pin "J4G1.15"
				( objectStatus "@baseboard_fab2_lib.baseboard_fab2(sch_1):page43_i259:vss(87)" )
			)
			( pin "J4G1.13"
				( objectStatus "@baseboard_fab2_lib.baseboard_fab2(sch_1):page43_i259:vss(88)" )
			)
			( pin "J4G1.11"
				( objectStatus "@baseboard_fab2_lib.baseboard_fab2(sch_1):page43_i259:vss(89)" )
			)
			( pin "J4G1.9"
				( objectStatus "@baseboard_fab2_lib.baseboard_fab2(sch_1):page43_i259:vss(90)" )
			)
			( pin "J4G1.6"
				( objectStatus "@baseboard_fab2_lib.baseboard_fab2(sch_1):page43_i259:vss(91)" )
			)
			( pin "J4G1.4"
				( objectStatus "@baseboard_fab2_lib.baseboard_fab2(sch_1):page43_i259:vss(92)" )
			)
			( pin "J4G1.2"
				( objectStatus "@baseboard_fab2_lib.baseboard_fab2(sch_1):page43_i259:vss(93)" )
			)
			( pin "J4G1.145"
				( objectStatus "@baseboard_fab2_lib.baseboard_fab2(sch_1):page43_i260:\12v\(0)" )
			)
			( pin "J4G1.1"
				( objectStatus "@baseboard_fab2_lib.baseboard_fab2(sch_1):page43_i260:\12v\(1)" )
			)
			( pin "J4G1.236"
				( objectStatus "@baseboard_fab2_lib.baseboard_fab2(sch_1):page43_i260:vdd(0)" )
			)
			( pin "J4G1.233"
				( objectStatus "@baseboard_fab2_lib.baseboard_fab2(sch_1):page43_i260:vdd(1)" )
			)
			( pin "J4G1.231"
				( objectStatus "@baseboard_fab2_lib.baseboard_fab2(sch_1):page43_i260:vdd(2)" )
			)
			( pin "J4G1.229"
				( objectStatus "@baseboard_fab2_lib.baseboard_fab2(sch_1):page43_i260:vdd(3)" )
			)
			( pin "J4G1.226"
				( objectStatus "@baseboard_fab2_lib.baseboard_fab2(sch_1):page43_i260:vdd(4)" )
			)
			( pin "J4G1.223"
				( objectStatus "@baseboard_fab2_lib.baseboard_fab2(sch_1):page43_i260:vdd(5)" )
			)
			( pin "J4G1.220"
				( objectStatus "@baseboard_fab2_lib.baseboard_fab2(sch_1):page43_i260:vdd(6)" )
			)
			( pin "J4G1.217"
				( objectStatus "@baseboard_fab2_lib.baseboard_fab2(sch_1):page43_i260:vdd(7)" )
			)
			( pin "J4G1.215"
				( objectStatus "@baseboard_fab2_lib.baseboard_fab2(sch_1):page43_i260:vdd(8)" )
			)
			( pin "J4G1.212"
				( objectStatus "@baseboard_fab2_lib.baseboard_fab2(sch_1):page43_i260:vdd(9)" )
			)
			( pin "J4G1.209"
				( objectStatus "@baseboard_fab2_lib.baseboard_fab2(sch_1):page43_i260:vdd(10)" )
			)
			( pin "J4G1.206"
				( objectStatus "@baseboard_fab2_lib.baseboard_fab2(sch_1):page43_i260:vdd(11)" )
			)
			( pin "J4G1.204"
				( objectStatus "@baseboard_fab2_lib.baseboard_fab2(sch_1):page43_i260:vdd(12)" )
			)
			( pin "J4G1.92"
				( objectStatus "@baseboard_fab2_lib.baseboard_fab2(sch_1):page43_i260:vdd(13)" )
			)
			( pin "J4G1.90"
				( objectStatus "@baseboard_fab2_lib.baseboard_fab2(sch_1):page43_i260:vdd(14)" )
			)
			( pin "J4G1.88"
				( objectStatus "@baseboard_fab2_lib.baseboard_fab2(sch_1):page43_i260:vdd(15)" )
			)
			( pin "J4G1.85"
				( objectStatus "@baseboard_fab2_lib.baseboard_fab2(sch_1):page43_i260:vdd(16)" )
			)
			( pin "J4G1.83"
				( objectStatus "@baseboard_fab2_lib.baseboard_fab2(sch_1):page43_i260:vdd(17)" )
			)
			( pin "J4G1.80"
				( objectStatus "@baseboard_fab2_lib.baseboard_fab2(sch_1):page43_i260:vdd(18)" )
			)
			( pin "J4G1.76"
				( objectStatus "@baseboard_fab2_lib.baseboard_fab2(sch_1):page43_i260:vdd(19)" )
			)
			( pin "J4G1.73"
				( objectStatus "@baseboard_fab2_lib.baseboard_fab2(sch_1):page43_i260:vdd(20)" )
			)
			( pin "J4G1.70"
				( objectStatus "@baseboard_fab2_lib.baseboard_fab2(sch_1):page43_i260:vdd(21)" )
			)
			( pin "J4G1.67"
				( objectStatus "@baseboard_fab2_lib.baseboard_fab2(sch_1):page43_i260:vdd(22)" )
			)
			( pin "J4G1.64"
				( objectStatus "@baseboard_fab2_lib.baseboard_fab2(sch_1):page43_i260:vdd(23)" )
			)
			( pin "J4G1.61"
				( objectStatus "@baseboard_fab2_lib.baseboard_fab2(sch_1):page43_i260:vdd(24)" )
			)
			( pin "J4G1.59"
				( objectStatus "@baseboard_fab2_lib.baseboard_fab2(sch_1):page43_i260:vdd(25)" )
			)
			( pin "J4G1.287"
				( objectStatus "@baseboard_fab2_lib.baseboard_fab2(sch_1):page43_i260:vpp(0)" )
			)
			( pin "J4G1.286"
				( objectStatus "@baseboard_fab2_lib.baseboard_fab2(sch_1):page43_i260:vpp(1)" )
			)
			( pin "J4G1.288"
				( objectStatus "@baseboard_fab2_lib.baseboard_fab2(sch_1):page43_i260:vpp(2)" )
			)
			( pin "J4G1.143"
				( objectStatus "@baseboard_fab2_lib.baseboard_fab2(sch_1):page43_i260:vpp(3)" )
			)
			( pin "J4G1.142"
				( objectStatus "@baseboard_fab2_lib.baseboard_fab2(sch_1):page43_i260:vpp(4)" )
			)
			( pin "J4G1.221"
				( objectStatus "@baseboard_fab2_lib.baseboard_fab2(sch_1):page43_i260:vtt(0)" )
			)
			( pin "J4G1.77"
				( objectStatus "@baseboard_fab2_lib.baseboard_fab2(sch_1):page43_i260:vtt(1)" )
			)
			( pin "C4F10.1"
				( objectStatus "@baseboard_fab2_lib.baseboard_fab2(sch_1):page43_i272:a" )
			)
			( pin "C4F10.2"
				( objectStatus "@baseboard_fab2_lib.baseboard_fab2(sch_1):page43_i272:b" )
			)
			( pin "C6T1.1"
				( objectStatus "@baseboard_fab2_lib.baseboard_fab2(sch_1):page44_i2:a" )
			)
			( pin "C6T1.2"
				( objectStatus "@baseboard_fab2_lib.baseboard_fab2(sch_1):page44_i2:b" )
			)
			( pin "J6T1.79"
				( objectStatus "@baseboard_fab2_lib.baseboard_fab2(sch_1):page44_i13:a0" )
			)
			( pin "J6T1.72"
				( objectStatus "@baseboard_fab2_lib.baseboard_fab2(sch_1):page44_i13:a1" )
			)
			( pin "J6T1.216"
				( objectStatus "@baseboard_fab2_lib.baseboard_fab2(sch_1):page44_i13:a2" )
			)
			( pin "J6T1.71"
				( objectStatus "@baseboard_fab2_lib.baseboard_fab2(sch_1):page44_i13:a3" )
			)
			( pin "J6T1.214"
				( objectStatus "@baseboard_fab2_lib.baseboard_fab2(sch_1):page44_i13:a4" )
			)
			( pin "J6T1.213"
				( objectStatus "@baseboard_fab2_lib.baseboard_fab2(sch_1):page44_i13:a5" )
			)
			( pin "J6T1.69"
				( objectStatus "@baseboard_fab2_lib.baseboard_fab2(sch_1):page44_i13:a6" )
			)
			( pin "J6T1.211"
				( objectStatus "@baseboard_fab2_lib.baseboard_fab2(sch_1):page44_i13:a7" )
			)
			( pin "J6T1.68"
				( objectStatus "@baseboard_fab2_lib.baseboard_fab2(sch_1):page44_i13:a8" )
			)
			( pin "J6T1.66"
				( objectStatus "@baseboard_fab2_lib.baseboard_fab2(sch_1):page44_i13:a9" )
			)
			( pin "J6T1.225"
				( objectStatus "@baseboard_fab2_lib.baseboard_fab2(sch_1):page44_i13:a10" )
			)
			( pin "J6T1.210"
				( objectStatus "@baseboard_fab2_lib.baseboard_fab2(sch_1):page44_i13:a11" )
			)
			( pin "J6T1.65"
				( objectStatus "@baseboard_fab2_lib.baseboard_fab2(sch_1):page44_i13:a12" )
			)
			( pin "J6T1.232"
				( objectStatus "@baseboard_fab2_lib.baseboard_fab2(sch_1):page44_i13:a13" )
			)
			( pin "J6T1.228"
				( objectStatus "@baseboard_fab2_lib.baseboard_fab2(sch_1):page44_i13:a14_we_n" )
			)
			( pin "J6T1.86"
				( objectStatus "@baseboard_fab2_lib.baseboard_fab2(sch_1):page44_i13:a15_cas_n" )
			)
			( pin "J6T1.82"
				( objectStatus "@baseboard_fab2_lib.baseboard_fab2(sch_1):page44_i13:a16_ras_n" )
			)
			( pin "J6T1.234"
				( objectStatus "@baseboard_fab2_lib.baseboard_fab2(sch_1):page44_i13:a17" )
			)
			( pin "J6T1.62"
				( objectStatus "@baseboard_fab2_lib.baseboard_fab2(sch_1):page44_i13:act_n" )
			)
			( pin "J6T1.208"
				( objectStatus "@baseboard_fab2_lib.baseboard_fab2(sch_1):page44_i13:alert_n" )
			)
			( pin "J6T1.81"
				( objectStatus "@baseboard_fab2_lib.baseboard_fab2(sch_1):page44_i13:ba(0)" )
			)
			( pin "J6T1.224"
				( objectStatus "@baseboard_fab2_lib.baseboard_fab2(sch_1):page44_i13:ba(1)" )
			)
			( pin "J6T1.63"
				( objectStatus "@baseboard_fab2_lib.baseboard_fab2(sch_1):page44_i13:bg(0)" )
			)
			( pin "J6T1.207"
				( objectStatus "@baseboard_fab2_lib.baseboard_fab2(sch_1):page44_i13:bg(1)" )
			)
			( pin "J6T1.235"
				( objectStatus "@baseboard_fab2_lib.baseboard_fab2(sch_1):page44_i13:c(2)" )
			)
			( pin "J6T1.49"
				( objectStatus "@baseboard_fab2_lib.baseboard_fab2(sch_1):page44_i13:cb(0)" )
			)
			( pin "J6T1.194"
				( objectStatus "@baseboard_fab2_lib.baseboard_fab2(sch_1):page44_i13:cb(1)" )
			)
			( pin "J6T1.56"
				( objectStatus "@baseboard_fab2_lib.baseboard_fab2(sch_1):page44_i13:cb(2)" )
			)
			( pin "J6T1.201"
				( objectStatus "@baseboard_fab2_lib.baseboard_fab2(sch_1):page44_i13:cb(3)" )
			)
			( pin "J6T1.47"
				( objectStatus "@baseboard_fab2_lib.baseboard_fab2(sch_1):page44_i13:cb(4)" )
			)
			( pin "J6T1.192"
				( objectStatus "@baseboard_fab2_lib.baseboard_fab2(sch_1):page44_i13:cb(5)" )
			)
			( pin "J6T1.54"
				( objectStatus "@baseboard_fab2_lib.baseboard_fab2(sch_1):page44_i13:cb(6)" )
			)
			( pin "J6T1.199"
				( objectStatus "@baseboard_fab2_lib.baseboard_fab2(sch_1):page44_i13:cb(7)" )
			)
			( pin "J6T1.75"
				( objectStatus "@baseboard_fab2_lib.baseboard_fab2(sch_1):page44_i13:ck0n" )
			)
			( pin "J6T1.74"
				( objectStatus "@baseboard_fab2_lib.baseboard_fab2(sch_1):page44_i13:ck0p" )
			)
			( pin "J6T1.219"
				( objectStatus "@baseboard_fab2_lib.baseboard_fab2(sch_1):page44_i13:ck1n" )
			)
			( pin "J6T1.218"
				( objectStatus "@baseboard_fab2_lib.baseboard_fab2(sch_1):page44_i13:ck1p" )
			)
			( pin "J6T1.60"
				( objectStatus "@baseboard_fab2_lib.baseboard_fab2(sch_1):page44_i13:cke(0)" )
			)
			( pin "J6T1.203"
				( objectStatus "@baseboard_fab2_lib.baseboard_fab2(sch_1):page44_i13:cke(1)" )
			)
			( pin "J6T1.5"
				( objectStatus "@baseboard_fab2_lib.baseboard_fab2(sch_1):page44_i13:dq(0)" )
			)
			( pin "J6T1.150"
				( objectStatus "@baseboard_fab2_lib.baseboard_fab2(sch_1):page44_i13:dq(1)" )
			)
			( pin "J6T1.12"
				( objectStatus "@baseboard_fab2_lib.baseboard_fab2(sch_1):page44_i13:dq(2)" )
			)
			( pin "J6T1.157"
				( objectStatus "@baseboard_fab2_lib.baseboard_fab2(sch_1):page44_i13:dq(3)" )
			)
			( pin "J6T1.3"
				( objectStatus "@baseboard_fab2_lib.baseboard_fab2(sch_1):page44_i13:dq(4)" )
			)
			( pin "J6T1.148"
				( objectStatus "@baseboard_fab2_lib.baseboard_fab2(sch_1):page44_i13:dq(5)" )
			)
			( pin "J6T1.10"
				( objectStatus "@baseboard_fab2_lib.baseboard_fab2(sch_1):page44_i13:dq(6)" )
			)
			( pin "J6T1.155"
				( objectStatus "@baseboard_fab2_lib.baseboard_fab2(sch_1):page44_i13:dq(7)" )
			)
			( pin "J6T1.16"
				( objectStatus "@baseboard_fab2_lib.baseboard_fab2(sch_1):page44_i13:dq(8)" )
			)
			( pin "J6T1.161"
				( objectStatus "@baseboard_fab2_lib.baseboard_fab2(sch_1):page44_i13:dq(9)" )
			)
			( pin "J6T1.23"
				( objectStatus "@baseboard_fab2_lib.baseboard_fab2(sch_1):page44_i13:dq(10)" )
			)
			( pin "J6T1.168"
				( objectStatus "@baseboard_fab2_lib.baseboard_fab2(sch_1):page44_i13:dq(11)" )
			)
			( pin "J6T1.14"
				( objectStatus "@baseboard_fab2_lib.baseboard_fab2(sch_1):page44_i13:dq(12)" )
			)
			( pin "J6T1.159"
				( objectStatus "@baseboard_fab2_lib.baseboard_fab2(sch_1):page44_i13:dq(13)" )
			)
			( pin "J6T1.21"
				( objectStatus "@baseboard_fab2_lib.baseboard_fab2(sch_1):page44_i13:dq(14)" )
			)
			( pin "J6T1.166"
				( objectStatus "@baseboard_fab2_lib.baseboard_fab2(sch_1):page44_i13:dq(15)" )
			)
			( pin "J6T1.27"
				( objectStatus "@baseboard_fab2_lib.baseboard_fab2(sch_1):page44_i13:dq(16)" )
			)
			( pin "J6T1.172"
				( objectStatus "@baseboard_fab2_lib.baseboard_fab2(sch_1):page44_i13:dq(17)" )
			)
			( pin "J6T1.34"
				( objectStatus "@baseboard_fab2_lib.baseboard_fab2(sch_1):page44_i13:dq(18)" )
			)
			( pin "J6T1.179"
				( objectStatus "@baseboard_fab2_lib.baseboard_fab2(sch_1):page44_i13:dq(19)" )
			)
			( pin "J6T1.25"
				( objectStatus "@baseboard_fab2_lib.baseboard_fab2(sch_1):page44_i13:dq(20)" )
			)
			( pin "J6T1.170"
				( objectStatus "@baseboard_fab2_lib.baseboard_fab2(sch_1):page44_i13:dq(21)" )
			)
			( pin "J6T1.32"
				( objectStatus "@baseboard_fab2_lib.baseboard_fab2(sch_1):page44_i13:dq(22)" )
			)
			( pin "J6T1.177"
				( objectStatus "@baseboard_fab2_lib.baseboard_fab2(sch_1):page44_i13:dq(23)" )
			)
			( pin "J6T1.38"
				( objectStatus "@baseboard_fab2_lib.baseboard_fab2(sch_1):page44_i13:dq(24)" )
			)
			( pin "J6T1.183"
				( objectStatus "@baseboard_fab2_lib.baseboard_fab2(sch_1):page44_i13:dq(25)" )
			)
			( pin "J6T1.45"
				( objectStatus "@baseboard_fab2_lib.baseboard_fab2(sch_1):page44_i13:dq(26)" )
			)
			( pin "J6T1.190"
				( objectStatus "@baseboard_fab2_lib.baseboard_fab2(sch_1):page44_i13:dq(27)" )
			)
			( pin "J6T1.36"
				( objectStatus "@baseboard_fab2_lib.baseboard_fab2(sch_1):page44_i13:dq(28)" )
			)
			( pin "J6T1.181"
				( objectStatus "@baseboard_fab2_lib.baseboard_fab2(sch_1):page44_i13:dq(29)" )
			)
			( pin "J6T1.43"
				( objectStatus "@baseboard_fab2_lib.baseboard_fab2(sch_1):page44_i13:dq(30)" )
			)
			( pin "J6T1.188"
				( objectStatus "@baseboard_fab2_lib.baseboard_fab2(sch_1):page44_i13:dq(31)" )
			)
			( pin "J6T1.97"
				( objectStatus "@baseboard_fab2_lib.baseboard_fab2(sch_1):page44_i13:dq(32)" )
			)
			( pin "J6T1.242"
				( objectStatus "@baseboard_fab2_lib.baseboard_fab2(sch_1):page44_i13:dq(33)" )
			)
			( pin "J6T1.104"
				( objectStatus "@baseboard_fab2_lib.baseboard_fab2(sch_1):page44_i13:dq(34)" )
			)
			( pin "J6T1.249"
				( objectStatus "@baseboard_fab2_lib.baseboard_fab2(sch_1):page44_i13:dq(35)" )
			)
			( pin "J6T1.95"
				( objectStatus "@baseboard_fab2_lib.baseboard_fab2(sch_1):page44_i13:dq(36)" )
			)
			( pin "J6T1.240"
				( objectStatus "@baseboard_fab2_lib.baseboard_fab2(sch_1):page44_i13:dq(37)" )
			)
			( pin "J6T1.102"
				( objectStatus "@baseboard_fab2_lib.baseboard_fab2(sch_1):page44_i13:dq(38)" )
			)
			( pin "J6T1.247"
				( objectStatus "@baseboard_fab2_lib.baseboard_fab2(sch_1):page44_i13:dq(39)" )
			)
			( pin "J6T1.108"
				( objectStatus "@baseboard_fab2_lib.baseboard_fab2(sch_1):page44_i13:dq(40)" )
			)
			( pin "J6T1.253"
				( objectStatus "@baseboard_fab2_lib.baseboard_fab2(sch_1):page44_i13:dq(41)" )
			)
			( pin "J6T1.115"
				( objectStatus "@baseboard_fab2_lib.baseboard_fab2(sch_1):page44_i13:dq(42)" )
			)
			( pin "J6T1.260"
				( objectStatus "@baseboard_fab2_lib.baseboard_fab2(sch_1):page44_i13:dq(43)" )
			)
			( pin "J6T1.106"
				( objectStatus "@baseboard_fab2_lib.baseboard_fab2(sch_1):page44_i13:dq(44)" )
			)
			( pin "J6T1.251"
				( objectStatus "@baseboard_fab2_lib.baseboard_fab2(sch_1):page44_i13:dq(45)" )
			)
			( pin "J6T1.113"
				( objectStatus "@baseboard_fab2_lib.baseboard_fab2(sch_1):page44_i13:dq(46)" )
			)
			( pin "J6T1.258"
				( objectStatus "@baseboard_fab2_lib.baseboard_fab2(sch_1):page44_i13:dq(47)" )
			)
			( pin "J6T1.119"
				( objectStatus "@baseboard_fab2_lib.baseboard_fab2(sch_1):page44_i13:dq(48)" )
			)
			( pin "J6T1.264"
				( objectStatus "@baseboard_fab2_lib.baseboard_fab2(sch_1):page44_i13:dq(49)" )
			)
			( pin "J6T1.126"
				( objectStatus "@baseboard_fab2_lib.baseboard_fab2(sch_1):page44_i13:dq(50)" )
			)
			( pin "J6T1.271"
				( objectStatus "@baseboard_fab2_lib.baseboard_fab2(sch_1):page44_i13:dq(51)" )
			)
			( pin "J6T1.117"
				( objectStatus "@baseboard_fab2_lib.baseboard_fab2(sch_1):page44_i13:dq(52)" )
			)
			( pin "J6T1.262"
				( objectStatus "@baseboard_fab2_lib.baseboard_fab2(sch_1):page44_i13:dq(53)" )
			)
			( pin "J6T1.124"
				( objectStatus "@baseboard_fab2_lib.baseboard_fab2(sch_1):page44_i13:dq(54)" )
			)
			( pin "J6T1.269"
				( objectStatus "@baseboard_fab2_lib.baseboard_fab2(sch_1):page44_i13:dq(55)" )
			)
			( pin "J6T1.130"
				( objectStatus "@baseboard_fab2_lib.baseboard_fab2(sch_1):page44_i13:dq(56)" )
			)
			( pin "J6T1.275"
				( objectStatus "@baseboard_fab2_lib.baseboard_fab2(sch_1):page44_i13:dq(57)" )
			)
			( pin "J6T1.137"
				( objectStatus "@baseboard_fab2_lib.baseboard_fab2(sch_1):page44_i13:dq(58)" )
			)
			( pin "J6T1.282"
				( objectStatus "@baseboard_fab2_lib.baseboard_fab2(sch_1):page44_i13:dq(59)" )
			)
			( pin "J6T1.128"
				( objectStatus "@baseboard_fab2_lib.baseboard_fab2(sch_1):page44_i13:dq(60)" )
			)
			( pin "J6T1.273"
				( objectStatus "@baseboard_fab2_lib.baseboard_fab2(sch_1):page44_i13:dq(61)" )
			)
			( pin "J6T1.135"
				( objectStatus "@baseboard_fab2_lib.baseboard_fab2(sch_1):page44_i13:dq(62)" )
			)
			( pin "J6T1.280"
				( objectStatus "@baseboard_fab2_lib.baseboard_fab2(sch_1):page44_i13:dq(63)" )
			)
			( pin "J6T1.78"
				( objectStatus "@baseboard_fab2_lib.baseboard_fab2(sch_1):page44_i13:event_n" )
			)
			( pin "J6T1.87"
				( objectStatus "@baseboard_fab2_lib.baseboard_fab2(sch_1):page44_i13:odt(0)" )
			)
			( pin "J6T1.91"
				( objectStatus "@baseboard_fab2_lib.baseboard_fab2(sch_1):page44_i13:odt(1)" )
			)
			( pin "J6T1.222"
				( objectStatus "@baseboard_fab2_lib.baseboard_fab2(sch_1):page44_i13:par" )
			)
			( pin "J6T1.58"
				( objectStatus "@baseboard_fab2_lib.baseboard_fab2(sch_1):page44_i13:reset_n" )
			)
			( pin "J6T1.205"
				( objectStatus "@baseboard_fab2_lib.baseboard_fab2(sch_1):page44_i13:rfu(0)" )
			)
			( pin "J6T1.227"
				( objectStatus "@baseboard_fab2_lib.baseboard_fab2(sch_1):page44_i13:rfu(1)" )
			)
			( pin "J6T1.144"
				( objectStatus "@baseboard_fab2_lib.baseboard_fab2(sch_1):page44_i13:rfu(2)" )
			)
			( pin "J6T1.84"
				( objectStatus "@baseboard_fab2_lib.baseboard_fab2(sch_1):page44_i13:s0_n" )
			)
			( pin "J6T1.89"
				( objectStatus "@baseboard_fab2_lib.baseboard_fab2(sch_1):page44_i13:s1_n" )
			)
			( pin "J6T1.93"
				( objectStatus "@baseboard_fab2_lib.baseboard_fab2(sch_1):page44_i13:s2_n_c(0)" )
			)
			( pin "J6T1.237"
				( objectStatus "@baseboard_fab2_lib.baseboard_fab2(sch_1):page44_i13:s3_n_c(1)" )
			)
			( pin "J6T1.139"
				( objectStatus "@baseboard_fab2_lib.baseboard_fab2(sch_1):page44_i13:sa(0)" )
			)
			( pin "J6T1.140"
				( objectStatus "@baseboard_fab2_lib.baseboard_fab2(sch_1):page44_i13:sa(1)" )
			)
			( pin "J6T1.238"
				( objectStatus "@baseboard_fab2_lib.baseboard_fab2(sch_1):page44_i13:sa(2)" )
			)
			( pin "J6T1.230"
				( objectStatus "@baseboard_fab2_lib.baseboard_fab2(sch_1):page44_i13:save_n_nc" )
			)
			( pin "J6T1.141"
				( objectStatus "@baseboard_fab2_lib.baseboard_fab2(sch_1):page44_i13:scl" )
			)
			( pin "J6T1.285"
				( objectStatus "@baseboard_fab2_lib.baseboard_fab2(sch_1):page44_i13:sda" )
			)
			( pin "J6T1.284"
				( objectStatus "@baseboard_fab2_lib.baseboard_fab2(sch_1):page44_i13:vddspd" )
			)
			( pin "J6T1.146"
				( objectStatus "@baseboard_fab2_lib.baseboard_fab2(sch_1):page44_i13:vrefca" )
			)
			( pin "J6T1.145"
				( objectStatus "@baseboard_fab2_lib.baseboard_fab2(sch_1):page44_i75:\12v\(0)" )
			)
			( pin "J6T1.1"
				( objectStatus "@baseboard_fab2_lib.baseboard_fab2(sch_1):page44_i75:\12v\(1)" )
			)
			( pin "J6T1.236"
				( objectStatus "@baseboard_fab2_lib.baseboard_fab2(sch_1):page44_i75:vdd(0)" )
			)
			( pin "J6T1.233"
				( objectStatus "@baseboard_fab2_lib.baseboard_fab2(sch_1):page44_i75:vdd(1)" )
			)
			( pin "J6T1.231"
				( objectStatus "@baseboard_fab2_lib.baseboard_fab2(sch_1):page44_i75:vdd(2)" )
			)
			( pin "J6T1.229"
				( objectStatus "@baseboard_fab2_lib.baseboard_fab2(sch_1):page44_i75:vdd(3)" )
			)
			( pin "J6T1.226"
				( objectStatus "@baseboard_fab2_lib.baseboard_fab2(sch_1):page44_i75:vdd(4)" )
			)
			( pin "J6T1.223"
				( objectStatus "@baseboard_fab2_lib.baseboard_fab2(sch_1):page44_i75:vdd(5)" )
			)
			( pin "J6T1.220"
				( objectStatus "@baseboard_fab2_lib.baseboard_fab2(sch_1):page44_i75:vdd(6)" )
			)
			( pin "J6T1.217"
				( objectStatus "@baseboard_fab2_lib.baseboard_fab2(sch_1):page44_i75:vdd(7)" )
			)
			( pin "J6T1.215"
				( objectStatus "@baseboard_fab2_lib.baseboard_fab2(sch_1):page44_i75:vdd(8)" )
			)
			( pin "J6T1.212"
				( objectStatus "@baseboard_fab2_lib.baseboard_fab2(sch_1):page44_i75:vdd(9)" )
			)
			( pin "J6T1.209"
				( objectStatus "@baseboard_fab2_lib.baseboard_fab2(sch_1):page44_i75:vdd(10)" )
			)
			( pin "J6T1.206"
				( objectStatus "@baseboard_fab2_lib.baseboard_fab2(sch_1):page44_i75:vdd(11)" )
			)
			( pin "J6T1.204"
				( objectStatus "@baseboard_fab2_lib.baseboard_fab2(sch_1):page44_i75:vdd(12)" )
			)
			( pin "J6T1.92"
				( objectStatus "@baseboard_fab2_lib.baseboard_fab2(sch_1):page44_i75:vdd(13)" )
			)
			( pin "J6T1.90"
				( objectStatus "@baseboard_fab2_lib.baseboard_fab2(sch_1):page44_i75:vdd(14)" )
			)
			( pin "J6T1.88"
				( objectStatus "@baseboard_fab2_lib.baseboard_fab2(sch_1):page44_i75:vdd(15)" )
			)
			( pin "J6T1.85"
				( objectStatus "@baseboard_fab2_lib.baseboard_fab2(sch_1):page44_i75:vdd(16)" )
			)
			( pin "J6T1.83"
				( objectStatus "@baseboard_fab2_lib.baseboard_fab2(sch_1):page44_i75:vdd(17)" )
			)
			( pin "J6T1.80"
				( objectStatus "@baseboard_fab2_lib.baseboard_fab2(sch_1):page44_i75:vdd(18)" )
			)
			( pin "J6T1.76"
				( objectStatus "@baseboard_fab2_lib.baseboard_fab2(sch_1):page44_i75:vdd(19)" )
			)
			( pin "J6T1.73"
				( objectStatus "@baseboard_fab2_lib.baseboard_fab2(sch_1):page44_i75:vdd(20)" )
			)
			( pin "J6T1.70"
				( objectStatus "@baseboard_fab2_lib.baseboard_fab2(sch_1):page44_i75:vdd(21)" )
			)
			( pin "J6T1.67"
				( objectStatus "@baseboard_fab2_lib.baseboard_fab2(sch_1):page44_i75:vdd(22)" )
			)
			( pin "J6T1.64"
				( objectStatus "@baseboard_fab2_lib.baseboard_fab2(sch_1):page44_i75:vdd(23)" )
			)
			( pin "J6T1.61"
				( objectStatus "@baseboard_fab2_lib.baseboard_fab2(sch_1):page44_i75:vdd(24)" )
			)
			( pin "J6T1.59"
				( objectStatus "@baseboard_fab2_lib.baseboard_fab2(sch_1):page44_i75:vdd(25)" )
			)
			( pin "J6T1.287"
				( objectStatus "@baseboard_fab2_lib.baseboard_fab2(sch_1):page44_i75:vpp(0)" )
			)
			( pin "J6T1.286"
				( objectStatus "@baseboard_fab2_lib.baseboard_fab2(sch_1):page44_i75:vpp(1)" )
			)
			( pin "J6T1.288"
				( objectStatus "@baseboard_fab2_lib.baseboard_fab2(sch_1):page44_i75:vpp(2)" )
			)
			( pin "J6T1.143"
				( objectStatus "@baseboard_fab2_lib.baseboard_fab2(sch_1):page44_i75:vpp(3)" )
			)
			( pin "J6T1.142"
				( objectStatus "@baseboard_fab2_lib.baseboard_fab2(sch_1):page44_i75:vpp(4)" )
			)
			( pin "J6T1.221"
				( objectStatus "@baseboard_fab2_lib.baseboard_fab2(sch_1):page44_i75:vtt(0)" )
			)
			( pin "J6T1.77"
				( objectStatus "@baseboard_fab2_lib.baseboard_fab2(sch_1):page44_i75:vtt(1)" )
			)
			( pin "J6T1.152"
				( objectStatus "@baseboard_fab2_lib.baseboard_fab2(sch_1):page44_i120:dqs0n" )
			)
			( pin "J6T1.153"
				( objectStatus "@baseboard_fab2_lib.baseboard_fab2(sch_1):page44_i120:dqs0p" )
			)
			( pin "J6T1.163"
				( objectStatus "@baseboard_fab2_lib.baseboard_fab2(sch_1):page44_i120:dqs1n" )
			)
			( pin "J6T1.164"
				( objectStatus "@baseboard_fab2_lib.baseboard_fab2(sch_1):page44_i120:dqs1p" )
			)
			( pin "J6T1.174"
				( objectStatus "@baseboard_fab2_lib.baseboard_fab2(sch_1):page44_i120:dqs2n" )
			)
			( pin "J6T1.175"
				( objectStatus "@baseboard_fab2_lib.baseboard_fab2(sch_1):page44_i120:dqs2p" )
			)
			( pin "J6T1.185"
				( objectStatus "@baseboard_fab2_lib.baseboard_fab2(sch_1):page44_i120:dqs3n" )
			)
			( pin "J6T1.186"
				( objectStatus "@baseboard_fab2_lib.baseboard_fab2(sch_1):page44_i120:dqs3p" )
			)
			( pin "J6T1.244"
				( objectStatus "@baseboard_fab2_lib.baseboard_fab2(sch_1):page44_i120:dqs4n" )
			)
			( pin "J6T1.245"
				( objectStatus "@baseboard_fab2_lib.baseboard_fab2(sch_1):page44_i120:dqs4p" )
			)
			( pin "J6T1.255"
				( objectStatus "@baseboard_fab2_lib.baseboard_fab2(sch_1):page44_i120:dqs5n" )
			)
			( pin "J6T1.256"
				( objectStatus "@baseboard_fab2_lib.baseboard_fab2(sch_1):page44_i120:dqs5p" )
			)
			( pin "J6T1.266"
				( objectStatus "@baseboard_fab2_lib.baseboard_fab2(sch_1):page44_i120:dqs6n" )
			)
			( pin "J6T1.267"
				( objectStatus "@baseboard_fab2_lib.baseboard_fab2(sch_1):page44_i120:dqs6p" )
			)
			( pin "J6T1.277"
				( objectStatus "@baseboard_fab2_lib.baseboard_fab2(sch_1):page44_i120:dqs7n" )
			)
			( pin "J6T1.278"
				( objectStatus "@baseboard_fab2_lib.baseboard_fab2(sch_1):page44_i120:dqs7p" )
			)
			( pin "J6T1.196"
				( objectStatus "@baseboard_fab2_lib.baseboard_fab2(sch_1):page44_i120:dqs8n" )
			)
			( pin "J6T1.197"
				( objectStatus "@baseboard_fab2_lib.baseboard_fab2(sch_1):page44_i120:dqs8p" )
			)
			( pin "J6T1.8"
				( objectStatus "@baseboard_fab2_lib.baseboard_fab2(sch_1):page44_i120:dqs9n" )
			)
			( pin "J6T1.7"
				( objectStatus "@baseboard_fab2_lib.baseboard_fab2(sch_1):page44_i120:dqs9p" )
			)
			( pin "J6T1.19"
				( objectStatus "@baseboard_fab2_lib.baseboard_fab2(sch_1):page44_i120:dqs10n" )
			)
			( pin "J6T1.18"
				( objectStatus "@baseboard_fab2_lib.baseboard_fab2(sch_1):page44_i120:dqs10p" )
			)
			( pin "J6T1.30"
				( objectStatus "@baseboard_fab2_lib.baseboard_fab2(sch_1):page44_i120:dqs11n" )
			)
			( pin "J6T1.29"
				( objectStatus "@baseboard_fab2_lib.baseboard_fab2(sch_1):page44_i120:dqs11p" )
			)
			( pin "J6T1.41"
				( objectStatus "@baseboard_fab2_lib.baseboard_fab2(sch_1):page44_i120:dqs12n" )
			)
			( pin "J6T1.40"
				( objectStatus "@baseboard_fab2_lib.baseboard_fab2(sch_1):page44_i120:dqs12p" )
			)
			( pin "J6T1.100"
				( objectStatus "@baseboard_fab2_lib.baseboard_fab2(sch_1):page44_i120:dqs13n" )
			)
			( pin "J6T1.99"
				( objectStatus "@baseboard_fab2_lib.baseboard_fab2(sch_1):page44_i120:dqs13p" )
			)
			( pin "J6T1.111"
				( objectStatus "@baseboard_fab2_lib.baseboard_fab2(sch_1):page44_i120:dqs14n" )
			)
			( pin "J6T1.110"
				( objectStatus "@baseboard_fab2_lib.baseboard_fab2(sch_1):page44_i120:dqs14p" )
			)
			( pin "J6T1.122"
				( objectStatus "@baseboard_fab2_lib.baseboard_fab2(sch_1):page44_i120:dqs15n" )
			)
			( pin "J6T1.121"
				( objectStatus "@baseboard_fab2_lib.baseboard_fab2(sch_1):page44_i120:dqs15p" )
			)
			( pin "J6T1.133"
				( objectStatus "@baseboard_fab2_lib.baseboard_fab2(sch_1):page44_i120:dqs16n" )
			)
			( pin "J6T1.132"
				( objectStatus "@baseboard_fab2_lib.baseboard_fab2(sch_1):page44_i120:dqs16p" )
			)
			( pin "J6T1.52"
				( objectStatus "@baseboard_fab2_lib.baseboard_fab2(sch_1):page44_i120:dqs17n" )
			)
			( pin "J6T1.51"
				( objectStatus "@baseboard_fab2_lib.baseboard_fab2(sch_1):page44_i120:dqs17p" )
			)
			( pin "J6T1.283"
				( objectStatus "@baseboard_fab2_lib.baseboard_fab2(sch_1):page44_i139:vss(0)" )
			)
			( pin "J6T1.281"
				( objectStatus "@baseboard_fab2_lib.baseboard_fab2(sch_1):page44_i139:vss(1)" )
			)
			( pin "J6T1.279"
				( objectStatus "@baseboard_fab2_lib.baseboard_fab2(sch_1):page44_i139:vss(2)" )
			)
			( pin "J6T1.276"
				( objectStatus "@baseboard_fab2_lib.baseboard_fab2(sch_1):page44_i139:vss(3)" )
			)
			( pin "J6T1.274"
				( objectStatus "@baseboard_fab2_lib.baseboard_fab2(sch_1):page44_i139:vss(4)" )
			)
			( pin "J6T1.272"
				( objectStatus "@baseboard_fab2_lib.baseboard_fab2(sch_1):page44_i139:vss(5)" )
			)
			( pin "J6T1.270"
				( objectStatus "@baseboard_fab2_lib.baseboard_fab2(sch_1):page44_i139:vss(6)" )
			)
			( pin "J6T1.268"
				( objectStatus "@baseboard_fab2_lib.baseboard_fab2(sch_1):page44_i139:vss(7)" )
			)
			( pin "J6T1.265"
				( objectStatus "@baseboard_fab2_lib.baseboard_fab2(sch_1):page44_i139:vss(8)" )
			)
			( pin "J6T1.263"
				( objectStatus "@baseboard_fab2_lib.baseboard_fab2(sch_1):page44_i139:vss(9)" )
			)
			( pin "J6T1.261"
				( objectStatus "@baseboard_fab2_lib.baseboard_fab2(sch_1):page44_i139:vss(10)" )
			)
			( pin "J6T1.259"
				( objectStatus "@baseboard_fab2_lib.baseboard_fab2(sch_1):page44_i139:vss(11)" )
			)
			( pin "J6T1.257"
				( objectStatus "@baseboard_fab2_lib.baseboard_fab2(sch_1):page44_i139:vss(12)" )
			)
			( pin "J6T1.254"
				( objectStatus "@baseboard_fab2_lib.baseboard_fab2(sch_1):page44_i139:vss(13)" )
			)
			( pin "J6T1.252"
				( objectStatus "@baseboard_fab2_lib.baseboard_fab2(sch_1):page44_i139:vss(14)" )
			)
			( pin "J6T1.250"
				( objectStatus "@baseboard_fab2_lib.baseboard_fab2(sch_1):page44_i139:vss(15)" )
			)
			( pin "J6T1.248"
				( objectStatus "@baseboard_fab2_lib.baseboard_fab2(sch_1):page44_i139:vss(16)" )
			)
			( pin "J6T1.246"
				( objectStatus "@baseboard_fab2_lib.baseboard_fab2(sch_1):page44_i139:vss(17)" )
			)
			( pin "J6T1.243"
				( objectStatus "@baseboard_fab2_lib.baseboard_fab2(sch_1):page44_i139:vss(18)" )
			)
			( pin "J6T1.241"
				( objectStatus "@baseboard_fab2_lib.baseboard_fab2(sch_1):page44_i139:vss(19)" )
			)
			( pin "J6T1.239"
				( objectStatus "@baseboard_fab2_lib.baseboard_fab2(sch_1):page44_i139:vss(20)" )
			)
			( pin "J6T1.202"
				( objectStatus "@baseboard_fab2_lib.baseboard_fab2(sch_1):page44_i139:vss(21)" )
			)
			( pin "J6T1.200"
				( objectStatus "@baseboard_fab2_lib.baseboard_fab2(sch_1):page44_i139:vss(22)" )
			)
			( pin "J6T1.198"
				( objectStatus "@baseboard_fab2_lib.baseboard_fab2(sch_1):page44_i139:vss(23)" )
			)
			( pin "J6T1.195"
				( objectStatus "@baseboard_fab2_lib.baseboard_fab2(sch_1):page44_i139:vss(24)" )
			)
			( pin "J6T1.193"
				( objectStatus "@baseboard_fab2_lib.baseboard_fab2(sch_1):page44_i139:vss(25)" )
			)
			( pin "J6T1.191"
				( objectStatus "@baseboard_fab2_lib.baseboard_fab2(sch_1):page44_i139:vss(26)" )
			)
			( pin "J6T1.189"
				( objectStatus "@baseboard_fab2_lib.baseboard_fab2(sch_1):page44_i139:vss(27)" )
			)
			( pin "J6T1.187"
				( objectStatus "@baseboard_fab2_lib.baseboard_fab2(sch_1):page44_i139:vss(28)" )
			)
			( pin "J6T1.184"
				( objectStatus "@baseboard_fab2_lib.baseboard_fab2(sch_1):page44_i139:vss(29)" )
			)
			( pin "J6T1.182"
				( objectStatus "@baseboard_fab2_lib.baseboard_fab2(sch_1):page44_i139:vss(30)" )
			)
			( pin "J6T1.180"
				( objectStatus "@baseboard_fab2_lib.baseboard_fab2(sch_1):page44_i139:vss(31)" )
			)
			( pin "J6T1.178"
				( objectStatus "@baseboard_fab2_lib.baseboard_fab2(sch_1):page44_i139:vss(32)" )
			)
			( pin "J6T1.176"
				( objectStatus "@baseboard_fab2_lib.baseboard_fab2(sch_1):page44_i139:vss(33)" )
			)
			( pin "J6T1.173"
				( objectStatus "@baseboard_fab2_lib.baseboard_fab2(sch_1):page44_i139:vss(34)" )
			)
			( pin "J6T1.171"
				( objectStatus "@baseboard_fab2_lib.baseboard_fab2(sch_1):page44_i139:vss(35)" )
			)
			( pin "J6T1.169"
				( objectStatus "@baseboard_fab2_lib.baseboard_fab2(sch_1):page44_i139:vss(36)" )
			)
			( pin "J6T1.167"
				( objectStatus "@baseboard_fab2_lib.baseboard_fab2(sch_1):page44_i139:vss(37)" )
			)
			( pin "J6T1.165"
				( objectStatus "@baseboard_fab2_lib.baseboard_fab2(sch_1):page44_i139:vss(38)" )
			)
			( pin "J6T1.162"
				( objectStatus "@baseboard_fab2_lib.baseboard_fab2(sch_1):page44_i139:vss(39)" )
			)
			( pin "J6T1.160"
				( objectStatus "@baseboard_fab2_lib.baseboard_fab2(sch_1):page44_i139:vss(40)" )
			)
			( pin "J6T1.158"
				( objectStatus "@baseboard_fab2_lib.baseboard_fab2(sch_1):page44_i139:vss(41)" )
			)
			( pin "J6T1.156"
				( objectStatus "@baseboard_fab2_lib.baseboard_fab2(sch_1):page44_i139:vss(42)" )
			)
			( pin "J6T1.154"
				( objectStatus "@baseboard_fab2_lib.baseboard_fab2(sch_1):page44_i139:vss(43)" )
			)
			( pin "J6T1.151"
				( objectStatus "@baseboard_fab2_lib.baseboard_fab2(sch_1):page44_i139:vss(44)" )
			)
			( pin "J6T1.149"
				( objectStatus "@baseboard_fab2_lib.baseboard_fab2(sch_1):page44_i139:vss(45)" )
			)
			( pin "J6T1.147"
				( objectStatus "@baseboard_fab2_lib.baseboard_fab2(sch_1):page44_i139:vss(46)" )
			)
			( pin "J6T1.138"
				( objectStatus "@baseboard_fab2_lib.baseboard_fab2(sch_1):page44_i139:vss(47)" )
			)
			( pin "J6T1.136"
				( objectStatus "@baseboard_fab2_lib.baseboard_fab2(sch_1):page44_i139:vss(48)" )
			)
			( pin "J6T1.134"
				( objectStatus "@baseboard_fab2_lib.baseboard_fab2(sch_1):page44_i139:vss(49)" )
			)
			( pin "J6T1.131"
				( objectStatus "@baseboard_fab2_lib.baseboard_fab2(sch_1):page44_i139:vss(50)" )
			)
			( pin "J6T1.129"
				( objectStatus "@baseboard_fab2_lib.baseboard_fab2(sch_1):page44_i139:vss(51)" )
			)
			( pin "J6T1.127"
				( objectStatus "@baseboard_fab2_lib.baseboard_fab2(sch_1):page44_i139:vss(52)" )
			)
			( pin "J6T1.125"
				( objectStatus "@baseboard_fab2_lib.baseboard_fab2(sch_1):page44_i139:vss(53)" )
			)
			( pin "J6T1.123"
				( objectStatus "@baseboard_fab2_lib.baseboard_fab2(sch_1):page44_i139:vss(54)" )
			)
			( pin "J6T1.120"
				( objectStatus "@baseboard_fab2_lib.baseboard_fab2(sch_1):page44_i139:vss(55)" )
			)
			( pin "J6T1.118"
				( objectStatus "@baseboard_fab2_lib.baseboard_fab2(sch_1):page44_i139:vss(56)" )
			)
			( pin "J6T1.116"
				( objectStatus "@baseboard_fab2_lib.baseboard_fab2(sch_1):page44_i139:vss(57)" )
			)
			( pin "J6T1.114"
				( objectStatus "@baseboard_fab2_lib.baseboard_fab2(sch_1):page44_i139:vss(58)" )
			)
			( pin "J6T1.112"
				( objectStatus "@baseboard_fab2_lib.baseboard_fab2(sch_1):page44_i139:vss(59)" )
			)
			( pin "J6T1.109"
				( objectStatus "@baseboard_fab2_lib.baseboard_fab2(sch_1):page44_i139:vss(60)" )
			)
			( pin "J6T1.107"
				( objectStatus "@baseboard_fab2_lib.baseboard_fab2(sch_1):page44_i139:vss(61)" )
			)
			( pin "J6T1.105"
				( objectStatus "@baseboard_fab2_lib.baseboard_fab2(sch_1):page44_i139:vss(62)" )
			)
			( pin "J6T1.103"
				( objectStatus "@baseboard_fab2_lib.baseboard_fab2(sch_1):page44_i139:vss(63)" )
			)
			( pin "J6T1.101"
				( objectStatus "@baseboard_fab2_lib.baseboard_fab2(sch_1):page44_i139:vss(64)" )
			)
			( pin "J6T1.98"
				( objectStatus "@baseboard_fab2_lib.baseboard_fab2(sch_1):page44_i139:vss(65)" )
			)
			( pin "J6T1.96"
				( objectStatus "@baseboard_fab2_lib.baseboard_fab2(sch_1):page44_i139:vss(66)" )
			)
			( pin "J6T1.94"
				( objectStatus "@baseboard_fab2_lib.baseboard_fab2(sch_1):page44_i139:vss(67)" )
			)
			( pin "J6T1.57"
				( objectStatus "@baseboard_fab2_lib.baseboard_fab2(sch_1):page44_i139:vss(68)" )
			)
			( pin "J6T1.55"
				( objectStatus "@baseboard_fab2_lib.baseboard_fab2(sch_1):page44_i139:vss(69)" )
			)
			( pin "J6T1.53"
				( objectStatus "@baseboard_fab2_lib.baseboard_fab2(sch_1):page44_i139:vss(70)" )
			)
			( pin "J6T1.50"
				( objectStatus "@baseboard_fab2_lib.baseboard_fab2(sch_1):page44_i139:vss(71)" )
			)
			( pin "J6T1.48"
				( objectStatus "@baseboard_fab2_lib.baseboard_fab2(sch_1):page44_i139:vss(72)" )
			)
			( pin "J6T1.46"
				( objectStatus "@baseboard_fab2_lib.baseboard_fab2(sch_1):page44_i139:vss(73)" )
			)
			( pin "J6T1.44"
				( objectStatus "@baseboard_fab2_lib.baseboard_fab2(sch_1):page44_i139:vss(74)" )
			)
			( pin "J6T1.42"
				( objectStatus "@baseboard_fab2_lib.baseboard_fab2(sch_1):page44_i139:vss(75)" )
			)
			( pin "J6T1.39"
				( objectStatus "@baseboard_fab2_lib.baseboard_fab2(sch_1):page44_i139:vss(76)" )
			)
			( pin "J6T1.37"
				( objectStatus "@baseboard_fab2_lib.baseboard_fab2(sch_1):page44_i139:vss(77)" )
			)
			( pin "J6T1.35"
				( objectStatus "@baseboard_fab2_lib.baseboard_fab2(sch_1):page44_i139:vss(78)" )
			)
			( pin "J6T1.33"
				( objectStatus "@baseboard_fab2_lib.baseboard_fab2(sch_1):page44_i139:vss(79)" )
			)
			( pin "J6T1.31"
				( objectStatus "@baseboard_fab2_lib.baseboard_fab2(sch_1):page44_i139:vss(80)" )
			)
			( pin "J6T1.28"
				( objectStatus "@baseboard_fab2_lib.baseboard_fab2(sch_1):page44_i139:vss(81)" )
			)
			( pin "J6T1.26"
				( objectStatus "@baseboard_fab2_lib.baseboard_fab2(sch_1):page44_i139:vss(82)" )
			)
			( pin "J6T1.24"
				( objectStatus "@baseboard_fab2_lib.baseboard_fab2(sch_1):page44_i139:vss(83)" )
			)
			( pin "J6T1.22"
				( objectStatus "@baseboard_fab2_lib.baseboard_fab2(sch_1):page44_i139:vss(84)" )
			)
			( pin "J6T1.20"
				( objectStatus "@baseboard_fab2_lib.baseboard_fab2(sch_1):page44_i139:vss(85)" )
			)
			( pin "J6T1.17"
				( objectStatus "@baseboard_fab2_lib.baseboard_fab2(sch_1):page44_i139:vss(86)" )
			)
			( pin "J6T1.15"
				( objectStatus "@baseboard_fab2_lib.baseboard_fab2(sch_1):page44_i139:vss(87)" )
			)
			( pin "J6T1.13"
				( objectStatus "@baseboard_fab2_lib.baseboard_fab2(sch_1):page44_i139:vss(88)" )
			)
			( pin "J6T1.11"
				( objectStatus "@baseboard_fab2_lib.baseboard_fab2(sch_1):page44_i139:vss(89)" )
			)
			( pin "J6T1.9"
				( objectStatus "@baseboard_fab2_lib.baseboard_fab2(sch_1):page44_i139:vss(90)" )
			)
			( pin "J6T1.6"
				( objectStatus "@baseboard_fab2_lib.baseboard_fab2(sch_1):page44_i139:vss(91)" )
			)
			( pin "J6T1.4"
				( objectStatus "@baseboard_fab2_lib.baseboard_fab2(sch_1):page44_i139:vss(92)" )
			)
			( pin "J6T1.2"
				( objectStatus "@baseboard_fab2_lib.baseboard_fab2(sch_1):page44_i139:vss(93)" )
			)
			( pin "J4G2.283"
				( objectStatus "@baseboard_fab2_lib.baseboard_fab2(sch_1):page45_i43:vss(0)" )
			)
			( pin "J4G2.281"
				( objectStatus "@baseboard_fab2_lib.baseboard_fab2(sch_1):page45_i43:vss(1)" )
			)
			( pin "J4G2.279"
				( objectStatus "@baseboard_fab2_lib.baseboard_fab2(sch_1):page45_i43:vss(2)" )
			)
			( pin "J4G2.276"
				( objectStatus "@baseboard_fab2_lib.baseboard_fab2(sch_1):page45_i43:vss(3)" )
			)
			( pin "J4G2.274"
				( objectStatus "@baseboard_fab2_lib.baseboard_fab2(sch_1):page45_i43:vss(4)" )
			)
			( pin "J4G2.272"
				( objectStatus "@baseboard_fab2_lib.baseboard_fab2(sch_1):page45_i43:vss(5)" )
			)
			( pin "J4G2.270"
				( objectStatus "@baseboard_fab2_lib.baseboard_fab2(sch_1):page45_i43:vss(6)" )
			)
			( pin "J4G2.268"
				( objectStatus "@baseboard_fab2_lib.baseboard_fab2(sch_1):page45_i43:vss(7)" )
			)
			( pin "J4G2.265"
				( objectStatus "@baseboard_fab2_lib.baseboard_fab2(sch_1):page45_i43:vss(8)" )
			)
			( pin "J4G2.263"
				( objectStatus "@baseboard_fab2_lib.baseboard_fab2(sch_1):page45_i43:vss(9)" )
			)
			( pin "J4G2.261"
				( objectStatus "@baseboard_fab2_lib.baseboard_fab2(sch_1):page45_i43:vss(10)" )
			)
			( pin "J4G2.259"
				( objectStatus "@baseboard_fab2_lib.baseboard_fab2(sch_1):page45_i43:vss(11)" )
			)
			( pin "J4G2.257"
				( objectStatus "@baseboard_fab2_lib.baseboard_fab2(sch_1):page45_i43:vss(12)" )
			)
			( pin "J4G2.254"
				( objectStatus "@baseboard_fab2_lib.baseboard_fab2(sch_1):page45_i43:vss(13)" )
			)
			( pin "J4G2.252"
				( objectStatus "@baseboard_fab2_lib.baseboard_fab2(sch_1):page45_i43:vss(14)" )
			)
			( pin "J4G2.250"
				( objectStatus "@baseboard_fab2_lib.baseboard_fab2(sch_1):page45_i43:vss(15)" )
			)
			( pin "J4G2.248"
				( objectStatus "@baseboard_fab2_lib.baseboard_fab2(sch_1):page45_i43:vss(16)" )
			)
			( pin "J4G2.246"
				( objectStatus "@baseboard_fab2_lib.baseboard_fab2(sch_1):page45_i43:vss(17)" )
			)
			( pin "J4G2.243"
				( objectStatus "@baseboard_fab2_lib.baseboard_fab2(sch_1):page45_i43:vss(18)" )
			)
			( pin "J4G2.241"
				( objectStatus "@baseboard_fab2_lib.baseboard_fab2(sch_1):page45_i43:vss(19)" )
			)
			( pin "J4G2.239"
				( objectStatus "@baseboard_fab2_lib.baseboard_fab2(sch_1):page45_i43:vss(20)" )
			)
			( pin "J4G2.202"
				( objectStatus "@baseboard_fab2_lib.baseboard_fab2(sch_1):page45_i43:vss(21)" )
			)
			( pin "J4G2.200"
				( objectStatus "@baseboard_fab2_lib.baseboard_fab2(sch_1):page45_i43:vss(22)" )
			)
			( pin "J4G2.198"
				( objectStatus "@baseboard_fab2_lib.baseboard_fab2(sch_1):page45_i43:vss(23)" )
			)
			( pin "J4G2.195"
				( objectStatus "@baseboard_fab2_lib.baseboard_fab2(sch_1):page45_i43:vss(24)" )
			)
			( pin "J4G2.193"
				( objectStatus "@baseboard_fab2_lib.baseboard_fab2(sch_1):page45_i43:vss(25)" )
			)
			( pin "J4G2.191"
				( objectStatus "@baseboard_fab2_lib.baseboard_fab2(sch_1):page45_i43:vss(26)" )
			)
			( pin "J4G2.189"
				( objectStatus "@baseboard_fab2_lib.baseboard_fab2(sch_1):page45_i43:vss(27)" )
			)
			( pin "J4G2.187"
				( objectStatus "@baseboard_fab2_lib.baseboard_fab2(sch_1):page45_i43:vss(28)" )
			)
			( pin "J4G2.184"
				( objectStatus "@baseboard_fab2_lib.baseboard_fab2(sch_1):page45_i43:vss(29)" )
			)
			( pin "J4G2.182"
				( objectStatus "@baseboard_fab2_lib.baseboard_fab2(sch_1):page45_i43:vss(30)" )
			)
			( pin "J4G2.180"
				( objectStatus "@baseboard_fab2_lib.baseboard_fab2(sch_1):page45_i43:vss(31)" )
			)
			( pin "J4G2.178"
				( objectStatus "@baseboard_fab2_lib.baseboard_fab2(sch_1):page45_i43:vss(32)" )
			)
			( pin "J4G2.176"
				( objectStatus "@baseboard_fab2_lib.baseboard_fab2(sch_1):page45_i43:vss(33)" )
			)
			( pin "J4G2.173"
				( objectStatus "@baseboard_fab2_lib.baseboard_fab2(sch_1):page45_i43:vss(34)" )
			)
			( pin "J4G2.171"
				( objectStatus "@baseboard_fab2_lib.baseboard_fab2(sch_1):page45_i43:vss(35)" )
			)
			( pin "J4G2.169"
				( objectStatus "@baseboard_fab2_lib.baseboard_fab2(sch_1):page45_i43:vss(36)" )
			)
			( pin "J4G2.167"
				( objectStatus "@baseboard_fab2_lib.baseboard_fab2(sch_1):page45_i43:vss(37)" )
			)
			( pin "J4G2.165"
				( objectStatus "@baseboard_fab2_lib.baseboard_fab2(sch_1):page45_i43:vss(38)" )
			)
			( pin "J4G2.162"
				( objectStatus "@baseboard_fab2_lib.baseboard_fab2(sch_1):page45_i43:vss(39)" )
			)
			( pin "J4G2.160"
				( objectStatus "@baseboard_fab2_lib.baseboard_fab2(sch_1):page45_i43:vss(40)" )
			)
			( pin "J4G2.158"
				( objectStatus "@baseboard_fab2_lib.baseboard_fab2(sch_1):page45_i43:vss(41)" )
			)
			( pin "J4G2.156"
				( objectStatus "@baseboard_fab2_lib.baseboard_fab2(sch_1):page45_i43:vss(42)" )
			)
			( pin "J4G2.154"
				( objectStatus "@baseboard_fab2_lib.baseboard_fab2(sch_1):page45_i43:vss(43)" )
			)
			( pin "J4G2.151"
				( objectStatus "@baseboard_fab2_lib.baseboard_fab2(sch_1):page45_i43:vss(44)" )
			)
			( pin "J4G2.149"
				( objectStatus "@baseboard_fab2_lib.baseboard_fab2(sch_1):page45_i43:vss(45)" )
			)
			( pin "J4G2.147"
				( objectStatus "@baseboard_fab2_lib.baseboard_fab2(sch_1):page45_i43:vss(46)" )
			)
			( pin "J4G2.138"
				( objectStatus "@baseboard_fab2_lib.baseboard_fab2(sch_1):page45_i43:vss(47)" )
			)
			( pin "J4G2.136"
				( objectStatus "@baseboard_fab2_lib.baseboard_fab2(sch_1):page45_i43:vss(48)" )
			)
			( pin "J4G2.134"
				( objectStatus "@baseboard_fab2_lib.baseboard_fab2(sch_1):page45_i43:vss(49)" )
			)
			( pin "J4G2.131"
				( objectStatus "@baseboard_fab2_lib.baseboard_fab2(sch_1):page45_i43:vss(50)" )
			)
			( pin "J4G2.129"
				( objectStatus "@baseboard_fab2_lib.baseboard_fab2(sch_1):page45_i43:vss(51)" )
			)
			( pin "J4G2.127"
				( objectStatus "@baseboard_fab2_lib.baseboard_fab2(sch_1):page45_i43:vss(52)" )
			)
			( pin "J4G2.125"
				( objectStatus "@baseboard_fab2_lib.baseboard_fab2(sch_1):page45_i43:vss(53)" )
			)
			( pin "J4G2.123"
				( objectStatus "@baseboard_fab2_lib.baseboard_fab2(sch_1):page45_i43:vss(54)" )
			)
			( pin "J4G2.120"
				( objectStatus "@baseboard_fab2_lib.baseboard_fab2(sch_1):page45_i43:vss(55)" )
			)
			( pin "J4G2.118"
				( objectStatus "@baseboard_fab2_lib.baseboard_fab2(sch_1):page45_i43:vss(56)" )
			)
			( pin "J4G2.116"
				( objectStatus "@baseboard_fab2_lib.baseboard_fab2(sch_1):page45_i43:vss(57)" )
			)
			( pin "J4G2.114"
				( objectStatus "@baseboard_fab2_lib.baseboard_fab2(sch_1):page45_i43:vss(58)" )
			)
			( pin "J4G2.112"
				( objectStatus "@baseboard_fab2_lib.baseboard_fab2(sch_1):page45_i43:vss(59)" )
			)
			( pin "J4G2.109"
				( objectStatus "@baseboard_fab2_lib.baseboard_fab2(sch_1):page45_i43:vss(60)" )
			)
			( pin "J4G2.107"
				( objectStatus "@baseboard_fab2_lib.baseboard_fab2(sch_1):page45_i43:vss(61)" )
			)
			( pin "J4G2.105"
				( objectStatus "@baseboard_fab2_lib.baseboard_fab2(sch_1):page45_i43:vss(62)" )
			)
			( pin "J4G2.103"
				( objectStatus "@baseboard_fab2_lib.baseboard_fab2(sch_1):page45_i43:vss(63)" )
			)
			( pin "J4G2.101"
				( objectStatus "@baseboard_fab2_lib.baseboard_fab2(sch_1):page45_i43:vss(64)" )
			)
			( pin "J4G2.98"
				( objectStatus "@baseboard_fab2_lib.baseboard_fab2(sch_1):page45_i43:vss(65)" )
			)
			( pin "J4G2.96"
				( objectStatus "@baseboard_fab2_lib.baseboard_fab2(sch_1):page45_i43:vss(66)" )
			)
			( pin "J4G2.94"
				( objectStatus "@baseboard_fab2_lib.baseboard_fab2(sch_1):page45_i43:vss(67)" )
			)
			( pin "J4G2.57"
				( objectStatus "@baseboard_fab2_lib.baseboard_fab2(sch_1):page45_i43:vss(68)" )
			)
			( pin "J4G2.55"
				( objectStatus "@baseboard_fab2_lib.baseboard_fab2(sch_1):page45_i43:vss(69)" )
			)
			( pin "J4G2.53"
				( objectStatus "@baseboard_fab2_lib.baseboard_fab2(sch_1):page45_i43:vss(70)" )
			)
			( pin "J4G2.50"
				( objectStatus "@baseboard_fab2_lib.baseboard_fab2(sch_1):page45_i43:vss(71)" )
			)
			( pin "J4G2.48"
				( objectStatus "@baseboard_fab2_lib.baseboard_fab2(sch_1):page45_i43:vss(72)" )
			)
			( pin "J4G2.46"
				( objectStatus "@baseboard_fab2_lib.baseboard_fab2(sch_1):page45_i43:vss(73)" )
			)
			( pin "J4G2.44"
				( objectStatus "@baseboard_fab2_lib.baseboard_fab2(sch_1):page45_i43:vss(74)" )
			)
			( pin "J4G2.42"
				( objectStatus "@baseboard_fab2_lib.baseboard_fab2(sch_1):page45_i43:vss(75)" )
			)
			( pin "J4G2.39"
				( objectStatus "@baseboard_fab2_lib.baseboard_fab2(sch_1):page45_i43:vss(76)" )
			)
			( pin "J4G2.37"
				( objectStatus "@baseboard_fab2_lib.baseboard_fab2(sch_1):page45_i43:vss(77)" )
			)
			( pin "J4G2.35"
				( objectStatus "@baseboard_fab2_lib.baseboard_fab2(sch_1):page45_i43:vss(78)" )
			)
			( pin "J4G2.33"
				( objectStatus "@baseboard_fab2_lib.baseboard_fab2(sch_1):page45_i43:vss(79)" )
			)
			( pin "J4G2.31"
				( objectStatus "@baseboard_fab2_lib.baseboard_fab2(sch_1):page45_i43:vss(80)" )
			)
			( pin "J4G2.28"
				( objectStatus "@baseboard_fab2_lib.baseboard_fab2(sch_1):page45_i43:vss(81)" )
			)
			( pin "J4G2.26"
				( objectStatus "@baseboard_fab2_lib.baseboard_fab2(sch_1):page45_i43:vss(82)" )
			)
			( pin "J4G2.24"
				( objectStatus "@baseboard_fab2_lib.baseboard_fab2(sch_1):page45_i43:vss(83)" )
			)
			( pin "J4G2.22"
				( objectStatus "@baseboard_fab2_lib.baseboard_fab2(sch_1):page45_i43:vss(84)" )
			)
			( pin "J4G2.20"
				( objectStatus "@baseboard_fab2_lib.baseboard_fab2(sch_1):page45_i43:vss(85)" )
			)
			( pin "J4G2.17"
				( objectStatus "@baseboard_fab2_lib.baseboard_fab2(sch_1):page45_i43:vss(86)" )
			)
			( pin "J4G2.15"
				( objectStatus "@baseboard_fab2_lib.baseboard_fab2(sch_1):page45_i43:vss(87)" )
			)
			( pin "J4G2.13"
				( objectStatus "@baseboard_fab2_lib.baseboard_fab2(sch_1):page45_i43:vss(88)" )
			)
			( pin "J4G2.11"
				( objectStatus "@baseboard_fab2_lib.baseboard_fab2(sch_1):page45_i43:vss(89)" )
			)
			( pin "J4G2.9"
				( objectStatus "@baseboard_fab2_lib.baseboard_fab2(sch_1):page45_i43:vss(90)" )
			)
			( pin "J4G2.6"
				( objectStatus "@baseboard_fab2_lib.baseboard_fab2(sch_1):page45_i43:vss(91)" )
			)
			( pin "J4G2.4"
				( objectStatus "@baseboard_fab2_lib.baseboard_fab2(sch_1):page45_i43:vss(92)" )
			)
			( pin "J4G2.2"
				( objectStatus "@baseboard_fab2_lib.baseboard_fab2(sch_1):page45_i43:vss(93)" )
			)
			( pin "J4G2.152"
				( objectStatus "@baseboard_fab2_lib.baseboard_fab2(sch_1):page45_i61:dqs0n" )
			)
			( pin "J4G2.153"
				( objectStatus "@baseboard_fab2_lib.baseboard_fab2(sch_1):page45_i61:dqs0p" )
			)
			( pin "J4G2.163"
				( objectStatus "@baseboard_fab2_lib.baseboard_fab2(sch_1):page45_i61:dqs1n" )
			)
			( pin "J4G2.164"
				( objectStatus "@baseboard_fab2_lib.baseboard_fab2(sch_1):page45_i61:dqs1p" )
			)
			( pin "J4G2.174"
				( objectStatus "@baseboard_fab2_lib.baseboard_fab2(sch_1):page45_i61:dqs2n" )
			)
			( pin "J4G2.175"
				( objectStatus "@baseboard_fab2_lib.baseboard_fab2(sch_1):page45_i61:dqs2p" )
			)
			( pin "J4G2.185"
				( objectStatus "@baseboard_fab2_lib.baseboard_fab2(sch_1):page45_i61:dqs3n" )
			)
			( pin "J4G2.186"
				( objectStatus "@baseboard_fab2_lib.baseboard_fab2(sch_1):page45_i61:dqs3p" )
			)
			( pin "J4G2.244"
				( objectStatus "@baseboard_fab2_lib.baseboard_fab2(sch_1):page45_i61:dqs4n" )
			)
			( pin "J4G2.245"
				( objectStatus "@baseboard_fab2_lib.baseboard_fab2(sch_1):page45_i61:dqs4p" )
			)
			( pin "J4G2.255"
				( objectStatus "@baseboard_fab2_lib.baseboard_fab2(sch_1):page45_i61:dqs5n" )
			)
			( pin "J4G2.256"
				( objectStatus "@baseboard_fab2_lib.baseboard_fab2(sch_1):page45_i61:dqs5p" )
			)
			( pin "J4G2.266"
				( objectStatus "@baseboard_fab2_lib.baseboard_fab2(sch_1):page45_i61:dqs6n" )
			)
			( pin "J4G2.267"
				( objectStatus "@baseboard_fab2_lib.baseboard_fab2(sch_1):page45_i61:dqs6p" )
			)
			( pin "J4G2.277"
				( objectStatus "@baseboard_fab2_lib.baseboard_fab2(sch_1):page45_i61:dqs7n" )
			)
			( pin "J4G2.278"
				( objectStatus "@baseboard_fab2_lib.baseboard_fab2(sch_1):page45_i61:dqs7p" )
			)
			( pin "J4G2.196"
				( objectStatus "@baseboard_fab2_lib.baseboard_fab2(sch_1):page45_i61:dqs8n" )
			)
			( pin "J4G2.197"
				( objectStatus "@baseboard_fab2_lib.baseboard_fab2(sch_1):page45_i61:dqs8p" )
			)
			( pin "J4G2.8"
				( objectStatus "@baseboard_fab2_lib.baseboard_fab2(sch_1):page45_i61:dqs9n" )
			)
			( pin "J4G2.7"
				( objectStatus "@baseboard_fab2_lib.baseboard_fab2(sch_1):page45_i61:dqs9p" )
			)
			( pin "J4G2.19"
				( objectStatus "@baseboard_fab2_lib.baseboard_fab2(sch_1):page45_i61:dqs10n" )
			)
			( pin "J4G2.18"
				( objectStatus "@baseboard_fab2_lib.baseboard_fab2(sch_1):page45_i61:dqs10p" )
			)
			( pin "J4G2.30"
				( objectStatus "@baseboard_fab2_lib.baseboard_fab2(sch_1):page45_i61:dqs11n" )
			)
			( pin "J4G2.29"
				( objectStatus "@baseboard_fab2_lib.baseboard_fab2(sch_1):page45_i61:dqs11p" )
			)
			( pin "J4G2.41"
				( objectStatus "@baseboard_fab2_lib.baseboard_fab2(sch_1):page45_i61:dqs12n" )
			)
			( pin "J4G2.40"
				( objectStatus "@baseboard_fab2_lib.baseboard_fab2(sch_1):page45_i61:dqs12p" )
			)
			( pin "J4G2.100"
				( objectStatus "@baseboard_fab2_lib.baseboard_fab2(sch_1):page45_i61:dqs13n" )
			)
			( pin "J4G2.99"
				( objectStatus "@baseboard_fab2_lib.baseboard_fab2(sch_1):page45_i61:dqs13p" )
			)
			( pin "J4G2.111"
				( objectStatus "@baseboard_fab2_lib.baseboard_fab2(sch_1):page45_i61:dqs14n" )
			)
			( pin "J4G2.110"
				( objectStatus "@baseboard_fab2_lib.baseboard_fab2(sch_1):page45_i61:dqs14p" )
			)
			( pin "J4G2.122"
				( objectStatus "@baseboard_fab2_lib.baseboard_fab2(sch_1):page45_i61:dqs15n" )
			)
			( pin "J4G2.121"
				( objectStatus "@baseboard_fab2_lib.baseboard_fab2(sch_1):page45_i61:dqs15p" )
			)
			( pin "J4G2.133"
				( objectStatus "@baseboard_fab2_lib.baseboard_fab2(sch_1):page45_i61:dqs16n" )
			)
			( pin "J4G2.132"
				( objectStatus "@baseboard_fab2_lib.baseboard_fab2(sch_1):page45_i61:dqs16p" )
			)
			( pin "J4G2.52"
				( objectStatus "@baseboard_fab2_lib.baseboard_fab2(sch_1):page45_i61:dqs17n" )
			)
			( pin "J4G2.51"
				( objectStatus "@baseboard_fab2_lib.baseboard_fab2(sch_1):page45_i61:dqs17p" )
			)
			( pin "J4G2.79"
				( objectStatus "@baseboard_fab2_lib.baseboard_fab2(sch_1):page45_i111:a0" )
			)
			( pin "J4G2.72"
				( objectStatus "@baseboard_fab2_lib.baseboard_fab2(sch_1):page45_i111:a1" )
			)
			( pin "J4G2.216"
				( objectStatus "@baseboard_fab2_lib.baseboard_fab2(sch_1):page45_i111:a2" )
			)
			( pin "J4G2.71"
				( objectStatus "@baseboard_fab2_lib.baseboard_fab2(sch_1):page45_i111:a3" )
			)
			( pin "J4G2.214"
				( objectStatus "@baseboard_fab2_lib.baseboard_fab2(sch_1):page45_i111:a4" )
			)
			( pin "J4G2.213"
				( objectStatus "@baseboard_fab2_lib.baseboard_fab2(sch_1):page45_i111:a5" )
			)
			( pin "J4G2.69"
				( objectStatus "@baseboard_fab2_lib.baseboard_fab2(sch_1):page45_i111:a6" )
			)
			( pin "J4G2.211"
				( objectStatus "@baseboard_fab2_lib.baseboard_fab2(sch_1):page45_i111:a7" )
			)
			( pin "J4G2.68"
				( objectStatus "@baseboard_fab2_lib.baseboard_fab2(sch_1):page45_i111:a8" )
			)
			( pin "J4G2.66"
				( objectStatus "@baseboard_fab2_lib.baseboard_fab2(sch_1):page45_i111:a9" )
			)
			( pin "J4G2.225"
				( objectStatus "@baseboard_fab2_lib.baseboard_fab2(sch_1):page45_i111:a10" )
			)
			( pin "J4G2.210"
				( objectStatus "@baseboard_fab2_lib.baseboard_fab2(sch_1):page45_i111:a11" )
			)
			( pin "J4G2.65"
				( objectStatus "@baseboard_fab2_lib.baseboard_fab2(sch_1):page45_i111:a12" )
			)
			( pin "J4G2.232"
				( objectStatus "@baseboard_fab2_lib.baseboard_fab2(sch_1):page45_i111:a13" )
			)
			( pin "J4G2.228"
				( objectStatus "@baseboard_fab2_lib.baseboard_fab2(sch_1):page45_i111:a14_we_n" )
			)
			( pin "J4G2.86"
				( objectStatus "@baseboard_fab2_lib.baseboard_fab2(sch_1):page45_i111:a15_cas_n" )
			)
			( pin "J4G2.82"
				( objectStatus "@baseboard_fab2_lib.baseboard_fab2(sch_1):page45_i111:a16_ras_n" )
			)
			( pin "J4G2.234"
				( objectStatus "@baseboard_fab2_lib.baseboard_fab2(sch_1):page45_i111:a17" )
			)
			( pin "J4G2.62"
				( objectStatus "@baseboard_fab2_lib.baseboard_fab2(sch_1):page45_i111:act_n" )
			)
			( pin "J4G2.208"
				( objectStatus "@baseboard_fab2_lib.baseboard_fab2(sch_1):page45_i111:alert_n" )
			)
			( pin "J4G2.81"
				( objectStatus "@baseboard_fab2_lib.baseboard_fab2(sch_1):page45_i111:ba(0)" )
			)
			( pin "J4G2.224"
				( objectStatus "@baseboard_fab2_lib.baseboard_fab2(sch_1):page45_i111:ba(1)" )
			)
			( pin "J4G2.63"
				( objectStatus "@baseboard_fab2_lib.baseboard_fab2(sch_1):page45_i111:bg(0)" )
			)
			( pin "J4G2.207"
				( objectStatus "@baseboard_fab2_lib.baseboard_fab2(sch_1):page45_i111:bg(1)" )
			)
			( pin "J4G2.235"
				( objectStatus "@baseboard_fab2_lib.baseboard_fab2(sch_1):page45_i111:c(2)" )
			)
			( pin "J4G2.49"
				( objectStatus "@baseboard_fab2_lib.baseboard_fab2(sch_1):page45_i111:cb(0)" )
			)
			( pin "J4G2.194"
				( objectStatus "@baseboard_fab2_lib.baseboard_fab2(sch_1):page45_i111:cb(1)" )
			)
			( pin "J4G2.56"
				( objectStatus "@baseboard_fab2_lib.baseboard_fab2(sch_1):page45_i111:cb(2)" )
			)
			( pin "J4G2.201"
				( objectStatus "@baseboard_fab2_lib.baseboard_fab2(sch_1):page45_i111:cb(3)" )
			)
			( pin "J4G2.47"
				( objectStatus "@baseboard_fab2_lib.baseboard_fab2(sch_1):page45_i111:cb(4)" )
			)
			( pin "J4G2.192"
				( objectStatus "@baseboard_fab2_lib.baseboard_fab2(sch_1):page45_i111:cb(5)" )
			)
			( pin "J4G2.54"
				( objectStatus "@baseboard_fab2_lib.baseboard_fab2(sch_1):page45_i111:cb(6)" )
			)
			( pin "J4G2.199"
				( objectStatus "@baseboard_fab2_lib.baseboard_fab2(sch_1):page45_i111:cb(7)" )
			)
			( pin "J4G2.75"
				( objectStatus "@baseboard_fab2_lib.baseboard_fab2(sch_1):page45_i111:ck0n" )
			)
			( pin "J4G2.74"
				( objectStatus "@baseboard_fab2_lib.baseboard_fab2(sch_1):page45_i111:ck0p" )
			)
			( pin "J4G2.219"
				( objectStatus "@baseboard_fab2_lib.baseboard_fab2(sch_1):page45_i111:ck1n" )
			)
			( pin "J4G2.218"
				( objectStatus "@baseboard_fab2_lib.baseboard_fab2(sch_1):page45_i111:ck1p" )
			)
			( pin "J4G2.60"
				( objectStatus "@baseboard_fab2_lib.baseboard_fab2(sch_1):page45_i111:cke(0)" )
			)
			( pin "J4G2.203"
				( objectStatus "@baseboard_fab2_lib.baseboard_fab2(sch_1):page45_i111:cke(1)" )
			)
			( pin "J4G2.5"
				( objectStatus "@baseboard_fab2_lib.baseboard_fab2(sch_1):page45_i111:dq(0)" )
			)
			( pin "J4G2.150"
				( objectStatus "@baseboard_fab2_lib.baseboard_fab2(sch_1):page45_i111:dq(1)" )
			)
			( pin "J4G2.12"
				( objectStatus "@baseboard_fab2_lib.baseboard_fab2(sch_1):page45_i111:dq(2)" )
			)
			( pin "J4G2.157"
				( objectStatus "@baseboard_fab2_lib.baseboard_fab2(sch_1):page45_i111:dq(3)" )
			)
			( pin "J4G2.3"
				( objectStatus "@baseboard_fab2_lib.baseboard_fab2(sch_1):page45_i111:dq(4)" )
			)
			( pin "J4G2.148"
				( objectStatus "@baseboard_fab2_lib.baseboard_fab2(sch_1):page45_i111:dq(5)" )
			)
			( pin "J4G2.10"
				( objectStatus "@baseboard_fab2_lib.baseboard_fab2(sch_1):page45_i111:dq(6)" )
			)
			( pin "J4G2.155"
				( objectStatus "@baseboard_fab2_lib.baseboard_fab2(sch_1):page45_i111:dq(7)" )
			)
			( pin "J4G2.16"
				( objectStatus "@baseboard_fab2_lib.baseboard_fab2(sch_1):page45_i111:dq(8)" )
			)
			( pin "J4G2.161"
				( objectStatus "@baseboard_fab2_lib.baseboard_fab2(sch_1):page45_i111:dq(9)" )
			)
			( pin "J4G2.23"
				( objectStatus "@baseboard_fab2_lib.baseboard_fab2(sch_1):page45_i111:dq(10)" )
			)
			( pin "J4G2.168"
				( objectStatus "@baseboard_fab2_lib.baseboard_fab2(sch_1):page45_i111:dq(11)" )
			)
			( pin "J4G2.14"
				( objectStatus "@baseboard_fab2_lib.baseboard_fab2(sch_1):page45_i111:dq(12)" )
			)
			( pin "J4G2.159"
				( objectStatus "@baseboard_fab2_lib.baseboard_fab2(sch_1):page45_i111:dq(13)" )
			)
			( pin "J4G2.21"
				( objectStatus "@baseboard_fab2_lib.baseboard_fab2(sch_1):page45_i111:dq(14)" )
			)
			( pin "J4G2.166"
				( objectStatus "@baseboard_fab2_lib.baseboard_fab2(sch_1):page45_i111:dq(15)" )
			)
			( pin "J4G2.27"
				( objectStatus "@baseboard_fab2_lib.baseboard_fab2(sch_1):page45_i111:dq(16)" )
			)
			( pin "J4G2.172"
				( objectStatus "@baseboard_fab2_lib.baseboard_fab2(sch_1):page45_i111:dq(17)" )
			)
			( pin "J4G2.34"
				( objectStatus "@baseboard_fab2_lib.baseboard_fab2(sch_1):page45_i111:dq(18)" )
			)
			( pin "J4G2.179"
				( objectStatus "@baseboard_fab2_lib.baseboard_fab2(sch_1):page45_i111:dq(19)" )
			)
			( pin "J4G2.25"
				( objectStatus "@baseboard_fab2_lib.baseboard_fab2(sch_1):page45_i111:dq(20)" )
			)
			( pin "J4G2.170"
				( objectStatus "@baseboard_fab2_lib.baseboard_fab2(sch_1):page45_i111:dq(21)" )
			)
			( pin "J4G2.32"
				( objectStatus "@baseboard_fab2_lib.baseboard_fab2(sch_1):page45_i111:dq(22)" )
			)
			( pin "J4G2.177"
				( objectStatus "@baseboard_fab2_lib.baseboard_fab2(sch_1):page45_i111:dq(23)" )
			)
			( pin "J4G2.38"
				( objectStatus "@baseboard_fab2_lib.baseboard_fab2(sch_1):page45_i111:dq(24)" )
			)
			( pin "J4G2.183"
				( objectStatus "@baseboard_fab2_lib.baseboard_fab2(sch_1):page45_i111:dq(25)" )
			)
			( pin "J4G2.45"
				( objectStatus "@baseboard_fab2_lib.baseboard_fab2(sch_1):page45_i111:dq(26)" )
			)
			( pin "J4G2.190"
				( objectStatus "@baseboard_fab2_lib.baseboard_fab2(sch_1):page45_i111:dq(27)" )
			)
			( pin "J4G2.36"
				( objectStatus "@baseboard_fab2_lib.baseboard_fab2(sch_1):page45_i111:dq(28)" )
			)
			( pin "J4G2.181"
				( objectStatus "@baseboard_fab2_lib.baseboard_fab2(sch_1):page45_i111:dq(29)" )
			)
			( pin "J4G2.43"
				( objectStatus "@baseboard_fab2_lib.baseboard_fab2(sch_1):page45_i111:dq(30)" )
			)
			( pin "J4G2.188"
				( objectStatus "@baseboard_fab2_lib.baseboard_fab2(sch_1):page45_i111:dq(31)" )
			)
			( pin "J4G2.97"
				( objectStatus "@baseboard_fab2_lib.baseboard_fab2(sch_1):page45_i111:dq(32)" )
			)
			( pin "J4G2.242"
				( objectStatus "@baseboard_fab2_lib.baseboard_fab2(sch_1):page45_i111:dq(33)" )
			)
			( pin "J4G2.104"
				( objectStatus "@baseboard_fab2_lib.baseboard_fab2(sch_1):page45_i111:dq(34)" )
			)
			( pin "J4G2.249"
				( objectStatus "@baseboard_fab2_lib.baseboard_fab2(sch_1):page45_i111:dq(35)" )
			)
			( pin "J4G2.95"
				( objectStatus "@baseboard_fab2_lib.baseboard_fab2(sch_1):page45_i111:dq(36)" )
			)
			( pin "J4G2.240"
				( objectStatus "@baseboard_fab2_lib.baseboard_fab2(sch_1):page45_i111:dq(37)" )
			)
			( pin "J4G2.102"
				( objectStatus "@baseboard_fab2_lib.baseboard_fab2(sch_1):page45_i111:dq(38)" )
			)
			( pin "J4G2.247"
				( objectStatus "@baseboard_fab2_lib.baseboard_fab2(sch_1):page45_i111:dq(39)" )
			)
			( pin "J4G2.108"
				( objectStatus "@baseboard_fab2_lib.baseboard_fab2(sch_1):page45_i111:dq(40)" )
			)
			( pin "J4G2.253"
				( objectStatus "@baseboard_fab2_lib.baseboard_fab2(sch_1):page45_i111:dq(41)" )
			)
			( pin "J4G2.115"
				( objectStatus "@baseboard_fab2_lib.baseboard_fab2(sch_1):page45_i111:dq(42)" )
			)
			( pin "J4G2.260"
				( objectStatus "@baseboard_fab2_lib.baseboard_fab2(sch_1):page45_i111:dq(43)" )
			)
			( pin "J4G2.106"
				( objectStatus "@baseboard_fab2_lib.baseboard_fab2(sch_1):page45_i111:dq(44)" )
			)
			( pin "J4G2.251"
				( objectStatus "@baseboard_fab2_lib.baseboard_fab2(sch_1):page45_i111:dq(45)" )
			)
			( pin "J4G2.113"
				( objectStatus "@baseboard_fab2_lib.baseboard_fab2(sch_1):page45_i111:dq(46)" )
			)
			( pin "J4G2.258"
				( objectStatus "@baseboard_fab2_lib.baseboard_fab2(sch_1):page45_i111:dq(47)" )
			)
			( pin "J4G2.119"
				( objectStatus "@baseboard_fab2_lib.baseboard_fab2(sch_1):page45_i111:dq(48)" )
			)
			( pin "J4G2.264"
				( objectStatus "@baseboard_fab2_lib.baseboard_fab2(sch_1):page45_i111:dq(49)" )
			)
			( pin "J4G2.126"
				( objectStatus "@baseboard_fab2_lib.baseboard_fab2(sch_1):page45_i111:dq(50)" )
			)
			( pin "J4G2.271"
				( objectStatus "@baseboard_fab2_lib.baseboard_fab2(sch_1):page45_i111:dq(51)" )
			)
			( pin "J4G2.117"
				( objectStatus "@baseboard_fab2_lib.baseboard_fab2(sch_1):page45_i111:dq(52)" )
			)
			( pin "J4G2.262"
				( objectStatus "@baseboard_fab2_lib.baseboard_fab2(sch_1):page45_i111:dq(53)" )
			)
			( pin "J4G2.124"
				( objectStatus "@baseboard_fab2_lib.baseboard_fab2(sch_1):page45_i111:dq(54)" )
			)
			( pin "J4G2.269"
				( objectStatus "@baseboard_fab2_lib.baseboard_fab2(sch_1):page45_i111:dq(55)" )
			)
			( pin "J4G2.130"
				( objectStatus "@baseboard_fab2_lib.baseboard_fab2(sch_1):page45_i111:dq(56)" )
			)
			( pin "J4G2.275"
				( objectStatus "@baseboard_fab2_lib.baseboard_fab2(sch_1):page45_i111:dq(57)" )
			)
			( pin "J4G2.137"
				( objectStatus "@baseboard_fab2_lib.baseboard_fab2(sch_1):page45_i111:dq(58)" )
			)
			( pin "J4G2.282"
				( objectStatus "@baseboard_fab2_lib.baseboard_fab2(sch_1):page45_i111:dq(59)" )
			)
			( pin "J4G2.128"
				( objectStatus "@baseboard_fab2_lib.baseboard_fab2(sch_1):page45_i111:dq(60)" )
			)
			( pin "J4G2.273"
				( objectStatus "@baseboard_fab2_lib.baseboard_fab2(sch_1):page45_i111:dq(61)" )
			)
			( pin "J4G2.135"
				( objectStatus "@baseboard_fab2_lib.baseboard_fab2(sch_1):page45_i111:dq(62)" )
			)
			( pin "J4G2.280"
				( objectStatus "@baseboard_fab2_lib.baseboard_fab2(sch_1):page45_i111:dq(63)" )
			)
			( pin "J4G2.78"
				( objectStatus "@baseboard_fab2_lib.baseboard_fab2(sch_1):page45_i111:event_n" )
			)
			( pin "J4G2.87"
				( objectStatus "@baseboard_fab2_lib.baseboard_fab2(sch_1):page45_i111:odt(0)" )
			)
			( pin "J4G2.91"
				( objectStatus "@baseboard_fab2_lib.baseboard_fab2(sch_1):page45_i111:odt(1)" )
			)
			( pin "J4G2.222"
				( objectStatus "@baseboard_fab2_lib.baseboard_fab2(sch_1):page45_i111:par" )
			)
			( pin "J4G2.58"
				( objectStatus "@baseboard_fab2_lib.baseboard_fab2(sch_1):page45_i111:reset_n" )
			)
			( pin "J4G2.205"
				( objectStatus "@baseboard_fab2_lib.baseboard_fab2(sch_1):page45_i111:rfu(0)" )
			)
			( pin "J4G2.227"
				( objectStatus "@baseboard_fab2_lib.baseboard_fab2(sch_1):page45_i111:rfu(1)" )
			)
			( pin "J4G2.144"
				( objectStatus "@baseboard_fab2_lib.baseboard_fab2(sch_1):page45_i111:rfu(2)" )
			)
			( pin "J4G2.84"
				( objectStatus "@baseboard_fab2_lib.baseboard_fab2(sch_1):page45_i111:s0_n" )
			)
			( pin "J4G2.89"
				( objectStatus "@baseboard_fab2_lib.baseboard_fab2(sch_1):page45_i111:s1_n" )
			)
			( pin "J4G2.93"
				( objectStatus "@baseboard_fab2_lib.baseboard_fab2(sch_1):page45_i111:s2_n_c(0)" )
			)
			( pin "J4G2.237"
				( objectStatus "@baseboard_fab2_lib.baseboard_fab2(sch_1):page45_i111:s3_n_c(1)" )
			)
			( pin "J4G2.139"
				( objectStatus "@baseboard_fab2_lib.baseboard_fab2(sch_1):page45_i111:sa(0)" )
			)
			( pin "J4G2.140"
				( objectStatus "@baseboard_fab2_lib.baseboard_fab2(sch_1):page45_i111:sa(1)" )
			)
			( pin "J4G2.238"
				( objectStatus "@baseboard_fab2_lib.baseboard_fab2(sch_1):page45_i111:sa(2)" )
			)
			( pin "J4G2.230"
				( objectStatus "@baseboard_fab2_lib.baseboard_fab2(sch_1):page45_i111:save_n_nc" )
			)
			( pin "J4G2.141"
				( objectStatus "@baseboard_fab2_lib.baseboard_fab2(sch_1):page45_i111:scl" )
			)
			( pin "J4G2.285"
				( objectStatus "@baseboard_fab2_lib.baseboard_fab2(sch_1):page45_i111:sda" )
			)
			( pin "J4G2.284"
				( objectStatus "@baseboard_fab2_lib.baseboard_fab2(sch_1):page45_i111:vddspd" )
			)
			( pin "J4G2.146"
				( objectStatus "@baseboard_fab2_lib.baseboard_fab2(sch_1):page45_i111:vrefca" )
			)
			( pin "J4G2.145"
				( objectStatus "@baseboard_fab2_lib.baseboard_fab2(sch_1):page45_i169:\12v\(0)" )
			)
			( pin "J4G2.1"
				( objectStatus "@baseboard_fab2_lib.baseboard_fab2(sch_1):page45_i169:\12v\(1)" )
			)
			( pin "J4G2.236"
				( objectStatus "@baseboard_fab2_lib.baseboard_fab2(sch_1):page45_i169:vdd(0)" )
			)
			( pin "J4G2.233"
				( objectStatus "@baseboard_fab2_lib.baseboard_fab2(sch_1):page45_i169:vdd(1)" )
			)
			( pin "J4G2.231"
				( objectStatus "@baseboard_fab2_lib.baseboard_fab2(sch_1):page45_i169:vdd(2)" )
			)
			( pin "J4G2.229"
				( objectStatus "@baseboard_fab2_lib.baseboard_fab2(sch_1):page45_i169:vdd(3)" )
			)
			( pin "J4G2.226"
				( objectStatus "@baseboard_fab2_lib.baseboard_fab2(sch_1):page45_i169:vdd(4)" )
			)
			( pin "J4G2.223"
				( objectStatus "@baseboard_fab2_lib.baseboard_fab2(sch_1):page45_i169:vdd(5)" )
			)
			( pin "J4G2.220"
				( objectStatus "@baseboard_fab2_lib.baseboard_fab2(sch_1):page45_i169:vdd(6)" )
			)
			( pin "J4G2.217"
				( objectStatus "@baseboard_fab2_lib.baseboard_fab2(sch_1):page45_i169:vdd(7)" )
			)
			( pin "J4G2.215"
				( objectStatus "@baseboard_fab2_lib.baseboard_fab2(sch_1):page45_i169:vdd(8)" )
			)
			( pin "J4G2.212"
				( objectStatus "@baseboard_fab2_lib.baseboard_fab2(sch_1):page45_i169:vdd(9)" )
			)
			( pin "J4G2.209"
				( objectStatus "@baseboard_fab2_lib.baseboard_fab2(sch_1):page45_i169:vdd(10)" )
			)
			( pin "J4G2.206"
				( objectStatus "@baseboard_fab2_lib.baseboard_fab2(sch_1):page45_i169:vdd(11)" )
			)
			( pin "J4G2.204"
				( objectStatus "@baseboard_fab2_lib.baseboard_fab2(sch_1):page45_i169:vdd(12)" )
			)
			( pin "J4G2.92"
				( objectStatus "@baseboard_fab2_lib.baseboard_fab2(sch_1):page45_i169:vdd(13)" )
			)
			( pin "J4G2.90"
				( objectStatus "@baseboard_fab2_lib.baseboard_fab2(sch_1):page45_i169:vdd(14)" )
			)
			( pin "J4G2.88"
				( objectStatus "@baseboard_fab2_lib.baseboard_fab2(sch_1):page45_i169:vdd(15)" )
			)
			( pin "J4G2.85"
				( objectStatus "@baseboard_fab2_lib.baseboard_fab2(sch_1):page45_i169:vdd(16)" )
			)
			( pin "J4G2.83"
				( objectStatus "@baseboard_fab2_lib.baseboard_fab2(sch_1):page45_i169:vdd(17)" )
			)
			( pin "J4G2.80"
				( objectStatus "@baseboard_fab2_lib.baseboard_fab2(sch_1):page45_i169:vdd(18)" )
			)
			( pin "J4G2.76"
				( objectStatus "@baseboard_fab2_lib.baseboard_fab2(sch_1):page45_i169:vdd(19)" )
			)
			( pin "J4G2.73"
				( objectStatus "@baseboard_fab2_lib.baseboard_fab2(sch_1):page45_i169:vdd(20)" )
			)
			( pin "J4G2.70"
				( objectStatus "@baseboard_fab2_lib.baseboard_fab2(sch_1):page45_i169:vdd(21)" )
			)
			( pin "J4G2.67"
				( objectStatus "@baseboard_fab2_lib.baseboard_fab2(sch_1):page45_i169:vdd(22)" )
			)
			( pin "J4G2.64"
				( objectStatus "@baseboard_fab2_lib.baseboard_fab2(sch_1):page45_i169:vdd(23)" )
			)
			( pin "J4G2.61"
				( objectStatus "@baseboard_fab2_lib.baseboard_fab2(sch_1):page45_i169:vdd(24)" )
			)
			( pin "J4G2.59"
				( objectStatus "@baseboard_fab2_lib.baseboard_fab2(sch_1):page45_i169:vdd(25)" )
			)
			( pin "J4G2.287"
				( objectStatus "@baseboard_fab2_lib.baseboard_fab2(sch_1):page45_i169:vpp(0)" )
			)
			( pin "J4G2.286"
				( objectStatus "@baseboard_fab2_lib.baseboard_fab2(sch_1):page45_i169:vpp(1)" )
			)
			( pin "J4G2.288"
				( objectStatus "@baseboard_fab2_lib.baseboard_fab2(sch_1):page45_i169:vpp(2)" )
			)
			( pin "J4G2.143"
				( objectStatus "@baseboard_fab2_lib.baseboard_fab2(sch_1):page45_i169:vpp(3)" )
			)
			( pin "J4G2.142"
				( objectStatus "@baseboard_fab2_lib.baseboard_fab2(sch_1):page45_i169:vpp(4)" )
			)
			( pin "J4G2.221"
				( objectStatus "@baseboard_fab2_lib.baseboard_fab2(sch_1):page45_i169:vtt(0)" )
			)
			( pin "J4G2.77"
				( objectStatus "@baseboard_fab2_lib.baseboard_fab2(sch_1):page45_i169:vtt(1)" )
			)
			( pin "C4G3.1"
				( objectStatus "@baseboard_fab2_lib.baseboard_fab2(sch_1):page45_i179:a" )
			)
			( pin "C4G3.2"
				( objectStatus "@baseboard_fab2_lib.baseboard_fab2(sch_1):page45_i179:b" )
			)
			( pin "C6U9.1"
				( objectStatus "@baseboard_fab2_lib.baseboard_fab2(sch_1):page46_i5:a" )
			)
			( pin "C6U9.2"
				( objectStatus "@baseboard_fab2_lib.baseboard_fab2(sch_1):page46_i5:b" )
			)
			( pin "J6U1.79"
				( objectStatus "@baseboard_fab2_lib.baseboard_fab2(sch_1):page46_i14:a0" )
			)
			( pin "J6U1.72"
				( objectStatus "@baseboard_fab2_lib.baseboard_fab2(sch_1):page46_i14:a1" )
			)
			( pin "J6U1.216"
				( objectStatus "@baseboard_fab2_lib.baseboard_fab2(sch_1):page46_i14:a2" )
			)
			( pin "J6U1.71"
				( objectStatus "@baseboard_fab2_lib.baseboard_fab2(sch_1):page46_i14:a3" )
			)
			( pin "J6U1.214"
				( objectStatus "@baseboard_fab2_lib.baseboard_fab2(sch_1):page46_i14:a4" )
			)
			( pin "J6U1.213"
				( objectStatus "@baseboard_fab2_lib.baseboard_fab2(sch_1):page46_i14:a5" )
			)
			( pin "J6U1.69"
				( objectStatus "@baseboard_fab2_lib.baseboard_fab2(sch_1):page46_i14:a6" )
			)
			( pin "J6U1.211"
				( objectStatus "@baseboard_fab2_lib.baseboard_fab2(sch_1):page46_i14:a7" )
			)
			( pin "J6U1.68"
				( objectStatus "@baseboard_fab2_lib.baseboard_fab2(sch_1):page46_i14:a8" )
			)
			( pin "J6U1.66"
				( objectStatus "@baseboard_fab2_lib.baseboard_fab2(sch_1):page46_i14:a9" )
			)
			( pin "J6U1.225"
				( objectStatus "@baseboard_fab2_lib.baseboard_fab2(sch_1):page46_i14:a10" )
			)
			( pin "J6U1.210"
				( objectStatus "@baseboard_fab2_lib.baseboard_fab2(sch_1):page46_i14:a11" )
			)
			( pin "J6U1.65"
				( objectStatus "@baseboard_fab2_lib.baseboard_fab2(sch_1):page46_i14:a12" )
			)
			( pin "J6U1.232"
				( objectStatus "@baseboard_fab2_lib.baseboard_fab2(sch_1):page46_i14:a13" )
			)
			( pin "J6U1.228"
				( objectStatus "@baseboard_fab2_lib.baseboard_fab2(sch_1):page46_i14:a14_we_n" )
			)
			( pin "J6U1.86"
				( objectStatus "@baseboard_fab2_lib.baseboard_fab2(sch_1):page46_i14:a15_cas_n" )
			)
			( pin "J6U1.82"
				( objectStatus "@baseboard_fab2_lib.baseboard_fab2(sch_1):page46_i14:a16_ras_n" )
			)
			( pin "J6U1.234"
				( objectStatus "@baseboard_fab2_lib.baseboard_fab2(sch_1):page46_i14:a17" )
			)
			( pin "J6U1.62"
				( objectStatus "@baseboard_fab2_lib.baseboard_fab2(sch_1):page46_i14:act_n" )
			)
			( pin "J6U1.208"
				( objectStatus "@baseboard_fab2_lib.baseboard_fab2(sch_1):page46_i14:alert_n" )
			)
			( pin "J6U1.81"
				( objectStatus "@baseboard_fab2_lib.baseboard_fab2(sch_1):page46_i14:ba(0)" )
			)
			( pin "J6U1.224"
				( objectStatus "@baseboard_fab2_lib.baseboard_fab2(sch_1):page46_i14:ba(1)" )
			)
			( pin "J6U1.63"
				( objectStatus "@baseboard_fab2_lib.baseboard_fab2(sch_1):page46_i14:bg(0)" )
			)
			( pin "J6U1.207"
				( objectStatus "@baseboard_fab2_lib.baseboard_fab2(sch_1):page46_i14:bg(1)" )
			)
			( pin "J6U1.235"
				( objectStatus "@baseboard_fab2_lib.baseboard_fab2(sch_1):page46_i14:c(2)" )
			)
			( pin "J6U1.49"
				( objectStatus "@baseboard_fab2_lib.baseboard_fab2(sch_1):page46_i14:cb(0)" )
			)
			( pin "J6U1.194"
				( objectStatus "@baseboard_fab2_lib.baseboard_fab2(sch_1):page46_i14:cb(1)" )
			)
			( pin "J6U1.56"
				( objectStatus "@baseboard_fab2_lib.baseboard_fab2(sch_1):page46_i14:cb(2)" )
			)
			( pin "J6U1.201"
				( objectStatus "@baseboard_fab2_lib.baseboard_fab2(sch_1):page46_i14:cb(3)" )
			)
			( pin "J6U1.47"
				( objectStatus "@baseboard_fab2_lib.baseboard_fab2(sch_1):page46_i14:cb(4)" )
			)
			( pin "J6U1.192"
				( objectStatus "@baseboard_fab2_lib.baseboard_fab2(sch_1):page46_i14:cb(5)" )
			)
			( pin "J6U1.54"
				( objectStatus "@baseboard_fab2_lib.baseboard_fab2(sch_1):page46_i14:cb(6)" )
			)
			( pin "J6U1.199"
				( objectStatus "@baseboard_fab2_lib.baseboard_fab2(sch_1):page46_i14:cb(7)" )
			)
			( pin "J6U1.75"
				( objectStatus "@baseboard_fab2_lib.baseboard_fab2(sch_1):page46_i14:ck0n" )
			)
			( pin "J6U1.74"
				( objectStatus "@baseboard_fab2_lib.baseboard_fab2(sch_1):page46_i14:ck0p" )
			)
			( pin "J6U1.219"
				( objectStatus "@baseboard_fab2_lib.baseboard_fab2(sch_1):page46_i14:ck1n" )
			)
			( pin "J6U1.218"
				( objectStatus "@baseboard_fab2_lib.baseboard_fab2(sch_1):page46_i14:ck1p" )
			)
			( pin "J6U1.60"
				( objectStatus "@baseboard_fab2_lib.baseboard_fab2(sch_1):page46_i14:cke(0)" )
			)
			( pin "J6U1.203"
				( objectStatus "@baseboard_fab2_lib.baseboard_fab2(sch_1):page46_i14:cke(1)" )
			)
			( pin "J6U1.5"
				( objectStatus "@baseboard_fab2_lib.baseboard_fab2(sch_1):page46_i14:dq(0)" )
			)
			( pin "J6U1.150"
				( objectStatus "@baseboard_fab2_lib.baseboard_fab2(sch_1):page46_i14:dq(1)" )
			)
			( pin "J6U1.12"
				( objectStatus "@baseboard_fab2_lib.baseboard_fab2(sch_1):page46_i14:dq(2)" )
			)
			( pin "J6U1.157"
				( objectStatus "@baseboard_fab2_lib.baseboard_fab2(sch_1):page46_i14:dq(3)" )
			)
			( pin "J6U1.3"
				( objectStatus "@baseboard_fab2_lib.baseboard_fab2(sch_1):page46_i14:dq(4)" )
			)
			( pin "J6U1.148"
				( objectStatus "@baseboard_fab2_lib.baseboard_fab2(sch_1):page46_i14:dq(5)" )
			)
			( pin "J6U1.10"
				( objectStatus "@baseboard_fab2_lib.baseboard_fab2(sch_1):page46_i14:dq(6)" )
			)
			( pin "J6U1.155"
				( objectStatus "@baseboard_fab2_lib.baseboard_fab2(sch_1):page46_i14:dq(7)" )
			)
			( pin "J6U1.16"
				( objectStatus "@baseboard_fab2_lib.baseboard_fab2(sch_1):page46_i14:dq(8)" )
			)
			( pin "J6U1.161"
				( objectStatus "@baseboard_fab2_lib.baseboard_fab2(sch_1):page46_i14:dq(9)" )
			)
			( pin "J6U1.23"
				( objectStatus "@baseboard_fab2_lib.baseboard_fab2(sch_1):page46_i14:dq(10)" )
			)
			( pin "J6U1.168"
				( objectStatus "@baseboard_fab2_lib.baseboard_fab2(sch_1):page46_i14:dq(11)" )
			)
			( pin "J6U1.14"
				( objectStatus "@baseboard_fab2_lib.baseboard_fab2(sch_1):page46_i14:dq(12)" )
			)
			( pin "J6U1.159"
				( objectStatus "@baseboard_fab2_lib.baseboard_fab2(sch_1):page46_i14:dq(13)" )
			)
			( pin "J6U1.21"
				( objectStatus "@baseboard_fab2_lib.baseboard_fab2(sch_1):page46_i14:dq(14)" )
			)
			( pin "J6U1.166"
				( objectStatus "@baseboard_fab2_lib.baseboard_fab2(sch_1):page46_i14:dq(15)" )
			)
			( pin "J6U1.27"
				( objectStatus "@baseboard_fab2_lib.baseboard_fab2(sch_1):page46_i14:dq(16)" )
			)
			( pin "J6U1.172"
				( objectStatus "@baseboard_fab2_lib.baseboard_fab2(sch_1):page46_i14:dq(17)" )
			)
			( pin "J6U1.34"
				( objectStatus "@baseboard_fab2_lib.baseboard_fab2(sch_1):page46_i14:dq(18)" )
			)
			( pin "J6U1.179"
				( objectStatus "@baseboard_fab2_lib.baseboard_fab2(sch_1):page46_i14:dq(19)" )
			)
			( pin "J6U1.25"
				( objectStatus "@baseboard_fab2_lib.baseboard_fab2(sch_1):page46_i14:dq(20)" )
			)
			( pin "J6U1.170"
				( objectStatus "@baseboard_fab2_lib.baseboard_fab2(sch_1):page46_i14:dq(21)" )
			)
			( pin "J6U1.32"
				( objectStatus "@baseboard_fab2_lib.baseboard_fab2(sch_1):page46_i14:dq(22)" )
			)
			( pin "J6U1.177"
				( objectStatus "@baseboard_fab2_lib.baseboard_fab2(sch_1):page46_i14:dq(23)" )
			)
			( pin "J6U1.38"
				( objectStatus "@baseboard_fab2_lib.baseboard_fab2(sch_1):page46_i14:dq(24)" )
			)
			( pin "J6U1.183"
				( objectStatus "@baseboard_fab2_lib.baseboard_fab2(sch_1):page46_i14:dq(25)" )
			)
			( pin "J6U1.45"
				( objectStatus "@baseboard_fab2_lib.baseboard_fab2(sch_1):page46_i14:dq(26)" )
			)
			( pin "J6U1.190"
				( objectStatus "@baseboard_fab2_lib.baseboard_fab2(sch_1):page46_i14:dq(27)" )
			)
			( pin "J6U1.36"
				( objectStatus "@baseboard_fab2_lib.baseboard_fab2(sch_1):page46_i14:dq(28)" )
			)
			( pin "J6U1.181"
				( objectStatus "@baseboard_fab2_lib.baseboard_fab2(sch_1):page46_i14:dq(29)" )
			)
			( pin "J6U1.43"
				( objectStatus "@baseboard_fab2_lib.baseboard_fab2(sch_1):page46_i14:dq(30)" )
			)
			( pin "J6U1.188"
				( objectStatus "@baseboard_fab2_lib.baseboard_fab2(sch_1):page46_i14:dq(31)" )
			)
			( pin "J6U1.97"
				( objectStatus "@baseboard_fab2_lib.baseboard_fab2(sch_1):page46_i14:dq(32)" )
			)
			( pin "J6U1.242"
				( objectStatus "@baseboard_fab2_lib.baseboard_fab2(sch_1):page46_i14:dq(33)" )
			)
			( pin "J6U1.104"
				( objectStatus "@baseboard_fab2_lib.baseboard_fab2(sch_1):page46_i14:dq(34)" )
			)
			( pin "J6U1.249"
				( objectStatus "@baseboard_fab2_lib.baseboard_fab2(sch_1):page46_i14:dq(35)" )
			)
			( pin "J6U1.95"
				( objectStatus "@baseboard_fab2_lib.baseboard_fab2(sch_1):page46_i14:dq(36)" )
			)
			( pin "J6U1.240"
				( objectStatus "@baseboard_fab2_lib.baseboard_fab2(sch_1):page46_i14:dq(37)" )
			)
			( pin "J6U1.102"
				( objectStatus "@baseboard_fab2_lib.baseboard_fab2(sch_1):page46_i14:dq(38)" )
			)
			( pin "J6U1.247"
				( objectStatus "@baseboard_fab2_lib.baseboard_fab2(sch_1):page46_i14:dq(39)" )
			)
			( pin "J6U1.108"
				( objectStatus "@baseboard_fab2_lib.baseboard_fab2(sch_1):page46_i14:dq(40)" )
			)
			( pin "J6U1.253"
				( objectStatus "@baseboard_fab2_lib.baseboard_fab2(sch_1):page46_i14:dq(41)" )
			)
			( pin "J6U1.115"
				( objectStatus "@baseboard_fab2_lib.baseboard_fab2(sch_1):page46_i14:dq(42)" )
			)
			( pin "J6U1.260"
				( objectStatus "@baseboard_fab2_lib.baseboard_fab2(sch_1):page46_i14:dq(43)" )
			)
			( pin "J6U1.106"
				( objectStatus "@baseboard_fab2_lib.baseboard_fab2(sch_1):page46_i14:dq(44)" )
			)
			( pin "J6U1.251"
				( objectStatus "@baseboard_fab2_lib.baseboard_fab2(sch_1):page46_i14:dq(45)" )
			)
			( pin "J6U1.113"
				( objectStatus "@baseboard_fab2_lib.baseboard_fab2(sch_1):page46_i14:dq(46)" )
			)
			( pin "J6U1.258"
				( objectStatus "@baseboard_fab2_lib.baseboard_fab2(sch_1):page46_i14:dq(47)" )
			)
			( pin "J6U1.119"
				( objectStatus "@baseboard_fab2_lib.baseboard_fab2(sch_1):page46_i14:dq(48)" )
			)
			( pin "J6U1.264"
				( objectStatus "@baseboard_fab2_lib.baseboard_fab2(sch_1):page46_i14:dq(49)" )
			)
			( pin "J6U1.126"
				( objectStatus "@baseboard_fab2_lib.baseboard_fab2(sch_1):page46_i14:dq(50)" )
			)
			( pin "J6U1.271"
				( objectStatus "@baseboard_fab2_lib.baseboard_fab2(sch_1):page46_i14:dq(51)" )
			)
			( pin "J6U1.117"
				( objectStatus "@baseboard_fab2_lib.baseboard_fab2(sch_1):page46_i14:dq(52)" )
			)
			( pin "J6U1.262"
				( objectStatus "@baseboard_fab2_lib.baseboard_fab2(sch_1):page46_i14:dq(53)" )
			)
			( pin "J6U1.124"
				( objectStatus "@baseboard_fab2_lib.baseboard_fab2(sch_1):page46_i14:dq(54)" )
			)
			( pin "J6U1.269"
				( objectStatus "@baseboard_fab2_lib.baseboard_fab2(sch_1):page46_i14:dq(55)" )
			)
			( pin "J6U1.130"
				( objectStatus "@baseboard_fab2_lib.baseboard_fab2(sch_1):page46_i14:dq(56)" )
			)
			( pin "J6U1.275"
				( objectStatus "@baseboard_fab2_lib.baseboard_fab2(sch_1):page46_i14:dq(57)" )
			)
			( pin "J6U1.137"
				( objectStatus "@baseboard_fab2_lib.baseboard_fab2(sch_1):page46_i14:dq(58)" )
			)
			( pin "J6U1.282"
				( objectStatus "@baseboard_fab2_lib.baseboard_fab2(sch_1):page46_i14:dq(59)" )
			)
			( pin "J6U1.128"
				( objectStatus "@baseboard_fab2_lib.baseboard_fab2(sch_1):page46_i14:dq(60)" )
			)
			( pin "J6U1.273"
				( objectStatus "@baseboard_fab2_lib.baseboard_fab2(sch_1):page46_i14:dq(61)" )
			)
			( pin "J6U1.135"
				( objectStatus "@baseboard_fab2_lib.baseboard_fab2(sch_1):page46_i14:dq(62)" )
			)
			( pin "J6U1.280"
				( objectStatus "@baseboard_fab2_lib.baseboard_fab2(sch_1):page46_i14:dq(63)" )
			)
			( pin "J6U1.78"
				( objectStatus "@baseboard_fab2_lib.baseboard_fab2(sch_1):page46_i14:event_n" )
			)
			( pin "J6U1.87"
				( objectStatus "@baseboard_fab2_lib.baseboard_fab2(sch_1):page46_i14:odt(0)" )
			)
			( pin "J6U1.91"
				( objectStatus "@baseboard_fab2_lib.baseboard_fab2(sch_1):page46_i14:odt(1)" )
			)
			( pin "J6U1.222"
				( objectStatus "@baseboard_fab2_lib.baseboard_fab2(sch_1):page46_i14:par" )
			)
			( pin "J6U1.58"
				( objectStatus "@baseboard_fab2_lib.baseboard_fab2(sch_1):page46_i14:reset_n" )
			)
			( pin "J6U1.205"
				( objectStatus "@baseboard_fab2_lib.baseboard_fab2(sch_1):page46_i14:rfu(0)" )
			)
			( pin "J6U1.227"
				( objectStatus "@baseboard_fab2_lib.baseboard_fab2(sch_1):page46_i14:rfu(1)" )
			)
			( pin "J6U1.144"
				( objectStatus "@baseboard_fab2_lib.baseboard_fab2(sch_1):page46_i14:rfu(2)" )
			)
			( pin "J6U1.84"
				( objectStatus "@baseboard_fab2_lib.baseboard_fab2(sch_1):page46_i14:s0_n" )
			)
			( pin "J6U1.89"
				( objectStatus "@baseboard_fab2_lib.baseboard_fab2(sch_1):page46_i14:s1_n" )
			)
			( pin "J6U1.93"
				( objectStatus "@baseboard_fab2_lib.baseboard_fab2(sch_1):page46_i14:s2_n_c(0)" )
			)
			( pin "J6U1.237"
				( objectStatus "@baseboard_fab2_lib.baseboard_fab2(sch_1):page46_i14:s3_n_c(1)" )
			)
			( pin "J6U1.139"
				( objectStatus "@baseboard_fab2_lib.baseboard_fab2(sch_1):page46_i14:sa(0)" )
			)
			( pin "J6U1.140"
				( objectStatus "@baseboard_fab2_lib.baseboard_fab2(sch_1):page46_i14:sa(1)" )
			)
			( pin "J6U1.238"
				( objectStatus "@baseboard_fab2_lib.baseboard_fab2(sch_1):page46_i14:sa(2)" )
			)
			( pin "J6U1.230"
				( objectStatus "@baseboard_fab2_lib.baseboard_fab2(sch_1):page46_i14:save_n_nc" )
			)
			( pin "J6U1.141"
				( objectStatus "@baseboard_fab2_lib.baseboard_fab2(sch_1):page46_i14:scl" )
			)
			( pin "J6U1.285"
				( objectStatus "@baseboard_fab2_lib.baseboard_fab2(sch_1):page46_i14:sda" )
			)
			( pin "J6U1.284"
				( objectStatus "@baseboard_fab2_lib.baseboard_fab2(sch_1):page46_i14:vddspd" )
			)
			( pin "J6U1.146"
				( objectStatus "@baseboard_fab2_lib.baseboard_fab2(sch_1):page46_i14:vrefca" )
			)
			( pin "J6U1.145"
				( objectStatus "@baseboard_fab2_lib.baseboard_fab2(sch_1):page46_i67:\12v\(0)" )
			)
			( pin "J6U1.1"
				( objectStatus "@baseboard_fab2_lib.baseboard_fab2(sch_1):page46_i67:\12v\(1)" )
			)
			( pin "J6U1.236"
				( objectStatus "@baseboard_fab2_lib.baseboard_fab2(sch_1):page46_i67:vdd(0)" )
			)
			( pin "J6U1.233"
				( objectStatus "@baseboard_fab2_lib.baseboard_fab2(sch_1):page46_i67:vdd(1)" )
			)
			( pin "J6U1.231"
				( objectStatus "@baseboard_fab2_lib.baseboard_fab2(sch_1):page46_i67:vdd(2)" )
			)
			( pin "J6U1.229"
				( objectStatus "@baseboard_fab2_lib.baseboard_fab2(sch_1):page46_i67:vdd(3)" )
			)
			( pin "J6U1.226"
				( objectStatus "@baseboard_fab2_lib.baseboard_fab2(sch_1):page46_i67:vdd(4)" )
			)
			( pin "J6U1.223"
				( objectStatus "@baseboard_fab2_lib.baseboard_fab2(sch_1):page46_i67:vdd(5)" )
			)
			( pin "J6U1.220"
				( objectStatus "@baseboard_fab2_lib.baseboard_fab2(sch_1):page46_i67:vdd(6)" )
			)
			( pin "J6U1.217"
				( objectStatus "@baseboard_fab2_lib.baseboard_fab2(sch_1):page46_i67:vdd(7)" )
			)
			( pin "J6U1.215"
				( objectStatus "@baseboard_fab2_lib.baseboard_fab2(sch_1):page46_i67:vdd(8)" )
			)
			( pin "J6U1.212"
				( objectStatus "@baseboard_fab2_lib.baseboard_fab2(sch_1):page46_i67:vdd(9)" )
			)
			( pin "J6U1.209"
				( objectStatus "@baseboard_fab2_lib.baseboard_fab2(sch_1):page46_i67:vdd(10)" )
			)
			( pin "J6U1.206"
				( objectStatus "@baseboard_fab2_lib.baseboard_fab2(sch_1):page46_i67:vdd(11)" )
			)
			( pin "J6U1.204"
				( objectStatus "@baseboard_fab2_lib.baseboard_fab2(sch_1):page46_i67:vdd(12)" )
			)
			( pin "J6U1.92"
				( objectStatus "@baseboard_fab2_lib.baseboard_fab2(sch_1):page46_i67:vdd(13)" )
			)
			( pin "J6U1.90"
				( objectStatus "@baseboard_fab2_lib.baseboard_fab2(sch_1):page46_i67:vdd(14)" )
			)
			( pin "J6U1.88"
				( objectStatus "@baseboard_fab2_lib.baseboard_fab2(sch_1):page46_i67:vdd(15)" )
			)
			( pin "J6U1.85"
				( objectStatus "@baseboard_fab2_lib.baseboard_fab2(sch_1):page46_i67:vdd(16)" )
			)
			( pin "J6U1.83"
				( objectStatus "@baseboard_fab2_lib.baseboard_fab2(sch_1):page46_i67:vdd(17)" )
			)
			( pin "J6U1.80"
				( objectStatus "@baseboard_fab2_lib.baseboard_fab2(sch_1):page46_i67:vdd(18)" )
			)
			( pin "J6U1.76"
				( objectStatus "@baseboard_fab2_lib.baseboard_fab2(sch_1):page46_i67:vdd(19)" )
			)
			( pin "J6U1.73"
				( objectStatus "@baseboard_fab2_lib.baseboard_fab2(sch_1):page46_i67:vdd(20)" )
			)
			( pin "J6U1.70"
				( objectStatus "@baseboard_fab2_lib.baseboard_fab2(sch_1):page46_i67:vdd(21)" )
			)
			( pin "J6U1.67"
				( objectStatus "@baseboard_fab2_lib.baseboard_fab2(sch_1):page46_i67:vdd(22)" )
			)
			( pin "J6U1.64"
				( objectStatus "@baseboard_fab2_lib.baseboard_fab2(sch_1):page46_i67:vdd(23)" )
			)
			( pin "J6U1.61"
				( objectStatus "@baseboard_fab2_lib.baseboard_fab2(sch_1):page46_i67:vdd(24)" )
			)
			( pin "J6U1.59"
				( objectStatus "@baseboard_fab2_lib.baseboard_fab2(sch_1):page46_i67:vdd(25)" )
			)
			( pin "J6U1.287"
				( objectStatus "@baseboard_fab2_lib.baseboard_fab2(sch_1):page46_i67:vpp(0)" )
			)
			( pin "J6U1.286"
				( objectStatus "@baseboard_fab2_lib.baseboard_fab2(sch_1):page46_i67:vpp(1)" )
			)
			( pin "J6U1.288"
				( objectStatus "@baseboard_fab2_lib.baseboard_fab2(sch_1):page46_i67:vpp(2)" )
			)
			( pin "J6U1.143"
				( objectStatus "@baseboard_fab2_lib.baseboard_fab2(sch_1):page46_i67:vpp(3)" )
			)
			( pin "J6U1.142"
				( objectStatus "@baseboard_fab2_lib.baseboard_fab2(sch_1):page46_i67:vpp(4)" )
			)
			( pin "J6U1.221"
				( objectStatus "@baseboard_fab2_lib.baseboard_fab2(sch_1):page46_i67:vtt(0)" )
			)
			( pin "J6U1.77"
				( objectStatus "@baseboard_fab2_lib.baseboard_fab2(sch_1):page46_i67:vtt(1)" )
			)
			( pin "J6U1.152"
				( objectStatus "@baseboard_fab2_lib.baseboard_fab2(sch_1):page46_i112:dqs0n" )
			)
			( pin "J6U1.153"
				( objectStatus "@baseboard_fab2_lib.baseboard_fab2(sch_1):page46_i112:dqs0p" )
			)
			( pin "J6U1.163"
				( objectStatus "@baseboard_fab2_lib.baseboard_fab2(sch_1):page46_i112:dqs1n" )
			)
			( pin "J6U1.164"
				( objectStatus "@baseboard_fab2_lib.baseboard_fab2(sch_1):page46_i112:dqs1p" )
			)
			( pin "J6U1.174"
				( objectStatus "@baseboard_fab2_lib.baseboard_fab2(sch_1):page46_i112:dqs2n" )
			)
			( pin "J6U1.175"
				( objectStatus "@baseboard_fab2_lib.baseboard_fab2(sch_1):page46_i112:dqs2p" )
			)
			( pin "J6U1.185"
				( objectStatus "@baseboard_fab2_lib.baseboard_fab2(sch_1):page46_i112:dqs3n" )
			)
			( pin "J6U1.186"
				( objectStatus "@baseboard_fab2_lib.baseboard_fab2(sch_1):page46_i112:dqs3p" )
			)
			( pin "J6U1.244"
				( objectStatus "@baseboard_fab2_lib.baseboard_fab2(sch_1):page46_i112:dqs4n" )
			)
			( pin "J6U1.245"
				( objectStatus "@baseboard_fab2_lib.baseboard_fab2(sch_1):page46_i112:dqs4p" )
			)
			( pin "J6U1.255"
				( objectStatus "@baseboard_fab2_lib.baseboard_fab2(sch_1):page46_i112:dqs5n" )
			)
			( pin "J6U1.256"
				( objectStatus "@baseboard_fab2_lib.baseboard_fab2(sch_1):page46_i112:dqs5p" )
			)
			( pin "J6U1.266"
				( objectStatus "@baseboard_fab2_lib.baseboard_fab2(sch_1):page46_i112:dqs6n" )
			)
			( pin "J6U1.267"
				( objectStatus "@baseboard_fab2_lib.baseboard_fab2(sch_1):page46_i112:dqs6p" )
			)
			( pin "J6U1.277"
				( objectStatus "@baseboard_fab2_lib.baseboard_fab2(sch_1):page46_i112:dqs7n" )
			)
			( pin "J6U1.278"
				( objectStatus "@baseboard_fab2_lib.baseboard_fab2(sch_1):page46_i112:dqs7p" )
			)
			( pin "J6U1.196"
				( objectStatus "@baseboard_fab2_lib.baseboard_fab2(sch_1):page46_i112:dqs8n" )
			)
			( pin "J6U1.197"
				( objectStatus "@baseboard_fab2_lib.baseboard_fab2(sch_1):page46_i112:dqs8p" )
			)
			( pin "J6U1.8"
				( objectStatus "@baseboard_fab2_lib.baseboard_fab2(sch_1):page46_i112:dqs9n" )
			)
			( pin "J6U1.7"
				( objectStatus "@baseboard_fab2_lib.baseboard_fab2(sch_1):page46_i112:dqs9p" )
			)
			( pin "J6U1.19"
				( objectStatus "@baseboard_fab2_lib.baseboard_fab2(sch_1):page46_i112:dqs10n" )
			)
			( pin "J6U1.18"
				( objectStatus "@baseboard_fab2_lib.baseboard_fab2(sch_1):page46_i112:dqs10p" )
			)
			( pin "J6U1.30"
				( objectStatus "@baseboard_fab2_lib.baseboard_fab2(sch_1):page46_i112:dqs11n" )
			)
			( pin "J6U1.29"
				( objectStatus "@baseboard_fab2_lib.baseboard_fab2(sch_1):page46_i112:dqs11p" )
			)
			( pin "J6U1.41"
				( objectStatus "@baseboard_fab2_lib.baseboard_fab2(sch_1):page46_i112:dqs12n" )
			)
			( pin "J6U1.40"
				( objectStatus "@baseboard_fab2_lib.baseboard_fab2(sch_1):page46_i112:dqs12p" )
			)
			( pin "J6U1.100"
				( objectStatus "@baseboard_fab2_lib.baseboard_fab2(sch_1):page46_i112:dqs13n" )
			)
			( pin "J6U1.99"
				( objectStatus "@baseboard_fab2_lib.baseboard_fab2(sch_1):page46_i112:dqs13p" )
			)
			( pin "J6U1.111"
				( objectStatus "@baseboard_fab2_lib.baseboard_fab2(sch_1):page46_i112:dqs14n" )
			)
			( pin "J6U1.110"
				( objectStatus "@baseboard_fab2_lib.baseboard_fab2(sch_1):page46_i112:dqs14p" )
			)
			( pin "J6U1.122"
				( objectStatus "@baseboard_fab2_lib.baseboard_fab2(sch_1):page46_i112:dqs15n" )
			)
			( pin "J6U1.121"
				( objectStatus "@baseboard_fab2_lib.baseboard_fab2(sch_1):page46_i112:dqs15p" )
			)
			( pin "J6U1.133"
				( objectStatus "@baseboard_fab2_lib.baseboard_fab2(sch_1):page46_i112:dqs16n" )
			)
			( pin "J6U1.132"
				( objectStatus "@baseboard_fab2_lib.baseboard_fab2(sch_1):page46_i112:dqs16p" )
			)
			( pin "J6U1.52"
				( objectStatus "@baseboard_fab2_lib.baseboard_fab2(sch_1):page46_i112:dqs17n" )
			)
			( pin "J6U1.51"
				( objectStatus "@baseboard_fab2_lib.baseboard_fab2(sch_1):page46_i112:dqs17p" )
			)
			( pin "J6U1.283"
				( objectStatus "@baseboard_fab2_lib.baseboard_fab2(sch_1):page46_i138:vss(0)" )
			)
			( pin "J6U1.281"
				( objectStatus "@baseboard_fab2_lib.baseboard_fab2(sch_1):page46_i138:vss(1)" )
			)
			( pin "J6U1.279"
				( objectStatus "@baseboard_fab2_lib.baseboard_fab2(sch_1):page46_i138:vss(2)" )
			)
			( pin "J6U1.276"
				( objectStatus "@baseboard_fab2_lib.baseboard_fab2(sch_1):page46_i138:vss(3)" )
			)
			( pin "J6U1.274"
				( objectStatus "@baseboard_fab2_lib.baseboard_fab2(sch_1):page46_i138:vss(4)" )
			)
			( pin "J6U1.272"
				( objectStatus "@baseboard_fab2_lib.baseboard_fab2(sch_1):page46_i138:vss(5)" )
			)
			( pin "J6U1.270"
				( objectStatus "@baseboard_fab2_lib.baseboard_fab2(sch_1):page46_i138:vss(6)" )
			)
			( pin "J6U1.268"
				( objectStatus "@baseboard_fab2_lib.baseboard_fab2(sch_1):page46_i138:vss(7)" )
			)
			( pin "J6U1.265"
				( objectStatus "@baseboard_fab2_lib.baseboard_fab2(sch_1):page46_i138:vss(8)" )
			)
			( pin "J6U1.263"
				( objectStatus "@baseboard_fab2_lib.baseboard_fab2(sch_1):page46_i138:vss(9)" )
			)
			( pin "J6U1.261"
				( objectStatus "@baseboard_fab2_lib.baseboard_fab2(sch_1):page46_i138:vss(10)" )
			)
			( pin "J6U1.259"
				( objectStatus "@baseboard_fab2_lib.baseboard_fab2(sch_1):page46_i138:vss(11)" )
			)
			( pin "J6U1.257"
				( objectStatus "@baseboard_fab2_lib.baseboard_fab2(sch_1):page46_i138:vss(12)" )
			)
			( pin "J6U1.254"
				( objectStatus "@baseboard_fab2_lib.baseboard_fab2(sch_1):page46_i138:vss(13)" )
			)
			( pin "J6U1.252"
				( objectStatus "@baseboard_fab2_lib.baseboard_fab2(sch_1):page46_i138:vss(14)" )
			)
			( pin "J6U1.250"
				( objectStatus "@baseboard_fab2_lib.baseboard_fab2(sch_1):page46_i138:vss(15)" )
			)
			( pin "J6U1.248"
				( objectStatus "@baseboard_fab2_lib.baseboard_fab2(sch_1):page46_i138:vss(16)" )
			)
			( pin "J6U1.246"
				( objectStatus "@baseboard_fab2_lib.baseboard_fab2(sch_1):page46_i138:vss(17)" )
			)
			( pin "J6U1.243"
				( objectStatus "@baseboard_fab2_lib.baseboard_fab2(sch_1):page46_i138:vss(18)" )
			)
			( pin "J6U1.241"
				( objectStatus "@baseboard_fab2_lib.baseboard_fab2(sch_1):page46_i138:vss(19)" )
			)
			( pin "J6U1.239"
				( objectStatus "@baseboard_fab2_lib.baseboard_fab2(sch_1):page46_i138:vss(20)" )
			)
			( pin "J6U1.202"
				( objectStatus "@baseboard_fab2_lib.baseboard_fab2(sch_1):page46_i138:vss(21)" )
			)
			( pin "J6U1.200"
				( objectStatus "@baseboard_fab2_lib.baseboard_fab2(sch_1):page46_i138:vss(22)" )
			)
			( pin "J6U1.198"
				( objectStatus "@baseboard_fab2_lib.baseboard_fab2(sch_1):page46_i138:vss(23)" )
			)
			( pin "J6U1.195"
				( objectStatus "@baseboard_fab2_lib.baseboard_fab2(sch_1):page46_i138:vss(24)" )
			)
			( pin "J6U1.193"
				( objectStatus "@baseboard_fab2_lib.baseboard_fab2(sch_1):page46_i138:vss(25)" )
			)
			( pin "J6U1.191"
				( objectStatus "@baseboard_fab2_lib.baseboard_fab2(sch_1):page46_i138:vss(26)" )
			)
			( pin "J6U1.189"
				( objectStatus "@baseboard_fab2_lib.baseboard_fab2(sch_1):page46_i138:vss(27)" )
			)
			( pin "J6U1.187"
				( objectStatus "@baseboard_fab2_lib.baseboard_fab2(sch_1):page46_i138:vss(28)" )
			)
			( pin "J6U1.184"
				( objectStatus "@baseboard_fab2_lib.baseboard_fab2(sch_1):page46_i138:vss(29)" )
			)
			( pin "J6U1.182"
				( objectStatus "@baseboard_fab2_lib.baseboard_fab2(sch_1):page46_i138:vss(30)" )
			)
			( pin "J6U1.180"
				( objectStatus "@baseboard_fab2_lib.baseboard_fab2(sch_1):page46_i138:vss(31)" )
			)
			( pin "J6U1.178"
				( objectStatus "@baseboard_fab2_lib.baseboard_fab2(sch_1):page46_i138:vss(32)" )
			)
			( pin "J6U1.176"
				( objectStatus "@baseboard_fab2_lib.baseboard_fab2(sch_1):page46_i138:vss(33)" )
			)
			( pin "J6U1.173"
				( objectStatus "@baseboard_fab2_lib.baseboard_fab2(sch_1):page46_i138:vss(34)" )
			)
			( pin "J6U1.171"
				( objectStatus "@baseboard_fab2_lib.baseboard_fab2(sch_1):page46_i138:vss(35)" )
			)
			( pin "J6U1.169"
				( objectStatus "@baseboard_fab2_lib.baseboard_fab2(sch_1):page46_i138:vss(36)" )
			)
			( pin "J6U1.167"
				( objectStatus "@baseboard_fab2_lib.baseboard_fab2(sch_1):page46_i138:vss(37)" )
			)
			( pin "J6U1.165"
				( objectStatus "@baseboard_fab2_lib.baseboard_fab2(sch_1):page46_i138:vss(38)" )
			)
			( pin "J6U1.162"
				( objectStatus "@baseboard_fab2_lib.baseboard_fab2(sch_1):page46_i138:vss(39)" )
			)
			( pin "J6U1.160"
				( objectStatus "@baseboard_fab2_lib.baseboard_fab2(sch_1):page46_i138:vss(40)" )
			)
			( pin "J6U1.158"
				( objectStatus "@baseboard_fab2_lib.baseboard_fab2(sch_1):page46_i138:vss(41)" )
			)
			( pin "J6U1.156"
				( objectStatus "@baseboard_fab2_lib.baseboard_fab2(sch_1):page46_i138:vss(42)" )
			)
			( pin "J6U1.154"
				( objectStatus "@baseboard_fab2_lib.baseboard_fab2(sch_1):page46_i138:vss(43)" )
			)
			( pin "J6U1.151"
				( objectStatus "@baseboard_fab2_lib.baseboard_fab2(sch_1):page46_i138:vss(44)" )
			)
			( pin "J6U1.149"
				( objectStatus "@baseboard_fab2_lib.baseboard_fab2(sch_1):page46_i138:vss(45)" )
			)
			( pin "J6U1.147"
				( objectStatus "@baseboard_fab2_lib.baseboard_fab2(sch_1):page46_i138:vss(46)" )
			)
			( pin "J6U1.138"
				( objectStatus "@baseboard_fab2_lib.baseboard_fab2(sch_1):page46_i138:vss(47)" )
			)
			( pin "J6U1.136"
				( objectStatus "@baseboard_fab2_lib.baseboard_fab2(sch_1):page46_i138:vss(48)" )
			)
			( pin "J6U1.134"
				( objectStatus "@baseboard_fab2_lib.baseboard_fab2(sch_1):page46_i138:vss(49)" )
			)
			( pin "J6U1.131"
				( objectStatus "@baseboard_fab2_lib.baseboard_fab2(sch_1):page46_i138:vss(50)" )
			)
			( pin "J6U1.129"
				( objectStatus "@baseboard_fab2_lib.baseboard_fab2(sch_1):page46_i138:vss(51)" )
			)
			( pin "J6U1.127"
				( objectStatus "@baseboard_fab2_lib.baseboard_fab2(sch_1):page46_i138:vss(52)" )
			)
			( pin "J6U1.125"
				( objectStatus "@baseboard_fab2_lib.baseboard_fab2(sch_1):page46_i138:vss(53)" )
			)
			( pin "J6U1.123"
				( objectStatus "@baseboard_fab2_lib.baseboard_fab2(sch_1):page46_i138:vss(54)" )
			)
			( pin "J6U1.120"
				( objectStatus "@baseboard_fab2_lib.baseboard_fab2(sch_1):page46_i138:vss(55)" )
			)
			( pin "J6U1.118"
				( objectStatus "@baseboard_fab2_lib.baseboard_fab2(sch_1):page46_i138:vss(56)" )
			)
			( pin "J6U1.116"
				( objectStatus "@baseboard_fab2_lib.baseboard_fab2(sch_1):page46_i138:vss(57)" )
			)
			( pin "J6U1.114"
				( objectStatus "@baseboard_fab2_lib.baseboard_fab2(sch_1):page46_i138:vss(58)" )
			)
			( pin "J6U1.112"
				( objectStatus "@baseboard_fab2_lib.baseboard_fab2(sch_1):page46_i138:vss(59)" )
			)
			( pin "J6U1.109"
				( objectStatus "@baseboard_fab2_lib.baseboard_fab2(sch_1):page46_i138:vss(60)" )
			)
			( pin "J6U1.107"
				( objectStatus "@baseboard_fab2_lib.baseboard_fab2(sch_1):page46_i138:vss(61)" )
			)
			( pin "J6U1.105"
				( objectStatus "@baseboard_fab2_lib.baseboard_fab2(sch_1):page46_i138:vss(62)" )
			)
			( pin "J6U1.103"
				( objectStatus "@baseboard_fab2_lib.baseboard_fab2(sch_1):page46_i138:vss(63)" )
			)
			( pin "J6U1.101"
				( objectStatus "@baseboard_fab2_lib.baseboard_fab2(sch_1):page46_i138:vss(64)" )
			)
			( pin "J6U1.98"
				( objectStatus "@baseboard_fab2_lib.baseboard_fab2(sch_1):page46_i138:vss(65)" )
			)
			( pin "J6U1.96"
				( objectStatus "@baseboard_fab2_lib.baseboard_fab2(sch_1):page46_i138:vss(66)" )
			)
			( pin "J6U1.94"
				( objectStatus "@baseboard_fab2_lib.baseboard_fab2(sch_1):page46_i138:vss(67)" )
			)
			( pin "J6U1.57"
				( objectStatus "@baseboard_fab2_lib.baseboard_fab2(sch_1):page46_i138:vss(68)" )
			)
			( pin "J6U1.55"
				( objectStatus "@baseboard_fab2_lib.baseboard_fab2(sch_1):page46_i138:vss(69)" )
			)
			( pin "J6U1.53"
				( objectStatus "@baseboard_fab2_lib.baseboard_fab2(sch_1):page46_i138:vss(70)" )
			)
			( pin "J6U1.50"
				( objectStatus "@baseboard_fab2_lib.baseboard_fab2(sch_1):page46_i138:vss(71)" )
			)
			( pin "J6U1.48"
				( objectStatus "@baseboard_fab2_lib.baseboard_fab2(sch_1):page46_i138:vss(72)" )
			)
			( pin "J6U1.46"
				( objectStatus "@baseboard_fab2_lib.baseboard_fab2(sch_1):page46_i138:vss(73)" )
			)
			( pin "J6U1.44"
				( objectStatus "@baseboard_fab2_lib.baseboard_fab2(sch_1):page46_i138:vss(74)" )
			)
			( pin "J6U1.42"
				( objectStatus "@baseboard_fab2_lib.baseboard_fab2(sch_1):page46_i138:vss(75)" )
			)
			( pin "J6U1.39"
				( objectStatus "@baseboard_fab2_lib.baseboard_fab2(sch_1):page46_i138:vss(76)" )
			)
			( pin "J6U1.37"
				( objectStatus "@baseboard_fab2_lib.baseboard_fab2(sch_1):page46_i138:vss(77)" )
			)
			( pin "J6U1.35"
				( objectStatus "@baseboard_fab2_lib.baseboard_fab2(sch_1):page46_i138:vss(78)" )
			)
			( pin "J6U1.33"
				( objectStatus "@baseboard_fab2_lib.baseboard_fab2(sch_1):page46_i138:vss(79)" )
			)
			( pin "J6U1.31"
				( objectStatus "@baseboard_fab2_lib.baseboard_fab2(sch_1):page46_i138:vss(80)" )
			)
			( pin "J6U1.28"
				( objectStatus "@baseboard_fab2_lib.baseboard_fab2(sch_1):page46_i138:vss(81)" )
			)
			( pin "J6U1.26"
				( objectStatus "@baseboard_fab2_lib.baseboard_fab2(sch_1):page46_i138:vss(82)" )
			)
			( pin "J6U1.24"
				( objectStatus "@baseboard_fab2_lib.baseboard_fab2(sch_1):page46_i138:vss(83)" )
			)
			( pin "J6U1.22"
				( objectStatus "@baseboard_fab2_lib.baseboard_fab2(sch_1):page46_i138:vss(84)" )
			)
			( pin "J6U1.20"
				( objectStatus "@baseboard_fab2_lib.baseboard_fab2(sch_1):page46_i138:vss(85)" )
			)
			( pin "J6U1.17"
				( objectStatus "@baseboard_fab2_lib.baseboard_fab2(sch_1):page46_i138:vss(86)" )
			)
			( pin "J6U1.15"
				( objectStatus "@baseboard_fab2_lib.baseboard_fab2(sch_1):page46_i138:vss(87)" )
			)
			( pin "J6U1.13"
				( objectStatus "@baseboard_fab2_lib.baseboard_fab2(sch_1):page46_i138:vss(88)" )
			)
			( pin "J6U1.11"
				( objectStatus "@baseboard_fab2_lib.baseboard_fab2(sch_1):page46_i138:vss(89)" )
			)
			( pin "J6U1.9"
				( objectStatus "@baseboard_fab2_lib.baseboard_fab2(sch_1):page46_i138:vss(90)" )
			)
			( pin "J6U1.6"
				( objectStatus "@baseboard_fab2_lib.baseboard_fab2(sch_1):page46_i138:vss(91)" )
			)
			( pin "J6U1.4"
				( objectStatus "@baseboard_fab2_lib.baseboard_fab2(sch_1):page46_i138:vss(92)" )
			)
			( pin "J6U1.2"
				( objectStatus "@baseboard_fab2_lib.baseboard_fab2(sch_1):page46_i138:vss(93)" )
			)
			( pin "J4G3.283"
				( objectStatus "@baseboard_fab2_lib.baseboard_fab2(sch_1):page47_i43:vss(0)" )
			)
			( pin "J4G3.281"
				( objectStatus "@baseboard_fab2_lib.baseboard_fab2(sch_1):page47_i43:vss(1)" )
			)
			( pin "J4G3.279"
				( objectStatus "@baseboard_fab2_lib.baseboard_fab2(sch_1):page47_i43:vss(2)" )
			)
			( pin "J4G3.276"
				( objectStatus "@baseboard_fab2_lib.baseboard_fab2(sch_1):page47_i43:vss(3)" )
			)
			( pin "J4G3.274"
				( objectStatus "@baseboard_fab2_lib.baseboard_fab2(sch_1):page47_i43:vss(4)" )
			)
			( pin "J4G3.272"
				( objectStatus "@baseboard_fab2_lib.baseboard_fab2(sch_1):page47_i43:vss(5)" )
			)
			( pin "J4G3.270"
				( objectStatus "@baseboard_fab2_lib.baseboard_fab2(sch_1):page47_i43:vss(6)" )
			)
			( pin "J4G3.268"
				( objectStatus "@baseboard_fab2_lib.baseboard_fab2(sch_1):page47_i43:vss(7)" )
			)
			( pin "J4G3.265"
				( objectStatus "@baseboard_fab2_lib.baseboard_fab2(sch_1):page47_i43:vss(8)" )
			)
			( pin "J4G3.263"
				( objectStatus "@baseboard_fab2_lib.baseboard_fab2(sch_1):page47_i43:vss(9)" )
			)
			( pin "J4G3.261"
				( objectStatus "@baseboard_fab2_lib.baseboard_fab2(sch_1):page47_i43:vss(10)" )
			)
			( pin "J4G3.259"
				( objectStatus "@baseboard_fab2_lib.baseboard_fab2(sch_1):page47_i43:vss(11)" )
			)
			( pin "J4G3.257"
				( objectStatus "@baseboard_fab2_lib.baseboard_fab2(sch_1):page47_i43:vss(12)" )
			)
			( pin "J4G3.254"
				( objectStatus "@baseboard_fab2_lib.baseboard_fab2(sch_1):page47_i43:vss(13)" )
			)
			( pin "J4G3.252"
				( objectStatus "@baseboard_fab2_lib.baseboard_fab2(sch_1):page47_i43:vss(14)" )
			)
			( pin "J4G3.250"
				( objectStatus "@baseboard_fab2_lib.baseboard_fab2(sch_1):page47_i43:vss(15)" )
			)
			( pin "J4G3.248"
				( objectStatus "@baseboard_fab2_lib.baseboard_fab2(sch_1):page47_i43:vss(16)" )
			)
			( pin "J4G3.246"
				( objectStatus "@baseboard_fab2_lib.baseboard_fab2(sch_1):page47_i43:vss(17)" )
			)
			( pin "J4G3.243"
				( objectStatus "@baseboard_fab2_lib.baseboard_fab2(sch_1):page47_i43:vss(18)" )
			)
			( pin "J4G3.241"
				( objectStatus "@baseboard_fab2_lib.baseboard_fab2(sch_1):page47_i43:vss(19)" )
			)
			( pin "J4G3.239"
				( objectStatus "@baseboard_fab2_lib.baseboard_fab2(sch_1):page47_i43:vss(20)" )
			)
			( pin "J4G3.202"
				( objectStatus "@baseboard_fab2_lib.baseboard_fab2(sch_1):page47_i43:vss(21)" )
			)
			( pin "J4G3.200"
				( objectStatus "@baseboard_fab2_lib.baseboard_fab2(sch_1):page47_i43:vss(22)" )
			)
			( pin "J4G3.198"
				( objectStatus "@baseboard_fab2_lib.baseboard_fab2(sch_1):page47_i43:vss(23)" )
			)
			( pin "J4G3.195"
				( objectStatus "@baseboard_fab2_lib.baseboard_fab2(sch_1):page47_i43:vss(24)" )
			)
			( pin "J4G3.193"
				( objectStatus "@baseboard_fab2_lib.baseboard_fab2(sch_1):page47_i43:vss(25)" )
			)
			( pin "J4G3.191"
				( objectStatus "@baseboard_fab2_lib.baseboard_fab2(sch_1):page47_i43:vss(26)" )
			)
			( pin "J4G3.189"
				( objectStatus "@baseboard_fab2_lib.baseboard_fab2(sch_1):page47_i43:vss(27)" )
			)
			( pin "J4G3.187"
				( objectStatus "@baseboard_fab2_lib.baseboard_fab2(sch_1):page47_i43:vss(28)" )
			)
			( pin "J4G3.184"
				( objectStatus "@baseboard_fab2_lib.baseboard_fab2(sch_1):page47_i43:vss(29)" )
			)
			( pin "J4G3.182"
				( objectStatus "@baseboard_fab2_lib.baseboard_fab2(sch_1):page47_i43:vss(30)" )
			)
			( pin "J4G3.180"
				( objectStatus "@baseboard_fab2_lib.baseboard_fab2(sch_1):page47_i43:vss(31)" )
			)
			( pin "J4G3.178"
				( objectStatus "@baseboard_fab2_lib.baseboard_fab2(sch_1):page47_i43:vss(32)" )
			)
			( pin "J4G3.176"
				( objectStatus "@baseboard_fab2_lib.baseboard_fab2(sch_1):page47_i43:vss(33)" )
			)
			( pin "J4G3.173"
				( objectStatus "@baseboard_fab2_lib.baseboard_fab2(sch_1):page47_i43:vss(34)" )
			)
			( pin "J4G3.171"
				( objectStatus "@baseboard_fab2_lib.baseboard_fab2(sch_1):page47_i43:vss(35)" )
			)
			( pin "J4G3.169"
				( objectStatus "@baseboard_fab2_lib.baseboard_fab2(sch_1):page47_i43:vss(36)" )
			)
			( pin "J4G3.167"
				( objectStatus "@baseboard_fab2_lib.baseboard_fab2(sch_1):page47_i43:vss(37)" )
			)
			( pin "J4G3.165"
				( objectStatus "@baseboard_fab2_lib.baseboard_fab2(sch_1):page47_i43:vss(38)" )
			)
			( pin "J4G3.162"
				( objectStatus "@baseboard_fab2_lib.baseboard_fab2(sch_1):page47_i43:vss(39)" )
			)
			( pin "J4G3.160"
				( objectStatus "@baseboard_fab2_lib.baseboard_fab2(sch_1):page47_i43:vss(40)" )
			)
			( pin "J4G3.158"
				( objectStatus "@baseboard_fab2_lib.baseboard_fab2(sch_1):page47_i43:vss(41)" )
			)
			( pin "J4G3.156"
				( objectStatus "@baseboard_fab2_lib.baseboard_fab2(sch_1):page47_i43:vss(42)" )
			)
			( pin "J4G3.154"
				( objectStatus "@baseboard_fab2_lib.baseboard_fab2(sch_1):page47_i43:vss(43)" )
			)
			( pin "J4G3.151"
				( objectStatus "@baseboard_fab2_lib.baseboard_fab2(sch_1):page47_i43:vss(44)" )
			)
			( pin "J4G3.149"
				( objectStatus "@baseboard_fab2_lib.baseboard_fab2(sch_1):page47_i43:vss(45)" )
			)
			( pin "J4G3.147"
				( objectStatus "@baseboard_fab2_lib.baseboard_fab2(sch_1):page47_i43:vss(46)" )
			)
			( pin "J4G3.138"
				( objectStatus "@baseboard_fab2_lib.baseboard_fab2(sch_1):page47_i43:vss(47)" )
			)
			( pin "J4G3.136"
				( objectStatus "@baseboard_fab2_lib.baseboard_fab2(sch_1):page47_i43:vss(48)" )
			)
			( pin "J4G3.134"
				( objectStatus "@baseboard_fab2_lib.baseboard_fab2(sch_1):page47_i43:vss(49)" )
			)
			( pin "J4G3.131"
				( objectStatus "@baseboard_fab2_lib.baseboard_fab2(sch_1):page47_i43:vss(50)" )
			)
			( pin "J4G3.129"
				( objectStatus "@baseboard_fab2_lib.baseboard_fab2(sch_1):page47_i43:vss(51)" )
			)
			( pin "J4G3.127"
				( objectStatus "@baseboard_fab2_lib.baseboard_fab2(sch_1):page47_i43:vss(52)" )
			)
			( pin "J4G3.125"
				( objectStatus "@baseboard_fab2_lib.baseboard_fab2(sch_1):page47_i43:vss(53)" )
			)
			( pin "J4G3.123"
				( objectStatus "@baseboard_fab2_lib.baseboard_fab2(sch_1):page47_i43:vss(54)" )
			)
			( pin "J4G3.120"
				( objectStatus "@baseboard_fab2_lib.baseboard_fab2(sch_1):page47_i43:vss(55)" )
			)
			( pin "J4G3.118"
				( objectStatus "@baseboard_fab2_lib.baseboard_fab2(sch_1):page47_i43:vss(56)" )
			)
			( pin "J4G3.116"
				( objectStatus "@baseboard_fab2_lib.baseboard_fab2(sch_1):page47_i43:vss(57)" )
			)
			( pin "J4G3.114"
				( objectStatus "@baseboard_fab2_lib.baseboard_fab2(sch_1):page47_i43:vss(58)" )
			)
			( pin "J4G3.112"
				( objectStatus "@baseboard_fab2_lib.baseboard_fab2(sch_1):page47_i43:vss(59)" )
			)
			( pin "J4G3.109"
				( objectStatus "@baseboard_fab2_lib.baseboard_fab2(sch_1):page47_i43:vss(60)" )
			)
			( pin "J4G3.107"
				( objectStatus "@baseboard_fab2_lib.baseboard_fab2(sch_1):page47_i43:vss(61)" )
			)
			( pin "J4G3.105"
				( objectStatus "@baseboard_fab2_lib.baseboard_fab2(sch_1):page47_i43:vss(62)" )
			)
			( pin "J4G3.103"
				( objectStatus "@baseboard_fab2_lib.baseboard_fab2(sch_1):page47_i43:vss(63)" )
			)
			( pin "J4G3.101"
				( objectStatus "@baseboard_fab2_lib.baseboard_fab2(sch_1):page47_i43:vss(64)" )
			)
			( pin "J4G3.98"
				( objectStatus "@baseboard_fab2_lib.baseboard_fab2(sch_1):page47_i43:vss(65)" )
			)
			( pin "J4G3.96"
				( objectStatus "@baseboard_fab2_lib.baseboard_fab2(sch_1):page47_i43:vss(66)" )
			)
			( pin "J4G3.94"
				( objectStatus "@baseboard_fab2_lib.baseboard_fab2(sch_1):page47_i43:vss(67)" )
			)
			( pin "J4G3.57"
				( objectStatus "@baseboard_fab2_lib.baseboard_fab2(sch_1):page47_i43:vss(68)" )
			)
			( pin "J4G3.55"
				( objectStatus "@baseboard_fab2_lib.baseboard_fab2(sch_1):page47_i43:vss(69)" )
			)
			( pin "J4G3.53"
				( objectStatus "@baseboard_fab2_lib.baseboard_fab2(sch_1):page47_i43:vss(70)" )
			)
			( pin "J4G3.50"
				( objectStatus "@baseboard_fab2_lib.baseboard_fab2(sch_1):page47_i43:vss(71)" )
			)
			( pin "J4G3.48"
				( objectStatus "@baseboard_fab2_lib.baseboard_fab2(sch_1):page47_i43:vss(72)" )
			)
			( pin "J4G3.46"
				( objectStatus "@baseboard_fab2_lib.baseboard_fab2(sch_1):page47_i43:vss(73)" )
			)
			( pin "J4G3.44"
				( objectStatus "@baseboard_fab2_lib.baseboard_fab2(sch_1):page47_i43:vss(74)" )
			)
			( pin "J4G3.42"
				( objectStatus "@baseboard_fab2_lib.baseboard_fab2(sch_1):page47_i43:vss(75)" )
			)
			( pin "J4G3.39"
				( objectStatus "@baseboard_fab2_lib.baseboard_fab2(sch_1):page47_i43:vss(76)" )
			)
			( pin "J4G3.37"
				( objectStatus "@baseboard_fab2_lib.baseboard_fab2(sch_1):page47_i43:vss(77)" )
			)
			( pin "J4G3.35"
				( objectStatus "@baseboard_fab2_lib.baseboard_fab2(sch_1):page47_i43:vss(78)" )
			)
			( pin "J4G3.33"
				( objectStatus "@baseboard_fab2_lib.baseboard_fab2(sch_1):page47_i43:vss(79)" )
			)
			( pin "J4G3.31"
				( objectStatus "@baseboard_fab2_lib.baseboard_fab2(sch_1):page47_i43:vss(80)" )
			)
			( pin "J4G3.28"
				( objectStatus "@baseboard_fab2_lib.baseboard_fab2(sch_1):page47_i43:vss(81)" )
			)
			( pin "J4G3.26"
				( objectStatus "@baseboard_fab2_lib.baseboard_fab2(sch_1):page47_i43:vss(82)" )
			)
			( pin "J4G3.24"
				( objectStatus "@baseboard_fab2_lib.baseboard_fab2(sch_1):page47_i43:vss(83)" )
			)
			( pin "J4G3.22"
				( objectStatus "@baseboard_fab2_lib.baseboard_fab2(sch_1):page47_i43:vss(84)" )
			)
			( pin "J4G3.20"
				( objectStatus "@baseboard_fab2_lib.baseboard_fab2(sch_1):page47_i43:vss(85)" )
			)
			( pin "J4G3.17"
				( objectStatus "@baseboard_fab2_lib.baseboard_fab2(sch_1):page47_i43:vss(86)" )
			)
			( pin "J4G3.15"
				( objectStatus "@baseboard_fab2_lib.baseboard_fab2(sch_1):page47_i43:vss(87)" )
			)
			( pin "J4G3.13"
				( objectStatus "@baseboard_fab2_lib.baseboard_fab2(sch_1):page47_i43:vss(88)" )
			)
			( pin "J4G3.11"
				( objectStatus "@baseboard_fab2_lib.baseboard_fab2(sch_1):page47_i43:vss(89)" )
			)
			( pin "J4G3.9"
				( objectStatus "@baseboard_fab2_lib.baseboard_fab2(sch_1):page47_i43:vss(90)" )
			)
			( pin "J4G3.6"
				( objectStatus "@baseboard_fab2_lib.baseboard_fab2(sch_1):page47_i43:vss(91)" )
			)
			( pin "J4G3.4"
				( objectStatus "@baseboard_fab2_lib.baseboard_fab2(sch_1):page47_i43:vss(92)" )
			)
			( pin "J4G3.2"
				( objectStatus "@baseboard_fab2_lib.baseboard_fab2(sch_1):page47_i43:vss(93)" )
			)
			( pin "J4G3.152"
				( objectStatus "@baseboard_fab2_lib.baseboard_fab2(sch_1):page47_i61:dqs0n" )
			)
			( pin "J4G3.153"
				( objectStatus "@baseboard_fab2_lib.baseboard_fab2(sch_1):page47_i61:dqs0p" )
			)
			( pin "J4G3.163"
				( objectStatus "@baseboard_fab2_lib.baseboard_fab2(sch_1):page47_i61:dqs1n" )
			)
			( pin "J4G3.164"
				( objectStatus "@baseboard_fab2_lib.baseboard_fab2(sch_1):page47_i61:dqs1p" )
			)
			( pin "J4G3.174"
				( objectStatus "@baseboard_fab2_lib.baseboard_fab2(sch_1):page47_i61:dqs2n" )
			)
			( pin "J4G3.175"
				( objectStatus "@baseboard_fab2_lib.baseboard_fab2(sch_1):page47_i61:dqs2p" )
			)
			( pin "J4G3.185"
				( objectStatus "@baseboard_fab2_lib.baseboard_fab2(sch_1):page47_i61:dqs3n" )
			)
			( pin "J4G3.186"
				( objectStatus "@baseboard_fab2_lib.baseboard_fab2(sch_1):page47_i61:dqs3p" )
			)
			( pin "J4G3.244"
				( objectStatus "@baseboard_fab2_lib.baseboard_fab2(sch_1):page47_i61:dqs4n" )
			)
			( pin "J4G3.245"
				( objectStatus "@baseboard_fab2_lib.baseboard_fab2(sch_1):page47_i61:dqs4p" )
			)
			( pin "J4G3.255"
				( objectStatus "@baseboard_fab2_lib.baseboard_fab2(sch_1):page47_i61:dqs5n" )
			)
			( pin "J4G3.256"
				( objectStatus "@baseboard_fab2_lib.baseboard_fab2(sch_1):page47_i61:dqs5p" )
			)
			( pin "J4G3.266"
				( objectStatus "@baseboard_fab2_lib.baseboard_fab2(sch_1):page47_i61:dqs6n" )
			)
			( pin "J4G3.267"
				( objectStatus "@baseboard_fab2_lib.baseboard_fab2(sch_1):page47_i61:dqs6p" )
			)
			( pin "J4G3.277"
				( objectStatus "@baseboard_fab2_lib.baseboard_fab2(sch_1):page47_i61:dqs7n" )
			)
			( pin "J4G3.278"
				( objectStatus "@baseboard_fab2_lib.baseboard_fab2(sch_1):page47_i61:dqs7p" )
			)
			( pin "J4G3.196"
				( objectStatus "@baseboard_fab2_lib.baseboard_fab2(sch_1):page47_i61:dqs8n" )
			)
			( pin "J4G3.197"
				( objectStatus "@baseboard_fab2_lib.baseboard_fab2(sch_1):page47_i61:dqs8p" )
			)
			( pin "J4G3.8"
				( objectStatus "@baseboard_fab2_lib.baseboard_fab2(sch_1):page47_i61:dqs9n" )
			)
			( pin "J4G3.7"
				( objectStatus "@baseboard_fab2_lib.baseboard_fab2(sch_1):page47_i61:dqs9p" )
			)
			( pin "J4G3.19"
				( objectStatus "@baseboard_fab2_lib.baseboard_fab2(sch_1):page47_i61:dqs10n" )
			)
			( pin "J4G3.18"
				( objectStatus "@baseboard_fab2_lib.baseboard_fab2(sch_1):page47_i61:dqs10p" )
			)
			( pin "J4G3.30"
				( objectStatus "@baseboard_fab2_lib.baseboard_fab2(sch_1):page47_i61:dqs11n" )
			)
			( pin "J4G3.29"
				( objectStatus "@baseboard_fab2_lib.baseboard_fab2(sch_1):page47_i61:dqs11p" )
			)
			( pin "J4G3.41"
				( objectStatus "@baseboard_fab2_lib.baseboard_fab2(sch_1):page47_i61:dqs12n" )
			)
			( pin "J4G3.40"
				( objectStatus "@baseboard_fab2_lib.baseboard_fab2(sch_1):page47_i61:dqs12p" )
			)
			( pin "J4G3.100"
				( objectStatus "@baseboard_fab2_lib.baseboard_fab2(sch_1):page47_i61:dqs13n" )
			)
			( pin "J4G3.99"
				( objectStatus "@baseboard_fab2_lib.baseboard_fab2(sch_1):page47_i61:dqs13p" )
			)
			( pin "J4G3.111"
				( objectStatus "@baseboard_fab2_lib.baseboard_fab2(sch_1):page47_i61:dqs14n" )
			)
			( pin "J4G3.110"
				( objectStatus "@baseboard_fab2_lib.baseboard_fab2(sch_1):page47_i61:dqs14p" )
			)
			( pin "J4G3.122"
				( objectStatus "@baseboard_fab2_lib.baseboard_fab2(sch_1):page47_i61:dqs15n" )
			)
			( pin "J4G3.121"
				( objectStatus "@baseboard_fab2_lib.baseboard_fab2(sch_1):page47_i61:dqs15p" )
			)
			( pin "J4G3.133"
				( objectStatus "@baseboard_fab2_lib.baseboard_fab2(sch_1):page47_i61:dqs16n" )
			)
			( pin "J4G3.132"
				( objectStatus "@baseboard_fab2_lib.baseboard_fab2(sch_1):page47_i61:dqs16p" )
			)
			( pin "J4G3.52"
				( objectStatus "@baseboard_fab2_lib.baseboard_fab2(sch_1):page47_i61:dqs17n" )
			)
			( pin "J4G3.51"
				( objectStatus "@baseboard_fab2_lib.baseboard_fab2(sch_1):page47_i61:dqs17p" )
			)
			( pin "J4G3.79"
				( objectStatus "@baseboard_fab2_lib.baseboard_fab2(sch_1):page47_i111:a0" )
			)
			( pin "J4G3.72"
				( objectStatus "@baseboard_fab2_lib.baseboard_fab2(sch_1):page47_i111:a1" )
			)
			( pin "J4G3.216"
				( objectStatus "@baseboard_fab2_lib.baseboard_fab2(sch_1):page47_i111:a2" )
			)
			( pin "J4G3.71"
				( objectStatus "@baseboard_fab2_lib.baseboard_fab2(sch_1):page47_i111:a3" )
			)
			( pin "J4G3.214"
				( objectStatus "@baseboard_fab2_lib.baseboard_fab2(sch_1):page47_i111:a4" )
			)
			( pin "J4G3.213"
				( objectStatus "@baseboard_fab2_lib.baseboard_fab2(sch_1):page47_i111:a5" )
			)
			( pin "J4G3.69"
				( objectStatus "@baseboard_fab2_lib.baseboard_fab2(sch_1):page47_i111:a6" )
			)
			( pin "J4G3.211"
				( objectStatus "@baseboard_fab2_lib.baseboard_fab2(sch_1):page47_i111:a7" )
			)
			( pin "J4G3.68"
				( objectStatus "@baseboard_fab2_lib.baseboard_fab2(sch_1):page47_i111:a8" )
			)
			( pin "J4G3.66"
				( objectStatus "@baseboard_fab2_lib.baseboard_fab2(sch_1):page47_i111:a9" )
			)
			( pin "J4G3.225"
				( objectStatus "@baseboard_fab2_lib.baseboard_fab2(sch_1):page47_i111:a10" )
			)
			( pin "J4G3.210"
				( objectStatus "@baseboard_fab2_lib.baseboard_fab2(sch_1):page47_i111:a11" )
			)
			( pin "J4G3.65"
				( objectStatus "@baseboard_fab2_lib.baseboard_fab2(sch_1):page47_i111:a12" )
			)
			( pin "J4G3.232"
				( objectStatus "@baseboard_fab2_lib.baseboard_fab2(sch_1):page47_i111:a13" )
			)
			( pin "J4G3.228"
				( objectStatus "@baseboard_fab2_lib.baseboard_fab2(sch_1):page47_i111:a14_we_n" )
			)
			( pin "J4G3.86"
				( objectStatus "@baseboard_fab2_lib.baseboard_fab2(sch_1):page47_i111:a15_cas_n" )
			)
			( pin "J4G3.82"
				( objectStatus "@baseboard_fab2_lib.baseboard_fab2(sch_1):page47_i111:a16_ras_n" )
			)
			( pin "J4G3.234"
				( objectStatus "@baseboard_fab2_lib.baseboard_fab2(sch_1):page47_i111:a17" )
			)
			( pin "J4G3.62"
				( objectStatus "@baseboard_fab2_lib.baseboard_fab2(sch_1):page47_i111:act_n" )
			)
			( pin "J4G3.208"
				( objectStatus "@baseboard_fab2_lib.baseboard_fab2(sch_1):page47_i111:alert_n" )
			)
			( pin "J4G3.81"
				( objectStatus "@baseboard_fab2_lib.baseboard_fab2(sch_1):page47_i111:ba(0)" )
			)
			( pin "J4G3.224"
				( objectStatus "@baseboard_fab2_lib.baseboard_fab2(sch_1):page47_i111:ba(1)" )
			)
			( pin "J4G3.63"
				( objectStatus "@baseboard_fab2_lib.baseboard_fab2(sch_1):page47_i111:bg(0)" )
			)
			( pin "J4G3.207"
				( objectStatus "@baseboard_fab2_lib.baseboard_fab2(sch_1):page47_i111:bg(1)" )
			)
			( pin "J4G3.235"
				( objectStatus "@baseboard_fab2_lib.baseboard_fab2(sch_1):page47_i111:c(2)" )
			)
			( pin "J4G3.49"
				( objectStatus "@baseboard_fab2_lib.baseboard_fab2(sch_1):page47_i111:cb(0)" )
			)
			( pin "J4G3.194"
				( objectStatus "@baseboard_fab2_lib.baseboard_fab2(sch_1):page47_i111:cb(1)" )
			)
			( pin "J4G3.56"
				( objectStatus "@baseboard_fab2_lib.baseboard_fab2(sch_1):page47_i111:cb(2)" )
			)
			( pin "J4G3.201"
				( objectStatus "@baseboard_fab2_lib.baseboard_fab2(sch_1):page47_i111:cb(3)" )
			)
			( pin "J4G3.47"
				( objectStatus "@baseboard_fab2_lib.baseboard_fab2(sch_1):page47_i111:cb(4)" )
			)
			( pin "J4G3.192"
				( objectStatus "@baseboard_fab2_lib.baseboard_fab2(sch_1):page47_i111:cb(5)" )
			)
			( pin "J4G3.54"
				( objectStatus "@baseboard_fab2_lib.baseboard_fab2(sch_1):page47_i111:cb(6)" )
			)
			( pin "J4G3.199"
				( objectStatus "@baseboard_fab2_lib.baseboard_fab2(sch_1):page47_i111:cb(7)" )
			)
			( pin "J4G3.75"
				( objectStatus "@baseboard_fab2_lib.baseboard_fab2(sch_1):page47_i111:ck0n" )
			)
			( pin "J4G3.74"
				( objectStatus "@baseboard_fab2_lib.baseboard_fab2(sch_1):page47_i111:ck0p" )
			)
			( pin "J4G3.219"
				( objectStatus "@baseboard_fab2_lib.baseboard_fab2(sch_1):page47_i111:ck1n" )
			)
			( pin "J4G3.218"
				( objectStatus "@baseboard_fab2_lib.baseboard_fab2(sch_1):page47_i111:ck1p" )
			)
			( pin "J4G3.60"
				( objectStatus "@baseboard_fab2_lib.baseboard_fab2(sch_1):page47_i111:cke(0)" )
			)
			( pin "J4G3.203"
				( objectStatus "@baseboard_fab2_lib.baseboard_fab2(sch_1):page47_i111:cke(1)" )
			)
			( pin "J4G3.5"
				( objectStatus "@baseboard_fab2_lib.baseboard_fab2(sch_1):page47_i111:dq(0)" )
			)
			( pin "J4G3.150"
				( objectStatus "@baseboard_fab2_lib.baseboard_fab2(sch_1):page47_i111:dq(1)" )
			)
			( pin "J4G3.12"
				( objectStatus "@baseboard_fab2_lib.baseboard_fab2(sch_1):page47_i111:dq(2)" )
			)
			( pin "J4G3.157"
				( objectStatus "@baseboard_fab2_lib.baseboard_fab2(sch_1):page47_i111:dq(3)" )
			)
			( pin "J4G3.3"
				( objectStatus "@baseboard_fab2_lib.baseboard_fab2(sch_1):page47_i111:dq(4)" )
			)
			( pin "J4G3.148"
				( objectStatus "@baseboard_fab2_lib.baseboard_fab2(sch_1):page47_i111:dq(5)" )
			)
			( pin "J4G3.10"
				( objectStatus "@baseboard_fab2_lib.baseboard_fab2(sch_1):page47_i111:dq(6)" )
			)
			( pin "J4G3.155"
				( objectStatus "@baseboard_fab2_lib.baseboard_fab2(sch_1):page47_i111:dq(7)" )
			)
			( pin "J4G3.16"
				( objectStatus "@baseboard_fab2_lib.baseboard_fab2(sch_1):page47_i111:dq(8)" )
			)
			( pin "J4G3.161"
				( objectStatus "@baseboard_fab2_lib.baseboard_fab2(sch_1):page47_i111:dq(9)" )
			)
			( pin "J4G3.23"
				( objectStatus "@baseboard_fab2_lib.baseboard_fab2(sch_1):page47_i111:dq(10)" )
			)
			( pin "J4G3.168"
				( objectStatus "@baseboard_fab2_lib.baseboard_fab2(sch_1):page47_i111:dq(11)" )
			)
			( pin "J4G3.14"
				( objectStatus "@baseboard_fab2_lib.baseboard_fab2(sch_1):page47_i111:dq(12)" )
			)
			( pin "J4G3.159"
				( objectStatus "@baseboard_fab2_lib.baseboard_fab2(sch_1):page47_i111:dq(13)" )
			)
			( pin "J4G3.21"
				( objectStatus "@baseboard_fab2_lib.baseboard_fab2(sch_1):page47_i111:dq(14)" )
			)
			( pin "J4G3.166"
				( objectStatus "@baseboard_fab2_lib.baseboard_fab2(sch_1):page47_i111:dq(15)" )
			)
			( pin "J4G3.27"
				( objectStatus "@baseboard_fab2_lib.baseboard_fab2(sch_1):page47_i111:dq(16)" )
			)
			( pin "J4G3.172"
				( objectStatus "@baseboard_fab2_lib.baseboard_fab2(sch_1):page47_i111:dq(17)" )
			)
			( pin "J4G3.34"
				( objectStatus "@baseboard_fab2_lib.baseboard_fab2(sch_1):page47_i111:dq(18)" )
			)
			( pin "J4G3.179"
				( objectStatus "@baseboard_fab2_lib.baseboard_fab2(sch_1):page47_i111:dq(19)" )
			)
			( pin "J4G3.25"
				( objectStatus "@baseboard_fab2_lib.baseboard_fab2(sch_1):page47_i111:dq(20)" )
			)
			( pin "J4G3.170"
				( objectStatus "@baseboard_fab2_lib.baseboard_fab2(sch_1):page47_i111:dq(21)" )
			)
			( pin "J4G3.32"
				( objectStatus "@baseboard_fab2_lib.baseboard_fab2(sch_1):page47_i111:dq(22)" )
			)
			( pin "J4G3.177"
				( objectStatus "@baseboard_fab2_lib.baseboard_fab2(sch_1):page47_i111:dq(23)" )
			)
			( pin "J4G3.38"
				( objectStatus "@baseboard_fab2_lib.baseboard_fab2(sch_1):page47_i111:dq(24)" )
			)
			( pin "J4G3.183"
				( objectStatus "@baseboard_fab2_lib.baseboard_fab2(sch_1):page47_i111:dq(25)" )
			)
			( pin "J4G3.45"
				( objectStatus "@baseboard_fab2_lib.baseboard_fab2(sch_1):page47_i111:dq(26)" )
			)
			( pin "J4G3.190"
				( objectStatus "@baseboard_fab2_lib.baseboard_fab2(sch_1):page47_i111:dq(27)" )
			)
			( pin "J4G3.36"
				( objectStatus "@baseboard_fab2_lib.baseboard_fab2(sch_1):page47_i111:dq(28)" )
			)
			( pin "J4G3.181"
				( objectStatus "@baseboard_fab2_lib.baseboard_fab2(sch_1):page47_i111:dq(29)" )
			)
			( pin "J4G3.43"
				( objectStatus "@baseboard_fab2_lib.baseboard_fab2(sch_1):page47_i111:dq(30)" )
			)
			( pin "J4G3.188"
				( objectStatus "@baseboard_fab2_lib.baseboard_fab2(sch_1):page47_i111:dq(31)" )
			)
			( pin "J4G3.97"
				( objectStatus "@baseboard_fab2_lib.baseboard_fab2(sch_1):page47_i111:dq(32)" )
			)
			( pin "J4G3.242"
				( objectStatus "@baseboard_fab2_lib.baseboard_fab2(sch_1):page47_i111:dq(33)" )
			)
			( pin "J4G3.104"
				( objectStatus "@baseboard_fab2_lib.baseboard_fab2(sch_1):page47_i111:dq(34)" )
			)
			( pin "J4G3.249"
				( objectStatus "@baseboard_fab2_lib.baseboard_fab2(sch_1):page47_i111:dq(35)" )
			)
			( pin "J4G3.95"
				( objectStatus "@baseboard_fab2_lib.baseboard_fab2(sch_1):page47_i111:dq(36)" )
			)
			( pin "J4G3.240"
				( objectStatus "@baseboard_fab2_lib.baseboard_fab2(sch_1):page47_i111:dq(37)" )
			)
			( pin "J4G3.102"
				( objectStatus "@baseboard_fab2_lib.baseboard_fab2(sch_1):page47_i111:dq(38)" )
			)
			( pin "J4G3.247"
				( objectStatus "@baseboard_fab2_lib.baseboard_fab2(sch_1):page47_i111:dq(39)" )
			)
			( pin "J4G3.108"
				( objectStatus "@baseboard_fab2_lib.baseboard_fab2(sch_1):page47_i111:dq(40)" )
			)
			( pin "J4G3.253"
				( objectStatus "@baseboard_fab2_lib.baseboard_fab2(sch_1):page47_i111:dq(41)" )
			)
			( pin "J4G3.115"
				( objectStatus "@baseboard_fab2_lib.baseboard_fab2(sch_1):page47_i111:dq(42)" )
			)
			( pin "J4G3.260"
				( objectStatus "@baseboard_fab2_lib.baseboard_fab2(sch_1):page47_i111:dq(43)" )
			)
			( pin "J4G3.106"
				( objectStatus "@baseboard_fab2_lib.baseboard_fab2(sch_1):page47_i111:dq(44)" )
			)
			( pin "J4G3.251"
				( objectStatus "@baseboard_fab2_lib.baseboard_fab2(sch_1):page47_i111:dq(45)" )
			)
			( pin "J4G3.113"
				( objectStatus "@baseboard_fab2_lib.baseboard_fab2(sch_1):page47_i111:dq(46)" )
			)
			( pin "J4G3.258"
				( objectStatus "@baseboard_fab2_lib.baseboard_fab2(sch_1):page47_i111:dq(47)" )
			)
			( pin "J4G3.119"
				( objectStatus "@baseboard_fab2_lib.baseboard_fab2(sch_1):page47_i111:dq(48)" )
			)
			( pin "J4G3.264"
				( objectStatus "@baseboard_fab2_lib.baseboard_fab2(sch_1):page47_i111:dq(49)" )
			)
			( pin "J4G3.126"
				( objectStatus "@baseboard_fab2_lib.baseboard_fab2(sch_1):page47_i111:dq(50)" )
			)
			( pin "J4G3.271"
				( objectStatus "@baseboard_fab2_lib.baseboard_fab2(sch_1):page47_i111:dq(51)" )
			)
			( pin "J4G3.117"
				( objectStatus "@baseboard_fab2_lib.baseboard_fab2(sch_1):page47_i111:dq(52)" )
			)
			( pin "J4G3.262"
				( objectStatus "@baseboard_fab2_lib.baseboard_fab2(sch_1):page47_i111:dq(53)" )
			)
			( pin "J4G3.124"
				( objectStatus "@baseboard_fab2_lib.baseboard_fab2(sch_1):page47_i111:dq(54)" )
			)
			( pin "J4G3.269"
				( objectStatus "@baseboard_fab2_lib.baseboard_fab2(sch_1):page47_i111:dq(55)" )
			)
			( pin "J4G3.130"
				( objectStatus "@baseboard_fab2_lib.baseboard_fab2(sch_1):page47_i111:dq(56)" )
			)
			( pin "J4G3.275"
				( objectStatus "@baseboard_fab2_lib.baseboard_fab2(sch_1):page47_i111:dq(57)" )
			)
			( pin "J4G3.137"
				( objectStatus "@baseboard_fab2_lib.baseboard_fab2(sch_1):page47_i111:dq(58)" )
			)
			( pin "J4G3.282"
				( objectStatus "@baseboard_fab2_lib.baseboard_fab2(sch_1):page47_i111:dq(59)" )
			)
			( pin "J4G3.128"
				( objectStatus "@baseboard_fab2_lib.baseboard_fab2(sch_1):page47_i111:dq(60)" )
			)
			( pin "J4G3.273"
				( objectStatus "@baseboard_fab2_lib.baseboard_fab2(sch_1):page47_i111:dq(61)" )
			)
			( pin "J4G3.135"
				( objectStatus "@baseboard_fab2_lib.baseboard_fab2(sch_1):page47_i111:dq(62)" )
			)
			( pin "J4G3.280"
				( objectStatus "@baseboard_fab2_lib.baseboard_fab2(sch_1):page47_i111:dq(63)" )
			)
			( pin "J4G3.78"
				( objectStatus "@baseboard_fab2_lib.baseboard_fab2(sch_1):page47_i111:event_n" )
			)
			( pin "J4G3.87"
				( objectStatus "@baseboard_fab2_lib.baseboard_fab2(sch_1):page47_i111:odt(0)" )
			)
			( pin "J4G3.91"
				( objectStatus "@baseboard_fab2_lib.baseboard_fab2(sch_1):page47_i111:odt(1)" )
			)
			( pin "J4G3.222"
				( objectStatus "@baseboard_fab2_lib.baseboard_fab2(sch_1):page47_i111:par" )
			)
			( pin "J4G3.58"
				( objectStatus "@baseboard_fab2_lib.baseboard_fab2(sch_1):page47_i111:reset_n" )
			)
			( pin "J4G3.205"
				( objectStatus "@baseboard_fab2_lib.baseboard_fab2(sch_1):page47_i111:rfu(0)" )
			)
			( pin "J4G3.227"
				( objectStatus "@baseboard_fab2_lib.baseboard_fab2(sch_1):page47_i111:rfu(1)" )
			)
			( pin "J4G3.144"
				( objectStatus "@baseboard_fab2_lib.baseboard_fab2(sch_1):page47_i111:rfu(2)" )
			)
			( pin "J4G3.84"
				( objectStatus "@baseboard_fab2_lib.baseboard_fab2(sch_1):page47_i111:s0_n" )
			)
			( pin "J4G3.89"
				( objectStatus "@baseboard_fab2_lib.baseboard_fab2(sch_1):page47_i111:s1_n" )
			)
			( pin "J4G3.93"
				( objectStatus "@baseboard_fab2_lib.baseboard_fab2(sch_1):page47_i111:s2_n_c(0)" )
			)
			( pin "J4G3.237"
				( objectStatus "@baseboard_fab2_lib.baseboard_fab2(sch_1):page47_i111:s3_n_c(1)" )
			)
			( pin "J4G3.139"
				( objectStatus "@baseboard_fab2_lib.baseboard_fab2(sch_1):page47_i111:sa(0)" )
			)
			( pin "J4G3.140"
				( objectStatus "@baseboard_fab2_lib.baseboard_fab2(sch_1):page47_i111:sa(1)" )
			)
			( pin "J4G3.238"
				( objectStatus "@baseboard_fab2_lib.baseboard_fab2(sch_1):page47_i111:sa(2)" )
			)
			( pin "J4G3.230"
				( objectStatus "@baseboard_fab2_lib.baseboard_fab2(sch_1):page47_i111:save_n_nc" )
			)
			( pin "J4G3.141"
				( objectStatus "@baseboard_fab2_lib.baseboard_fab2(sch_1):page47_i111:scl" )
			)
			( pin "J4G3.285"
				( objectStatus "@baseboard_fab2_lib.baseboard_fab2(sch_1):page47_i111:sda" )
			)
			( pin "J4G3.284"
				( objectStatus "@baseboard_fab2_lib.baseboard_fab2(sch_1):page47_i111:vddspd" )
			)
			( pin "J4G3.146"
				( objectStatus "@baseboard_fab2_lib.baseboard_fab2(sch_1):page47_i111:vrefca" )
			)
			( pin "J4G3.145"
				( objectStatus "@baseboard_fab2_lib.baseboard_fab2(sch_1):page47_i179:\12v\(0)" )
			)
			( pin "J4G3.1"
				( objectStatus "@baseboard_fab2_lib.baseboard_fab2(sch_1):page47_i179:\12v\(1)" )
			)
			( pin "J4G3.236"
				( objectStatus "@baseboard_fab2_lib.baseboard_fab2(sch_1):page47_i179:vdd(0)" )
			)
			( pin "J4G3.233"
				( objectStatus "@baseboard_fab2_lib.baseboard_fab2(sch_1):page47_i179:vdd(1)" )
			)
			( pin "J4G3.231"
				( objectStatus "@baseboard_fab2_lib.baseboard_fab2(sch_1):page47_i179:vdd(2)" )
			)
			( pin "J4G3.229"
				( objectStatus "@baseboard_fab2_lib.baseboard_fab2(sch_1):page47_i179:vdd(3)" )
			)
			( pin "J4G3.226"
				( objectStatus "@baseboard_fab2_lib.baseboard_fab2(sch_1):page47_i179:vdd(4)" )
			)
			( pin "J4G3.223"
				( objectStatus "@baseboard_fab2_lib.baseboard_fab2(sch_1):page47_i179:vdd(5)" )
			)
			( pin "J4G3.220"
				( objectStatus "@baseboard_fab2_lib.baseboard_fab2(sch_1):page47_i179:vdd(6)" )
			)
			( pin "J4G3.217"
				( objectStatus "@baseboard_fab2_lib.baseboard_fab2(sch_1):page47_i179:vdd(7)" )
			)
			( pin "J4G3.215"
				( objectStatus "@baseboard_fab2_lib.baseboard_fab2(sch_1):page47_i179:vdd(8)" )
			)
			( pin "J4G3.212"
				( objectStatus "@baseboard_fab2_lib.baseboard_fab2(sch_1):page47_i179:vdd(9)" )
			)
			( pin "J4G3.209"
				( objectStatus "@baseboard_fab2_lib.baseboard_fab2(sch_1):page47_i179:vdd(10)" )
			)
			( pin "J4G3.206"
				( objectStatus "@baseboard_fab2_lib.baseboard_fab2(sch_1):page47_i179:vdd(11)" )
			)
			( pin "J4G3.204"
				( objectStatus "@baseboard_fab2_lib.baseboard_fab2(sch_1):page47_i179:vdd(12)" )
			)
			( pin "J4G3.92"
				( objectStatus "@baseboard_fab2_lib.baseboard_fab2(sch_1):page47_i179:vdd(13)" )
			)
			( pin "J4G3.90"
				( objectStatus "@baseboard_fab2_lib.baseboard_fab2(sch_1):page47_i179:vdd(14)" )
			)
			( pin "J4G3.88"
				( objectStatus "@baseboard_fab2_lib.baseboard_fab2(sch_1):page47_i179:vdd(15)" )
			)
			( pin "J4G3.85"
				( objectStatus "@baseboard_fab2_lib.baseboard_fab2(sch_1):page47_i179:vdd(16)" )
			)
			( pin "J4G3.83"
				( objectStatus "@baseboard_fab2_lib.baseboard_fab2(sch_1):page47_i179:vdd(17)" )
			)
			( pin "J4G3.80"
				( objectStatus "@baseboard_fab2_lib.baseboard_fab2(sch_1):page47_i179:vdd(18)" )
			)
			( pin "J4G3.76"
				( objectStatus "@baseboard_fab2_lib.baseboard_fab2(sch_1):page47_i179:vdd(19)" )
			)
			( pin "J4G3.73"
				( objectStatus "@baseboard_fab2_lib.baseboard_fab2(sch_1):page47_i179:vdd(20)" )
			)
			( pin "J4G3.70"
				( objectStatus "@baseboard_fab2_lib.baseboard_fab2(sch_1):page47_i179:vdd(21)" )
			)
			( pin "J4G3.67"
				( objectStatus "@baseboard_fab2_lib.baseboard_fab2(sch_1):page47_i179:vdd(22)" )
			)
			( pin "J4G3.64"
				( objectStatus "@baseboard_fab2_lib.baseboard_fab2(sch_1):page47_i179:vdd(23)" )
			)
			( pin "J4G3.61"
				( objectStatus "@baseboard_fab2_lib.baseboard_fab2(sch_1):page47_i179:vdd(24)" )
			)
			( pin "J4G3.59"
				( objectStatus "@baseboard_fab2_lib.baseboard_fab2(sch_1):page47_i179:vdd(25)" )
			)
			( pin "J4G3.287"
				( objectStatus "@baseboard_fab2_lib.baseboard_fab2(sch_1):page47_i179:vpp(0)" )
			)
			( pin "J4G3.286"
				( objectStatus "@baseboard_fab2_lib.baseboard_fab2(sch_1):page47_i179:vpp(1)" )
			)
			( pin "J4G3.288"
				( objectStatus "@baseboard_fab2_lib.baseboard_fab2(sch_1):page47_i179:vpp(2)" )
			)
			( pin "J4G3.143"
				( objectStatus "@baseboard_fab2_lib.baseboard_fab2(sch_1):page47_i179:vpp(3)" )
			)
			( pin "J4G3.142"
				( objectStatus "@baseboard_fab2_lib.baseboard_fab2(sch_1):page47_i179:vpp(4)" )
			)
			( pin "J4G3.221"
				( objectStatus "@baseboard_fab2_lib.baseboard_fab2(sch_1):page47_i179:vtt(0)" )
			)
			( pin "J4G3.77"
				( objectStatus "@baseboard_fab2_lib.baseboard_fab2(sch_1):page47_i179:vtt(1)" )
			)
			( pin "C4G19.1"
				( objectStatus "@baseboard_fab2_lib.baseboard_fab2(sch_1):page47_i188:a" )
			)
			( pin "C4G19.2"
				( objectStatus "@baseboard_fab2_lib.baseboard_fab2(sch_1):page47_i188:b" )
			)
			( pin "J6U2.283"
				( objectStatus "@baseboard_fab2_lib.baseboard_fab2(sch_1):page48_i43:vss(0)" )
			)
			( pin "J6U2.281"
				( objectStatus "@baseboard_fab2_lib.baseboard_fab2(sch_1):page48_i43:vss(1)" )
			)
			( pin "J6U2.279"
				( objectStatus "@baseboard_fab2_lib.baseboard_fab2(sch_1):page48_i43:vss(2)" )
			)
			( pin "J6U2.276"
				( objectStatus "@baseboard_fab2_lib.baseboard_fab2(sch_1):page48_i43:vss(3)" )
			)
			( pin "J6U2.274"
				( objectStatus "@baseboard_fab2_lib.baseboard_fab2(sch_1):page48_i43:vss(4)" )
			)
			( pin "J6U2.272"
				( objectStatus "@baseboard_fab2_lib.baseboard_fab2(sch_1):page48_i43:vss(5)" )
			)
			( pin "J6U2.270"
				( objectStatus "@baseboard_fab2_lib.baseboard_fab2(sch_1):page48_i43:vss(6)" )
			)
			( pin "J6U2.268"
				( objectStatus "@baseboard_fab2_lib.baseboard_fab2(sch_1):page48_i43:vss(7)" )
			)
			( pin "J6U2.265"
				( objectStatus "@baseboard_fab2_lib.baseboard_fab2(sch_1):page48_i43:vss(8)" )
			)
			( pin "J6U2.263"
				( objectStatus "@baseboard_fab2_lib.baseboard_fab2(sch_1):page48_i43:vss(9)" )
			)
			( pin "J6U2.261"
				( objectStatus "@baseboard_fab2_lib.baseboard_fab2(sch_1):page48_i43:vss(10)" )
			)
			( pin "J6U2.259"
				( objectStatus "@baseboard_fab2_lib.baseboard_fab2(sch_1):page48_i43:vss(11)" )
			)
			( pin "J6U2.257"
				( objectStatus "@baseboard_fab2_lib.baseboard_fab2(sch_1):page48_i43:vss(12)" )
			)
			( pin "J6U2.254"
				( objectStatus "@baseboard_fab2_lib.baseboard_fab2(sch_1):page48_i43:vss(13)" )
			)
			( pin "J6U2.252"
				( objectStatus "@baseboard_fab2_lib.baseboard_fab2(sch_1):page48_i43:vss(14)" )
			)
			( pin "J6U2.250"
				( objectStatus "@baseboard_fab2_lib.baseboard_fab2(sch_1):page48_i43:vss(15)" )
			)
			( pin "J6U2.248"
				( objectStatus "@baseboard_fab2_lib.baseboard_fab2(sch_1):page48_i43:vss(16)" )
			)
			( pin "J6U2.246"
				( objectStatus "@baseboard_fab2_lib.baseboard_fab2(sch_1):page48_i43:vss(17)" )
			)
			( pin "J6U2.243"
				( objectStatus "@baseboard_fab2_lib.baseboard_fab2(sch_1):page48_i43:vss(18)" )
			)
			( pin "J6U2.241"
				( objectStatus "@baseboard_fab2_lib.baseboard_fab2(sch_1):page48_i43:vss(19)" )
			)
			( pin "J6U2.239"
				( objectStatus "@baseboard_fab2_lib.baseboard_fab2(sch_1):page48_i43:vss(20)" )
			)
			( pin "J6U2.202"
				( objectStatus "@baseboard_fab2_lib.baseboard_fab2(sch_1):page48_i43:vss(21)" )
			)
			( pin "J6U2.200"
				( objectStatus "@baseboard_fab2_lib.baseboard_fab2(sch_1):page48_i43:vss(22)" )
			)
			( pin "J6U2.198"
				( objectStatus "@baseboard_fab2_lib.baseboard_fab2(sch_1):page48_i43:vss(23)" )
			)
			( pin "J6U2.195"
				( objectStatus "@baseboard_fab2_lib.baseboard_fab2(sch_1):page48_i43:vss(24)" )
			)
			( pin "J6U2.193"
				( objectStatus "@baseboard_fab2_lib.baseboard_fab2(sch_1):page48_i43:vss(25)" )
			)
			( pin "J6U2.191"
				( objectStatus "@baseboard_fab2_lib.baseboard_fab2(sch_1):page48_i43:vss(26)" )
			)
			( pin "J6U2.189"
				( objectStatus "@baseboard_fab2_lib.baseboard_fab2(sch_1):page48_i43:vss(27)" )
			)
			( pin "J6U2.187"
				( objectStatus "@baseboard_fab2_lib.baseboard_fab2(sch_1):page48_i43:vss(28)" )
			)
			( pin "J6U2.184"
				( objectStatus "@baseboard_fab2_lib.baseboard_fab2(sch_1):page48_i43:vss(29)" )
			)
			( pin "J6U2.182"
				( objectStatus "@baseboard_fab2_lib.baseboard_fab2(sch_1):page48_i43:vss(30)" )
			)
			( pin "J6U2.180"
				( objectStatus "@baseboard_fab2_lib.baseboard_fab2(sch_1):page48_i43:vss(31)" )
			)
			( pin "J6U2.178"
				( objectStatus "@baseboard_fab2_lib.baseboard_fab2(sch_1):page48_i43:vss(32)" )
			)
			( pin "J6U2.176"
				( objectStatus "@baseboard_fab2_lib.baseboard_fab2(sch_1):page48_i43:vss(33)" )
			)
			( pin "J6U2.173"
				( objectStatus "@baseboard_fab2_lib.baseboard_fab2(sch_1):page48_i43:vss(34)" )
			)
			( pin "J6U2.171"
				( objectStatus "@baseboard_fab2_lib.baseboard_fab2(sch_1):page48_i43:vss(35)" )
			)
			( pin "J6U2.169"
				( objectStatus "@baseboard_fab2_lib.baseboard_fab2(sch_1):page48_i43:vss(36)" )
			)
			( pin "J6U2.167"
				( objectStatus "@baseboard_fab2_lib.baseboard_fab2(sch_1):page48_i43:vss(37)" )
			)
			( pin "J6U2.165"
				( objectStatus "@baseboard_fab2_lib.baseboard_fab2(sch_1):page48_i43:vss(38)" )
			)
			( pin "J6U2.162"
				( objectStatus "@baseboard_fab2_lib.baseboard_fab2(sch_1):page48_i43:vss(39)" )
			)
			( pin "J6U2.160"
				( objectStatus "@baseboard_fab2_lib.baseboard_fab2(sch_1):page48_i43:vss(40)" )
			)
			( pin "J6U2.158"
				( objectStatus "@baseboard_fab2_lib.baseboard_fab2(sch_1):page48_i43:vss(41)" )
			)
			( pin "J6U2.156"
				( objectStatus "@baseboard_fab2_lib.baseboard_fab2(sch_1):page48_i43:vss(42)" )
			)
			( pin "J6U2.154"
				( objectStatus "@baseboard_fab2_lib.baseboard_fab2(sch_1):page48_i43:vss(43)" )
			)
			( pin "J6U2.151"
				( objectStatus "@baseboard_fab2_lib.baseboard_fab2(sch_1):page48_i43:vss(44)" )
			)
			( pin "J6U2.149"
				( objectStatus "@baseboard_fab2_lib.baseboard_fab2(sch_1):page48_i43:vss(45)" )
			)
			( pin "J6U2.147"
				( objectStatus "@baseboard_fab2_lib.baseboard_fab2(sch_1):page48_i43:vss(46)" )
			)
			( pin "J6U2.138"
				( objectStatus "@baseboard_fab2_lib.baseboard_fab2(sch_1):page48_i43:vss(47)" )
			)
			( pin "J6U2.136"
				( objectStatus "@baseboard_fab2_lib.baseboard_fab2(sch_1):page48_i43:vss(48)" )
			)
			( pin "J6U2.134"
				( objectStatus "@baseboard_fab2_lib.baseboard_fab2(sch_1):page48_i43:vss(49)" )
			)
			( pin "J6U2.131"
				( objectStatus "@baseboard_fab2_lib.baseboard_fab2(sch_1):page48_i43:vss(50)" )
			)
			( pin "J6U2.129"
				( objectStatus "@baseboard_fab2_lib.baseboard_fab2(sch_1):page48_i43:vss(51)" )
			)
			( pin "J6U2.127"
				( objectStatus "@baseboard_fab2_lib.baseboard_fab2(sch_1):page48_i43:vss(52)" )
			)
			( pin "J6U2.125"
				( objectStatus "@baseboard_fab2_lib.baseboard_fab2(sch_1):page48_i43:vss(53)" )
			)
			( pin "J6U2.123"
				( objectStatus "@baseboard_fab2_lib.baseboard_fab2(sch_1):page48_i43:vss(54)" )
			)
			( pin "J6U2.120"
				( objectStatus "@baseboard_fab2_lib.baseboard_fab2(sch_1):page48_i43:vss(55)" )
			)
			( pin "J6U2.118"
				( objectStatus "@baseboard_fab2_lib.baseboard_fab2(sch_1):page48_i43:vss(56)" )
			)
			( pin "J6U2.116"
				( objectStatus "@baseboard_fab2_lib.baseboard_fab2(sch_1):page48_i43:vss(57)" )
			)
			( pin "J6U2.114"
				( objectStatus "@baseboard_fab2_lib.baseboard_fab2(sch_1):page48_i43:vss(58)" )
			)
			( pin "J6U2.112"
				( objectStatus "@baseboard_fab2_lib.baseboard_fab2(sch_1):page48_i43:vss(59)" )
			)
			( pin "J6U2.109"
				( objectStatus "@baseboard_fab2_lib.baseboard_fab2(sch_1):page48_i43:vss(60)" )
			)
			( pin "J6U2.107"
				( objectStatus "@baseboard_fab2_lib.baseboard_fab2(sch_1):page48_i43:vss(61)" )
			)
			( pin "J6U2.105"
				( objectStatus "@baseboard_fab2_lib.baseboard_fab2(sch_1):page48_i43:vss(62)" )
			)
			( pin "J6U2.103"
				( objectStatus "@baseboard_fab2_lib.baseboard_fab2(sch_1):page48_i43:vss(63)" )
			)
			( pin "J6U2.101"
				( objectStatus "@baseboard_fab2_lib.baseboard_fab2(sch_1):page48_i43:vss(64)" )
			)
			( pin "J6U2.98"
				( objectStatus "@baseboard_fab2_lib.baseboard_fab2(sch_1):page48_i43:vss(65)" )
			)
			( pin "J6U2.96"
				( objectStatus "@baseboard_fab2_lib.baseboard_fab2(sch_1):page48_i43:vss(66)" )
			)
			( pin "J6U2.94"
				( objectStatus "@baseboard_fab2_lib.baseboard_fab2(sch_1):page48_i43:vss(67)" )
			)
			( pin "J6U2.57"
				( objectStatus "@baseboard_fab2_lib.baseboard_fab2(sch_1):page48_i43:vss(68)" )
			)
			( pin "J6U2.55"
				( objectStatus "@baseboard_fab2_lib.baseboard_fab2(sch_1):page48_i43:vss(69)" )
			)
			( pin "J6U2.53"
				( objectStatus "@baseboard_fab2_lib.baseboard_fab2(sch_1):page48_i43:vss(70)" )
			)
			( pin "J6U2.50"
				( objectStatus "@baseboard_fab2_lib.baseboard_fab2(sch_1):page48_i43:vss(71)" )
			)
			( pin "J6U2.48"
				( objectStatus "@baseboard_fab2_lib.baseboard_fab2(sch_1):page48_i43:vss(72)" )
			)
			( pin "J6U2.46"
				( objectStatus "@baseboard_fab2_lib.baseboard_fab2(sch_1):page48_i43:vss(73)" )
			)
			( pin "J6U2.44"
				( objectStatus "@baseboard_fab2_lib.baseboard_fab2(sch_1):page48_i43:vss(74)" )
			)
			( pin "J6U2.42"
				( objectStatus "@baseboard_fab2_lib.baseboard_fab2(sch_1):page48_i43:vss(75)" )
			)
			( pin "J6U2.39"
				( objectStatus "@baseboard_fab2_lib.baseboard_fab2(sch_1):page48_i43:vss(76)" )
			)
			( pin "J6U2.37"
				( objectStatus "@baseboard_fab2_lib.baseboard_fab2(sch_1):page48_i43:vss(77)" )
			)
			( pin "J6U2.35"
				( objectStatus "@baseboard_fab2_lib.baseboard_fab2(sch_1):page48_i43:vss(78)" )
			)
			( pin "J6U2.33"
				( objectStatus "@baseboard_fab2_lib.baseboard_fab2(sch_1):page48_i43:vss(79)" )
			)
			( pin "J6U2.31"
				( objectStatus "@baseboard_fab2_lib.baseboard_fab2(sch_1):page48_i43:vss(80)" )
			)
			( pin "J6U2.28"
				( objectStatus "@baseboard_fab2_lib.baseboard_fab2(sch_1):page48_i43:vss(81)" )
			)
			( pin "J6U2.26"
				( objectStatus "@baseboard_fab2_lib.baseboard_fab2(sch_1):page48_i43:vss(82)" )
			)
			( pin "J6U2.24"
				( objectStatus "@baseboard_fab2_lib.baseboard_fab2(sch_1):page48_i43:vss(83)" )
			)
			( pin "J6U2.22"
				( objectStatus "@baseboard_fab2_lib.baseboard_fab2(sch_1):page48_i43:vss(84)" )
			)
			( pin "J6U2.20"
				( objectStatus "@baseboard_fab2_lib.baseboard_fab2(sch_1):page48_i43:vss(85)" )
			)
			( pin "J6U2.17"
				( objectStatus "@baseboard_fab2_lib.baseboard_fab2(sch_1):page48_i43:vss(86)" )
			)
			( pin "J6U2.15"
				( objectStatus "@baseboard_fab2_lib.baseboard_fab2(sch_1):page48_i43:vss(87)" )
			)
			( pin "J6U2.13"
				( objectStatus "@baseboard_fab2_lib.baseboard_fab2(sch_1):page48_i43:vss(88)" )
			)
			( pin "J6U2.11"
				( objectStatus "@baseboard_fab2_lib.baseboard_fab2(sch_1):page48_i43:vss(89)" )
			)
			( pin "J6U2.9"
				( objectStatus "@baseboard_fab2_lib.baseboard_fab2(sch_1):page48_i43:vss(90)" )
			)
			( pin "J6U2.6"
				( objectStatus "@baseboard_fab2_lib.baseboard_fab2(sch_1):page48_i43:vss(91)" )
			)
			( pin "J6U2.4"
				( objectStatus "@baseboard_fab2_lib.baseboard_fab2(sch_1):page48_i43:vss(92)" )
			)
			( pin "J6U2.2"
				( objectStatus "@baseboard_fab2_lib.baseboard_fab2(sch_1):page48_i43:vss(93)" )
			)
			( pin "J6U2.152"
				( objectStatus "@baseboard_fab2_lib.baseboard_fab2(sch_1):page48_i61:dqs0n" )
			)
			( pin "J6U2.153"
				( objectStatus "@baseboard_fab2_lib.baseboard_fab2(sch_1):page48_i61:dqs0p" )
			)
			( pin "J6U2.163"
				( objectStatus "@baseboard_fab2_lib.baseboard_fab2(sch_1):page48_i61:dqs1n" )
			)
			( pin "J6U2.164"
				( objectStatus "@baseboard_fab2_lib.baseboard_fab2(sch_1):page48_i61:dqs1p" )
			)
			( pin "J6U2.174"
				( objectStatus "@baseboard_fab2_lib.baseboard_fab2(sch_1):page48_i61:dqs2n" )
			)
			( pin "J6U2.175"
				( objectStatus "@baseboard_fab2_lib.baseboard_fab2(sch_1):page48_i61:dqs2p" )
			)
			( pin "J6U2.185"
				( objectStatus "@baseboard_fab2_lib.baseboard_fab2(sch_1):page48_i61:dqs3n" )
			)
			( pin "J6U2.186"
				( objectStatus "@baseboard_fab2_lib.baseboard_fab2(sch_1):page48_i61:dqs3p" )
			)
			( pin "J6U2.244"
				( objectStatus "@baseboard_fab2_lib.baseboard_fab2(sch_1):page48_i61:dqs4n" )
			)
			( pin "J6U2.245"
				( objectStatus "@baseboard_fab2_lib.baseboard_fab2(sch_1):page48_i61:dqs4p" )
			)
			( pin "J6U2.255"
				( objectStatus "@baseboard_fab2_lib.baseboard_fab2(sch_1):page48_i61:dqs5n" )
			)
			( pin "J6U2.256"
				( objectStatus "@baseboard_fab2_lib.baseboard_fab2(sch_1):page48_i61:dqs5p" )
			)
			( pin "J6U2.266"
				( objectStatus "@baseboard_fab2_lib.baseboard_fab2(sch_1):page48_i61:dqs6n" )
			)
			( pin "J6U2.267"
				( objectStatus "@baseboard_fab2_lib.baseboard_fab2(sch_1):page48_i61:dqs6p" )
			)
			( pin "J6U2.277"
				( objectStatus "@baseboard_fab2_lib.baseboard_fab2(sch_1):page48_i61:dqs7n" )
			)
			( pin "J6U2.278"
				( objectStatus "@baseboard_fab2_lib.baseboard_fab2(sch_1):page48_i61:dqs7p" )
			)
			( pin "J6U2.196"
				( objectStatus "@baseboard_fab2_lib.baseboard_fab2(sch_1):page48_i61:dqs8n" )
			)
			( pin "J6U2.197"
				( objectStatus "@baseboard_fab2_lib.baseboard_fab2(sch_1):page48_i61:dqs8p" )
			)
			( pin "J6U2.8"
				( objectStatus "@baseboard_fab2_lib.baseboard_fab2(sch_1):page48_i61:dqs9n" )
			)
			( pin "J6U2.7"
				( objectStatus "@baseboard_fab2_lib.baseboard_fab2(sch_1):page48_i61:dqs9p" )
			)
			( pin "J6U2.19"
				( objectStatus "@baseboard_fab2_lib.baseboard_fab2(sch_1):page48_i61:dqs10n" )
			)
			( pin "J6U2.18"
				( objectStatus "@baseboard_fab2_lib.baseboard_fab2(sch_1):page48_i61:dqs10p" )
			)
			( pin "J6U2.30"
				( objectStatus "@baseboard_fab2_lib.baseboard_fab2(sch_1):page48_i61:dqs11n" )
			)
			( pin "J6U2.29"
				( objectStatus "@baseboard_fab2_lib.baseboard_fab2(sch_1):page48_i61:dqs11p" )
			)
			( pin "J6U2.41"
				( objectStatus "@baseboard_fab2_lib.baseboard_fab2(sch_1):page48_i61:dqs12n" )
			)
			( pin "J6U2.40"
				( objectStatus "@baseboard_fab2_lib.baseboard_fab2(sch_1):page48_i61:dqs12p" )
			)
			( pin "J6U2.100"
				( objectStatus "@baseboard_fab2_lib.baseboard_fab2(sch_1):page48_i61:dqs13n" )
			)
			( pin "J6U2.99"
				( objectStatus "@baseboard_fab2_lib.baseboard_fab2(sch_1):page48_i61:dqs13p" )
			)
			( pin "J6U2.111"
				( objectStatus "@baseboard_fab2_lib.baseboard_fab2(sch_1):page48_i61:dqs14n" )
			)
			( pin "J6U2.110"
				( objectStatus "@baseboard_fab2_lib.baseboard_fab2(sch_1):page48_i61:dqs14p" )
			)
			( pin "J6U2.122"
				( objectStatus "@baseboard_fab2_lib.baseboard_fab2(sch_1):page48_i61:dqs15n" )
			)
			( pin "J6U2.121"
				( objectStatus "@baseboard_fab2_lib.baseboard_fab2(sch_1):page48_i61:dqs15p" )
			)
			( pin "J6U2.133"
				( objectStatus "@baseboard_fab2_lib.baseboard_fab2(sch_1):page48_i61:dqs16n" )
			)
			( pin "J6U2.132"
				( objectStatus "@baseboard_fab2_lib.baseboard_fab2(sch_1):page48_i61:dqs16p" )
			)
			( pin "J6U2.52"
				( objectStatus "@baseboard_fab2_lib.baseboard_fab2(sch_1):page48_i61:dqs17n" )
			)
			( pin "J6U2.51"
				( objectStatus "@baseboard_fab2_lib.baseboard_fab2(sch_1):page48_i61:dqs17p" )
			)
			( pin "J6U2.79"
				( objectStatus "@baseboard_fab2_lib.baseboard_fab2(sch_1):page48_i111:a0" )
			)
			( pin "J6U2.72"
				( objectStatus "@baseboard_fab2_lib.baseboard_fab2(sch_1):page48_i111:a1" )
			)
			( pin "J6U2.216"
				( objectStatus "@baseboard_fab2_lib.baseboard_fab2(sch_1):page48_i111:a2" )
			)
			( pin "J6U2.71"
				( objectStatus "@baseboard_fab2_lib.baseboard_fab2(sch_1):page48_i111:a3" )
			)
			( pin "J6U2.214"
				( objectStatus "@baseboard_fab2_lib.baseboard_fab2(sch_1):page48_i111:a4" )
			)
			( pin "J6U2.213"
				( objectStatus "@baseboard_fab2_lib.baseboard_fab2(sch_1):page48_i111:a5" )
			)
			( pin "J6U2.69"
				( objectStatus "@baseboard_fab2_lib.baseboard_fab2(sch_1):page48_i111:a6" )
			)
			( pin "J6U2.211"
				( objectStatus "@baseboard_fab2_lib.baseboard_fab2(sch_1):page48_i111:a7" )
			)
			( pin "J6U2.68"
				( objectStatus "@baseboard_fab2_lib.baseboard_fab2(sch_1):page48_i111:a8" )
			)
			( pin "J6U2.66"
				( objectStatus "@baseboard_fab2_lib.baseboard_fab2(sch_1):page48_i111:a9" )
			)
			( pin "J6U2.225"
				( objectStatus "@baseboard_fab2_lib.baseboard_fab2(sch_1):page48_i111:a10" )
			)
			( pin "J6U2.210"
				( objectStatus "@baseboard_fab2_lib.baseboard_fab2(sch_1):page48_i111:a11" )
			)
			( pin "J6U2.65"
				( objectStatus "@baseboard_fab2_lib.baseboard_fab2(sch_1):page48_i111:a12" )
			)
			( pin "J6U2.232"
				( objectStatus "@baseboard_fab2_lib.baseboard_fab2(sch_1):page48_i111:a13" )
			)
			( pin "J6U2.228"
				( objectStatus "@baseboard_fab2_lib.baseboard_fab2(sch_1):page48_i111:a14_we_n" )
			)
			( pin "J6U2.86"
				( objectStatus "@baseboard_fab2_lib.baseboard_fab2(sch_1):page48_i111:a15_cas_n" )
			)
			( pin "J6U2.82"
				( objectStatus "@baseboard_fab2_lib.baseboard_fab2(sch_1):page48_i111:a16_ras_n" )
			)
			( pin "J6U2.234"
				( objectStatus "@baseboard_fab2_lib.baseboard_fab2(sch_1):page48_i111:a17" )
			)
			( pin "J6U2.62"
				( objectStatus "@baseboard_fab2_lib.baseboard_fab2(sch_1):page48_i111:act_n" )
			)
			( pin "J6U2.208"
				( objectStatus "@baseboard_fab2_lib.baseboard_fab2(sch_1):page48_i111:alert_n" )
			)
			( pin "J6U2.81"
				( objectStatus "@baseboard_fab2_lib.baseboard_fab2(sch_1):page48_i111:ba(0)" )
			)
			( pin "J6U2.224"
				( objectStatus "@baseboard_fab2_lib.baseboard_fab2(sch_1):page48_i111:ba(1)" )
			)
			( pin "J6U2.63"
				( objectStatus "@baseboard_fab2_lib.baseboard_fab2(sch_1):page48_i111:bg(0)" )
			)
			( pin "J6U2.207"
				( objectStatus "@baseboard_fab2_lib.baseboard_fab2(sch_1):page48_i111:bg(1)" )
			)
			( pin "J6U2.235"
				( objectStatus "@baseboard_fab2_lib.baseboard_fab2(sch_1):page48_i111:c(2)" )
			)
			( pin "J6U2.49"
				( objectStatus "@baseboard_fab2_lib.baseboard_fab2(sch_1):page48_i111:cb(0)" )
			)
			( pin "J6U2.194"
				( objectStatus "@baseboard_fab2_lib.baseboard_fab2(sch_1):page48_i111:cb(1)" )
			)
			( pin "J6U2.56"
				( objectStatus "@baseboard_fab2_lib.baseboard_fab2(sch_1):page48_i111:cb(2)" )
			)
			( pin "J6U2.201"
				( objectStatus "@baseboard_fab2_lib.baseboard_fab2(sch_1):page48_i111:cb(3)" )
			)
			( pin "J6U2.47"
				( objectStatus "@baseboard_fab2_lib.baseboard_fab2(sch_1):page48_i111:cb(4)" )
			)
			( pin "J6U2.192"
				( objectStatus "@baseboard_fab2_lib.baseboard_fab2(sch_1):page48_i111:cb(5)" )
			)
			( pin "J6U2.54"
				( objectStatus "@baseboard_fab2_lib.baseboard_fab2(sch_1):page48_i111:cb(6)" )
			)
			( pin "J6U2.199"
				( objectStatus "@baseboard_fab2_lib.baseboard_fab2(sch_1):page48_i111:cb(7)" )
			)
			( pin "J6U2.75"
				( objectStatus "@baseboard_fab2_lib.baseboard_fab2(sch_1):page48_i111:ck0n" )
			)
			( pin "J6U2.74"
				( objectStatus "@baseboard_fab2_lib.baseboard_fab2(sch_1):page48_i111:ck0p" )
			)
			( pin "J6U2.219"
				( objectStatus "@baseboard_fab2_lib.baseboard_fab2(sch_1):page48_i111:ck1n" )
			)
			( pin "J6U2.218"
				( objectStatus "@baseboard_fab2_lib.baseboard_fab2(sch_1):page48_i111:ck1p" )
			)
			( pin "J6U2.60"
				( objectStatus "@baseboard_fab2_lib.baseboard_fab2(sch_1):page48_i111:cke(0)" )
			)
			( pin "J6U2.203"
				( objectStatus "@baseboard_fab2_lib.baseboard_fab2(sch_1):page48_i111:cke(1)" )
			)
			( pin "J6U2.5"
				( objectStatus "@baseboard_fab2_lib.baseboard_fab2(sch_1):page48_i111:dq(0)" )
			)
			( pin "J6U2.150"
				( objectStatus "@baseboard_fab2_lib.baseboard_fab2(sch_1):page48_i111:dq(1)" )
			)
			( pin "J6U2.12"
				( objectStatus "@baseboard_fab2_lib.baseboard_fab2(sch_1):page48_i111:dq(2)" )
			)
			( pin "J6U2.157"
				( objectStatus "@baseboard_fab2_lib.baseboard_fab2(sch_1):page48_i111:dq(3)" )
			)
			( pin "J6U2.3"
				( objectStatus "@baseboard_fab2_lib.baseboard_fab2(sch_1):page48_i111:dq(4)" )
			)
			( pin "J6U2.148"
				( objectStatus "@baseboard_fab2_lib.baseboard_fab2(sch_1):page48_i111:dq(5)" )
			)
			( pin "J6U2.10"
				( objectStatus "@baseboard_fab2_lib.baseboard_fab2(sch_1):page48_i111:dq(6)" )
			)
			( pin "J6U2.155"
				( objectStatus "@baseboard_fab2_lib.baseboard_fab2(sch_1):page48_i111:dq(7)" )
			)
			( pin "J6U2.16"
				( objectStatus "@baseboard_fab2_lib.baseboard_fab2(sch_1):page48_i111:dq(8)" )
			)
			( pin "J6U2.161"
				( objectStatus "@baseboard_fab2_lib.baseboard_fab2(sch_1):page48_i111:dq(9)" )
			)
			( pin "J6U2.23"
				( objectStatus "@baseboard_fab2_lib.baseboard_fab2(sch_1):page48_i111:dq(10)" )
			)
			( pin "J6U2.168"
				( objectStatus "@baseboard_fab2_lib.baseboard_fab2(sch_1):page48_i111:dq(11)" )
			)
			( pin "J6U2.14"
				( objectStatus "@baseboard_fab2_lib.baseboard_fab2(sch_1):page48_i111:dq(12)" )
			)
			( pin "J6U2.159"
				( objectStatus "@baseboard_fab2_lib.baseboard_fab2(sch_1):page48_i111:dq(13)" )
			)
			( pin "J6U2.21"
				( objectStatus "@baseboard_fab2_lib.baseboard_fab2(sch_1):page48_i111:dq(14)" )
			)
			( pin "J6U2.166"
				( objectStatus "@baseboard_fab2_lib.baseboard_fab2(sch_1):page48_i111:dq(15)" )
			)
			( pin "J6U2.27"
				( objectStatus "@baseboard_fab2_lib.baseboard_fab2(sch_1):page48_i111:dq(16)" )
			)
			( pin "J6U2.172"
				( objectStatus "@baseboard_fab2_lib.baseboard_fab2(sch_1):page48_i111:dq(17)" )
			)
			( pin "J6U2.34"
				( objectStatus "@baseboard_fab2_lib.baseboard_fab2(sch_1):page48_i111:dq(18)" )
			)
			( pin "J6U2.179"
				( objectStatus "@baseboard_fab2_lib.baseboard_fab2(sch_1):page48_i111:dq(19)" )
			)
			( pin "J6U2.25"
				( objectStatus "@baseboard_fab2_lib.baseboard_fab2(sch_1):page48_i111:dq(20)" )
			)
			( pin "J6U2.170"
				( objectStatus "@baseboard_fab2_lib.baseboard_fab2(sch_1):page48_i111:dq(21)" )
			)
			( pin "J6U2.32"
				( objectStatus "@baseboard_fab2_lib.baseboard_fab2(sch_1):page48_i111:dq(22)" )
			)
			( pin "J6U2.177"
				( objectStatus "@baseboard_fab2_lib.baseboard_fab2(sch_1):page48_i111:dq(23)" )
			)
			( pin "J6U2.38"
				( objectStatus "@baseboard_fab2_lib.baseboard_fab2(sch_1):page48_i111:dq(24)" )
			)
			( pin "J6U2.183"
				( objectStatus "@baseboard_fab2_lib.baseboard_fab2(sch_1):page48_i111:dq(25)" )
			)
			( pin "J6U2.45"
				( objectStatus "@baseboard_fab2_lib.baseboard_fab2(sch_1):page48_i111:dq(26)" )
			)
			( pin "J6U2.190"
				( objectStatus "@baseboard_fab2_lib.baseboard_fab2(sch_1):page48_i111:dq(27)" )
			)
			( pin "J6U2.36"
				( objectStatus "@baseboard_fab2_lib.baseboard_fab2(sch_1):page48_i111:dq(28)" )
			)
			( pin "J6U2.181"
				( objectStatus "@baseboard_fab2_lib.baseboard_fab2(sch_1):page48_i111:dq(29)" )
			)
			( pin "J6U2.43"
				( objectStatus "@baseboard_fab2_lib.baseboard_fab2(sch_1):page48_i111:dq(30)" )
			)
			( pin "J6U2.188"
				( objectStatus "@baseboard_fab2_lib.baseboard_fab2(sch_1):page48_i111:dq(31)" )
			)
			( pin "J6U2.97"
				( objectStatus "@baseboard_fab2_lib.baseboard_fab2(sch_1):page48_i111:dq(32)" )
			)
			( pin "J6U2.242"
				( objectStatus "@baseboard_fab2_lib.baseboard_fab2(sch_1):page48_i111:dq(33)" )
			)
			( pin "J6U2.104"
				( objectStatus "@baseboard_fab2_lib.baseboard_fab2(sch_1):page48_i111:dq(34)" )
			)
			( pin "J6U2.249"
				( objectStatus "@baseboard_fab2_lib.baseboard_fab2(sch_1):page48_i111:dq(35)" )
			)
			( pin "J6U2.95"
				( objectStatus "@baseboard_fab2_lib.baseboard_fab2(sch_1):page48_i111:dq(36)" )
			)
			( pin "J6U2.240"
				( objectStatus "@baseboard_fab2_lib.baseboard_fab2(sch_1):page48_i111:dq(37)" )
			)
			( pin "J6U2.102"
				( objectStatus "@baseboard_fab2_lib.baseboard_fab2(sch_1):page48_i111:dq(38)" )
			)
			( pin "J6U2.247"
				( objectStatus "@baseboard_fab2_lib.baseboard_fab2(sch_1):page48_i111:dq(39)" )
			)
			( pin "J6U2.108"
				( objectStatus "@baseboard_fab2_lib.baseboard_fab2(sch_1):page48_i111:dq(40)" )
			)
			( pin "J6U2.253"
				( objectStatus "@baseboard_fab2_lib.baseboard_fab2(sch_1):page48_i111:dq(41)" )
			)
			( pin "J6U2.115"
				( objectStatus "@baseboard_fab2_lib.baseboard_fab2(sch_1):page48_i111:dq(42)" )
			)
			( pin "J6U2.260"
				( objectStatus "@baseboard_fab2_lib.baseboard_fab2(sch_1):page48_i111:dq(43)" )
			)
			( pin "J6U2.106"
				( objectStatus "@baseboard_fab2_lib.baseboard_fab2(sch_1):page48_i111:dq(44)" )
			)
			( pin "J6U2.251"
				( objectStatus "@baseboard_fab2_lib.baseboard_fab2(sch_1):page48_i111:dq(45)" )
			)
			( pin "J6U2.113"
				( objectStatus "@baseboard_fab2_lib.baseboard_fab2(sch_1):page48_i111:dq(46)" )
			)
			( pin "J6U2.258"
				( objectStatus "@baseboard_fab2_lib.baseboard_fab2(sch_1):page48_i111:dq(47)" )
			)
			( pin "J6U2.119"
				( objectStatus "@baseboard_fab2_lib.baseboard_fab2(sch_1):page48_i111:dq(48)" )
			)
			( pin "J6U2.264"
				( objectStatus "@baseboard_fab2_lib.baseboard_fab2(sch_1):page48_i111:dq(49)" )
			)
			( pin "J6U2.126"
				( objectStatus "@baseboard_fab2_lib.baseboard_fab2(sch_1):page48_i111:dq(50)" )
			)
			( pin "J6U2.271"
				( objectStatus "@baseboard_fab2_lib.baseboard_fab2(sch_1):page48_i111:dq(51)" )
			)
			( pin "J6U2.117"
				( objectStatus "@baseboard_fab2_lib.baseboard_fab2(sch_1):page48_i111:dq(52)" )
			)
			( pin "J6U2.262"
				( objectStatus "@baseboard_fab2_lib.baseboard_fab2(sch_1):page48_i111:dq(53)" )
			)
			( pin "J6U2.124"
				( objectStatus "@baseboard_fab2_lib.baseboard_fab2(sch_1):page48_i111:dq(54)" )
			)
			( pin "J6U2.269"
				( objectStatus "@baseboard_fab2_lib.baseboard_fab2(sch_1):page48_i111:dq(55)" )
			)
			( pin "J6U2.130"
				( objectStatus "@baseboard_fab2_lib.baseboard_fab2(sch_1):page48_i111:dq(56)" )
			)
			( pin "J6U2.275"
				( objectStatus "@baseboard_fab2_lib.baseboard_fab2(sch_1):page48_i111:dq(57)" )
			)
			( pin "J6U2.137"
				( objectStatus "@baseboard_fab2_lib.baseboard_fab2(sch_1):page48_i111:dq(58)" )
			)
			( pin "J6U2.282"
				( objectStatus "@baseboard_fab2_lib.baseboard_fab2(sch_1):page48_i111:dq(59)" )
			)
			( pin "J6U2.128"
				( objectStatus "@baseboard_fab2_lib.baseboard_fab2(sch_1):page48_i111:dq(60)" )
			)
			( pin "J6U2.273"
				( objectStatus "@baseboard_fab2_lib.baseboard_fab2(sch_1):page48_i111:dq(61)" )
			)
			( pin "J6U2.135"
				( objectStatus "@baseboard_fab2_lib.baseboard_fab2(sch_1):page48_i111:dq(62)" )
			)
			( pin "J6U2.280"
				( objectStatus "@baseboard_fab2_lib.baseboard_fab2(sch_1):page48_i111:dq(63)" )
			)
			( pin "J6U2.78"
				( objectStatus "@baseboard_fab2_lib.baseboard_fab2(sch_1):page48_i111:event_n" )
			)
			( pin "J6U2.87"
				( objectStatus "@baseboard_fab2_lib.baseboard_fab2(sch_1):page48_i111:odt(0)" )
			)
			( pin "J6U2.91"
				( objectStatus "@baseboard_fab2_lib.baseboard_fab2(sch_1):page48_i111:odt(1)" )
			)
			( pin "J6U2.222"
				( objectStatus "@baseboard_fab2_lib.baseboard_fab2(sch_1):page48_i111:par" )
			)
			( pin "J6U2.58"
				( objectStatus "@baseboard_fab2_lib.baseboard_fab2(sch_1):page48_i111:reset_n" )
			)
			( pin "J6U2.205"
				( objectStatus "@baseboard_fab2_lib.baseboard_fab2(sch_1):page48_i111:rfu(0)" )
			)
			( pin "J6U2.227"
				( objectStatus "@baseboard_fab2_lib.baseboard_fab2(sch_1):page48_i111:rfu(1)" )
			)
			( pin "J6U2.144"
				( objectStatus "@baseboard_fab2_lib.baseboard_fab2(sch_1):page48_i111:rfu(2)" )
			)
			( pin "J6U2.84"
				( objectStatus "@baseboard_fab2_lib.baseboard_fab2(sch_1):page48_i111:s0_n" )
			)
			( pin "J6U2.89"
				( objectStatus "@baseboard_fab2_lib.baseboard_fab2(sch_1):page48_i111:s1_n" )
			)
			( pin "J6U2.93"
				( objectStatus "@baseboard_fab2_lib.baseboard_fab2(sch_1):page48_i111:s2_n_c(0)" )
			)
			( pin "J6U2.237"
				( objectStatus "@baseboard_fab2_lib.baseboard_fab2(sch_1):page48_i111:s3_n_c(1)" )
			)
			( pin "J6U2.139"
				( objectStatus "@baseboard_fab2_lib.baseboard_fab2(sch_1):page48_i111:sa(0)" )
			)
			( pin "J6U2.140"
				( objectStatus "@baseboard_fab2_lib.baseboard_fab2(sch_1):page48_i111:sa(1)" )
			)
			( pin "J6U2.238"
				( objectStatus "@baseboard_fab2_lib.baseboard_fab2(sch_1):page48_i111:sa(2)" )
			)
			( pin "J6U2.230"
				( objectStatus "@baseboard_fab2_lib.baseboard_fab2(sch_1):page48_i111:save_n_nc" )
			)
			( pin "J6U2.141"
				( objectStatus "@baseboard_fab2_lib.baseboard_fab2(sch_1):page48_i111:scl" )
			)
			( pin "J6U2.285"
				( objectStatus "@baseboard_fab2_lib.baseboard_fab2(sch_1):page48_i111:sda" )
			)
			( pin "J6U2.284"
				( objectStatus "@baseboard_fab2_lib.baseboard_fab2(sch_1):page48_i111:vddspd" )
			)
			( pin "J6U2.146"
				( objectStatus "@baseboard_fab2_lib.baseboard_fab2(sch_1):page48_i111:vrefca" )
			)
			( pin "J6U2.145"
				( objectStatus "@baseboard_fab2_lib.baseboard_fab2(sch_1):page48_i171:\12v\(0)" )
			)
			( pin "J6U2.1"
				( objectStatus "@baseboard_fab2_lib.baseboard_fab2(sch_1):page48_i171:\12v\(1)" )
			)
			( pin "J6U2.236"
				( objectStatus "@baseboard_fab2_lib.baseboard_fab2(sch_1):page48_i171:vdd(0)" )
			)
			( pin "J6U2.233"
				( objectStatus "@baseboard_fab2_lib.baseboard_fab2(sch_1):page48_i171:vdd(1)" )
			)
			( pin "J6U2.231"
				( objectStatus "@baseboard_fab2_lib.baseboard_fab2(sch_1):page48_i171:vdd(2)" )
			)
			( pin "J6U2.229"
				( objectStatus "@baseboard_fab2_lib.baseboard_fab2(sch_1):page48_i171:vdd(3)" )
			)
			( pin "J6U2.226"
				( objectStatus "@baseboard_fab2_lib.baseboard_fab2(sch_1):page48_i171:vdd(4)" )
			)
			( pin "J6U2.223"
				( objectStatus "@baseboard_fab2_lib.baseboard_fab2(sch_1):page48_i171:vdd(5)" )
			)
			( pin "J6U2.220"
				( objectStatus "@baseboard_fab2_lib.baseboard_fab2(sch_1):page48_i171:vdd(6)" )
			)
			( pin "J6U2.217"
				( objectStatus "@baseboard_fab2_lib.baseboard_fab2(sch_1):page48_i171:vdd(7)" )
			)
			( pin "J6U2.215"
				( objectStatus "@baseboard_fab2_lib.baseboard_fab2(sch_1):page48_i171:vdd(8)" )
			)
			( pin "J6U2.212"
				( objectStatus "@baseboard_fab2_lib.baseboard_fab2(sch_1):page48_i171:vdd(9)" )
			)
			( pin "J6U2.209"
				( objectStatus "@baseboard_fab2_lib.baseboard_fab2(sch_1):page48_i171:vdd(10)" )
			)
			( pin "J6U2.206"
				( objectStatus "@baseboard_fab2_lib.baseboard_fab2(sch_1):page48_i171:vdd(11)" )
			)
			( pin "J6U2.204"
				( objectStatus "@baseboard_fab2_lib.baseboard_fab2(sch_1):page48_i171:vdd(12)" )
			)
			( pin "J6U2.92"
				( objectStatus "@baseboard_fab2_lib.baseboard_fab2(sch_1):page48_i171:vdd(13)" )
			)
			( pin "J6U2.90"
				( objectStatus "@baseboard_fab2_lib.baseboard_fab2(sch_1):page48_i171:vdd(14)" )
			)
			( pin "J6U2.88"
				( objectStatus "@baseboard_fab2_lib.baseboard_fab2(sch_1):page48_i171:vdd(15)" )
			)
			( pin "J6U2.85"
				( objectStatus "@baseboard_fab2_lib.baseboard_fab2(sch_1):page48_i171:vdd(16)" )
			)
			( pin "J6U2.83"
				( objectStatus "@baseboard_fab2_lib.baseboard_fab2(sch_1):page48_i171:vdd(17)" )
			)
			( pin "J6U2.80"
				( objectStatus "@baseboard_fab2_lib.baseboard_fab2(sch_1):page48_i171:vdd(18)" )
			)
			( pin "J6U2.76"
				( objectStatus "@baseboard_fab2_lib.baseboard_fab2(sch_1):page48_i171:vdd(19)" )
			)
			( pin "J6U2.73"
				( objectStatus "@baseboard_fab2_lib.baseboard_fab2(sch_1):page48_i171:vdd(20)" )
			)
			( pin "J6U2.70"
				( objectStatus "@baseboard_fab2_lib.baseboard_fab2(sch_1):page48_i171:vdd(21)" )
			)
			( pin "J6U2.67"
				( objectStatus "@baseboard_fab2_lib.baseboard_fab2(sch_1):page48_i171:vdd(22)" )
			)
			( pin "J6U2.64"
				( objectStatus "@baseboard_fab2_lib.baseboard_fab2(sch_1):page48_i171:vdd(23)" )
			)
			( pin "J6U2.61"
				( objectStatus "@baseboard_fab2_lib.baseboard_fab2(sch_1):page48_i171:vdd(24)" )
			)
			( pin "J6U2.59"
				( objectStatus "@baseboard_fab2_lib.baseboard_fab2(sch_1):page48_i171:vdd(25)" )
			)
			( pin "J6U2.287"
				( objectStatus "@baseboard_fab2_lib.baseboard_fab2(sch_1):page48_i171:vpp(0)" )
			)
			( pin "J6U2.286"
				( objectStatus "@baseboard_fab2_lib.baseboard_fab2(sch_1):page48_i171:vpp(1)" )
			)
			( pin "J6U2.288"
				( objectStatus "@baseboard_fab2_lib.baseboard_fab2(sch_1):page48_i171:vpp(2)" )
			)
			( pin "J6U2.143"
				( objectStatus "@baseboard_fab2_lib.baseboard_fab2(sch_1):page48_i171:vpp(3)" )
			)
			( pin "J6U2.142"
				( objectStatus "@baseboard_fab2_lib.baseboard_fab2(sch_1):page48_i171:vpp(4)" )
			)
			( pin "J6U2.221"
				( objectStatus "@baseboard_fab2_lib.baseboard_fab2(sch_1):page48_i171:vtt(0)" )
			)
			( pin "J6U2.77"
				( objectStatus "@baseboard_fab2_lib.baseboard_fab2(sch_1):page48_i171:vtt(1)" )
			)
			( pin "C6U17.1"
				( objectStatus "@baseboard_fab2_lib.baseboard_fab2(sch_1):page48_i176:a" )
			)
			( pin "C6U17.2"
				( objectStatus "@baseboard_fab2_lib.baseboard_fab2(sch_1):page48_i176:b" )
			)
			( pin "J4B1.283"
				( objectStatus "@baseboard_fab2_lib.baseboard_fab2(sch_1):page49_i43:vss(0)" )
			)
			( pin "J4B1.281"
				( objectStatus "@baseboard_fab2_lib.baseboard_fab2(sch_1):page49_i43:vss(1)" )
			)
			( pin "J4B1.279"
				( objectStatus "@baseboard_fab2_lib.baseboard_fab2(sch_1):page49_i43:vss(2)" )
			)
			( pin "J4B1.276"
				( objectStatus "@baseboard_fab2_lib.baseboard_fab2(sch_1):page49_i43:vss(3)" )
			)
			( pin "J4B1.274"
				( objectStatus "@baseboard_fab2_lib.baseboard_fab2(sch_1):page49_i43:vss(4)" )
			)
			( pin "J4B1.272"
				( objectStatus "@baseboard_fab2_lib.baseboard_fab2(sch_1):page49_i43:vss(5)" )
			)
			( pin "J4B1.270"
				( objectStatus "@baseboard_fab2_lib.baseboard_fab2(sch_1):page49_i43:vss(6)" )
			)
			( pin "J4B1.268"
				( objectStatus "@baseboard_fab2_lib.baseboard_fab2(sch_1):page49_i43:vss(7)" )
			)
			( pin "J4B1.265"
				( objectStatus "@baseboard_fab2_lib.baseboard_fab2(sch_1):page49_i43:vss(8)" )
			)
			( pin "J4B1.263"
				( objectStatus "@baseboard_fab2_lib.baseboard_fab2(sch_1):page49_i43:vss(9)" )
			)
			( pin "J4B1.261"
				( objectStatus "@baseboard_fab2_lib.baseboard_fab2(sch_1):page49_i43:vss(10)" )
			)
			( pin "J4B1.259"
				( objectStatus "@baseboard_fab2_lib.baseboard_fab2(sch_1):page49_i43:vss(11)" )
			)
			( pin "J4B1.257"
				( objectStatus "@baseboard_fab2_lib.baseboard_fab2(sch_1):page49_i43:vss(12)" )
			)
			( pin "J4B1.254"
				( objectStatus "@baseboard_fab2_lib.baseboard_fab2(sch_1):page49_i43:vss(13)" )
			)
			( pin "J4B1.252"
				( objectStatus "@baseboard_fab2_lib.baseboard_fab2(sch_1):page49_i43:vss(14)" )
			)
			( pin "J4B1.250"
				( objectStatus "@baseboard_fab2_lib.baseboard_fab2(sch_1):page49_i43:vss(15)" )
			)
			( pin "J4B1.248"
				( objectStatus "@baseboard_fab2_lib.baseboard_fab2(sch_1):page49_i43:vss(16)" )
			)
			( pin "J4B1.246"
				( objectStatus "@baseboard_fab2_lib.baseboard_fab2(sch_1):page49_i43:vss(17)" )
			)
			( pin "J4B1.243"
				( objectStatus "@baseboard_fab2_lib.baseboard_fab2(sch_1):page49_i43:vss(18)" )
			)
			( pin "J4B1.241"
				( objectStatus "@baseboard_fab2_lib.baseboard_fab2(sch_1):page49_i43:vss(19)" )
			)
			( pin "J4B1.239"
				( objectStatus "@baseboard_fab2_lib.baseboard_fab2(sch_1):page49_i43:vss(20)" )
			)
			( pin "J4B1.202"
				( objectStatus "@baseboard_fab2_lib.baseboard_fab2(sch_1):page49_i43:vss(21)" )
			)
			( pin "J4B1.200"
				( objectStatus "@baseboard_fab2_lib.baseboard_fab2(sch_1):page49_i43:vss(22)" )
			)
			( pin "J4B1.198"
				( objectStatus "@baseboard_fab2_lib.baseboard_fab2(sch_1):page49_i43:vss(23)" )
			)
			( pin "J4B1.195"
				( objectStatus "@baseboard_fab2_lib.baseboard_fab2(sch_1):page49_i43:vss(24)" )
			)
			( pin "J4B1.193"
				( objectStatus "@baseboard_fab2_lib.baseboard_fab2(sch_1):page49_i43:vss(25)" )
			)
			( pin "J4B1.191"
				( objectStatus "@baseboard_fab2_lib.baseboard_fab2(sch_1):page49_i43:vss(26)" )
			)
			( pin "J4B1.189"
				( objectStatus "@baseboard_fab2_lib.baseboard_fab2(sch_1):page49_i43:vss(27)" )
			)
			( pin "J4B1.187"
				( objectStatus "@baseboard_fab2_lib.baseboard_fab2(sch_1):page49_i43:vss(28)" )
			)
			( pin "J4B1.184"
				( objectStatus "@baseboard_fab2_lib.baseboard_fab2(sch_1):page49_i43:vss(29)" )
			)
			( pin "J4B1.182"
				( objectStatus "@baseboard_fab2_lib.baseboard_fab2(sch_1):page49_i43:vss(30)" )
			)
			( pin "J4B1.180"
				( objectStatus "@baseboard_fab2_lib.baseboard_fab2(sch_1):page49_i43:vss(31)" )
			)
			( pin "J4B1.178"
				( objectStatus "@baseboard_fab2_lib.baseboard_fab2(sch_1):page49_i43:vss(32)" )
			)
			( pin "J4B1.176"
				( objectStatus "@baseboard_fab2_lib.baseboard_fab2(sch_1):page49_i43:vss(33)" )
			)
			( pin "J4B1.173"
				( objectStatus "@baseboard_fab2_lib.baseboard_fab2(sch_1):page49_i43:vss(34)" )
			)
			( pin "J4B1.171"
				( objectStatus "@baseboard_fab2_lib.baseboard_fab2(sch_1):page49_i43:vss(35)" )
			)
			( pin "J4B1.169"
				( objectStatus "@baseboard_fab2_lib.baseboard_fab2(sch_1):page49_i43:vss(36)" )
			)
			( pin "J4B1.167"
				( objectStatus "@baseboard_fab2_lib.baseboard_fab2(sch_1):page49_i43:vss(37)" )
			)
			( pin "J4B1.165"
				( objectStatus "@baseboard_fab2_lib.baseboard_fab2(sch_1):page49_i43:vss(38)" )
			)
			( pin "J4B1.162"
				( objectStatus "@baseboard_fab2_lib.baseboard_fab2(sch_1):page49_i43:vss(39)" )
			)
			( pin "J4B1.160"
				( objectStatus "@baseboard_fab2_lib.baseboard_fab2(sch_1):page49_i43:vss(40)" )
			)
			( pin "J4B1.158"
				( objectStatus "@baseboard_fab2_lib.baseboard_fab2(sch_1):page49_i43:vss(41)" )
			)
			( pin "J4B1.156"
				( objectStatus "@baseboard_fab2_lib.baseboard_fab2(sch_1):page49_i43:vss(42)" )
			)
			( pin "J4B1.154"
				( objectStatus "@baseboard_fab2_lib.baseboard_fab2(sch_1):page49_i43:vss(43)" )
			)
			( pin "J4B1.151"
				( objectStatus "@baseboard_fab2_lib.baseboard_fab2(sch_1):page49_i43:vss(44)" )
			)
			( pin "J4B1.149"
				( objectStatus "@baseboard_fab2_lib.baseboard_fab2(sch_1):page49_i43:vss(45)" )
			)
			( pin "J4B1.147"
				( objectStatus "@baseboard_fab2_lib.baseboard_fab2(sch_1):page49_i43:vss(46)" )
			)
			( pin "J4B1.138"
				( objectStatus "@baseboard_fab2_lib.baseboard_fab2(sch_1):page49_i43:vss(47)" )
			)
			( pin "J4B1.136"
				( objectStatus "@baseboard_fab2_lib.baseboard_fab2(sch_1):page49_i43:vss(48)" )
			)
			( pin "J4B1.134"
				( objectStatus "@baseboard_fab2_lib.baseboard_fab2(sch_1):page49_i43:vss(49)" )
			)
			( pin "J4B1.131"
				( objectStatus "@baseboard_fab2_lib.baseboard_fab2(sch_1):page49_i43:vss(50)" )
			)
			( pin "J4B1.129"
				( objectStatus "@baseboard_fab2_lib.baseboard_fab2(sch_1):page49_i43:vss(51)" )
			)
			( pin "J4B1.127"
				( objectStatus "@baseboard_fab2_lib.baseboard_fab2(sch_1):page49_i43:vss(52)" )
			)
			( pin "J4B1.125"
				( objectStatus "@baseboard_fab2_lib.baseboard_fab2(sch_1):page49_i43:vss(53)" )
			)
			( pin "J4B1.123"
				( objectStatus "@baseboard_fab2_lib.baseboard_fab2(sch_1):page49_i43:vss(54)" )
			)
			( pin "J4B1.120"
				( objectStatus "@baseboard_fab2_lib.baseboard_fab2(sch_1):page49_i43:vss(55)" )
			)
			( pin "J4B1.118"
				( objectStatus "@baseboard_fab2_lib.baseboard_fab2(sch_1):page49_i43:vss(56)" )
			)
			( pin "J4B1.116"
				( objectStatus "@baseboard_fab2_lib.baseboard_fab2(sch_1):page49_i43:vss(57)" )
			)
			( pin "J4B1.114"
				( objectStatus "@baseboard_fab2_lib.baseboard_fab2(sch_1):page49_i43:vss(58)" )
			)
			( pin "J4B1.112"
				( objectStatus "@baseboard_fab2_lib.baseboard_fab2(sch_1):page49_i43:vss(59)" )
			)
			( pin "J4B1.109"
				( objectStatus "@baseboard_fab2_lib.baseboard_fab2(sch_1):page49_i43:vss(60)" )
			)
			( pin "J4B1.107"
				( objectStatus "@baseboard_fab2_lib.baseboard_fab2(sch_1):page49_i43:vss(61)" )
			)
			( pin "J4B1.105"
				( objectStatus "@baseboard_fab2_lib.baseboard_fab2(sch_1):page49_i43:vss(62)" )
			)
			( pin "J4B1.103"
				( objectStatus "@baseboard_fab2_lib.baseboard_fab2(sch_1):page49_i43:vss(63)" )
			)
			( pin "J4B1.101"
				( objectStatus "@baseboard_fab2_lib.baseboard_fab2(sch_1):page49_i43:vss(64)" )
			)
			( pin "J4B1.98"
				( objectStatus "@baseboard_fab2_lib.baseboard_fab2(sch_1):page49_i43:vss(65)" )
			)
			( pin "J4B1.96"
				( objectStatus "@baseboard_fab2_lib.baseboard_fab2(sch_1):page49_i43:vss(66)" )
			)
			( pin "J4B1.94"
				( objectStatus "@baseboard_fab2_lib.baseboard_fab2(sch_1):page49_i43:vss(67)" )
			)
			( pin "J4B1.57"
				( objectStatus "@baseboard_fab2_lib.baseboard_fab2(sch_1):page49_i43:vss(68)" )
			)
			( pin "J4B1.55"
				( objectStatus "@baseboard_fab2_lib.baseboard_fab2(sch_1):page49_i43:vss(69)" )
			)
			( pin "J4B1.53"
				( objectStatus "@baseboard_fab2_lib.baseboard_fab2(sch_1):page49_i43:vss(70)" )
			)
			( pin "J4B1.50"
				( objectStatus "@baseboard_fab2_lib.baseboard_fab2(sch_1):page49_i43:vss(71)" )
			)
			( pin "J4B1.48"
				( objectStatus "@baseboard_fab2_lib.baseboard_fab2(sch_1):page49_i43:vss(72)" )
			)
			( pin "J4B1.46"
				( objectStatus "@baseboard_fab2_lib.baseboard_fab2(sch_1):page49_i43:vss(73)" )
			)
			( pin "J4B1.44"
				( objectStatus "@baseboard_fab2_lib.baseboard_fab2(sch_1):page49_i43:vss(74)" )
			)
			( pin "J4B1.42"
				( objectStatus "@baseboard_fab2_lib.baseboard_fab2(sch_1):page49_i43:vss(75)" )
			)
			( pin "J4B1.39"
				( objectStatus "@baseboard_fab2_lib.baseboard_fab2(sch_1):page49_i43:vss(76)" )
			)
			( pin "J4B1.37"
				( objectStatus "@baseboard_fab2_lib.baseboard_fab2(sch_1):page49_i43:vss(77)" )
			)
			( pin "J4B1.35"
				( objectStatus "@baseboard_fab2_lib.baseboard_fab2(sch_1):page49_i43:vss(78)" )
			)
			( pin "J4B1.33"
				( objectStatus "@baseboard_fab2_lib.baseboard_fab2(sch_1):page49_i43:vss(79)" )
			)
			( pin "J4B1.31"
				( objectStatus "@baseboard_fab2_lib.baseboard_fab2(sch_1):page49_i43:vss(80)" )
			)
			( pin "J4B1.28"
				( objectStatus "@baseboard_fab2_lib.baseboard_fab2(sch_1):page49_i43:vss(81)" )
			)
			( pin "J4B1.26"
				( objectStatus "@baseboard_fab2_lib.baseboard_fab2(sch_1):page49_i43:vss(82)" )
			)
			( pin "J4B1.24"
				( objectStatus "@baseboard_fab2_lib.baseboard_fab2(sch_1):page49_i43:vss(83)" )
			)
			( pin "J4B1.22"
				( objectStatus "@baseboard_fab2_lib.baseboard_fab2(sch_1):page49_i43:vss(84)" )
			)
			( pin "J4B1.20"
				( objectStatus "@baseboard_fab2_lib.baseboard_fab2(sch_1):page49_i43:vss(85)" )
			)
			( pin "J4B1.17"
				( objectStatus "@baseboard_fab2_lib.baseboard_fab2(sch_1):page49_i43:vss(86)" )
			)
			( pin "J4B1.15"
				( objectStatus "@baseboard_fab2_lib.baseboard_fab2(sch_1):page49_i43:vss(87)" )
			)
			( pin "J4B1.13"
				( objectStatus "@baseboard_fab2_lib.baseboard_fab2(sch_1):page49_i43:vss(88)" )
			)
			( pin "J4B1.11"
				( objectStatus "@baseboard_fab2_lib.baseboard_fab2(sch_1):page49_i43:vss(89)" )
			)
			( pin "J4B1.9"
				( objectStatus "@baseboard_fab2_lib.baseboard_fab2(sch_1):page49_i43:vss(90)" )
			)
			( pin "J4B1.6"
				( objectStatus "@baseboard_fab2_lib.baseboard_fab2(sch_1):page49_i43:vss(91)" )
			)
			( pin "J4B1.4"
				( objectStatus "@baseboard_fab2_lib.baseboard_fab2(sch_1):page49_i43:vss(92)" )
			)
			( pin "J4B1.2"
				( objectStatus "@baseboard_fab2_lib.baseboard_fab2(sch_1):page49_i43:vss(93)" )
			)
			( pin "J4B1.152"
				( objectStatus "@baseboard_fab2_lib.baseboard_fab2(sch_1):page49_i66:dqs0n" )
			)
			( pin "J4B1.153"
				( objectStatus "@baseboard_fab2_lib.baseboard_fab2(sch_1):page49_i66:dqs0p" )
			)
			( pin "J4B1.163"
				( objectStatus "@baseboard_fab2_lib.baseboard_fab2(sch_1):page49_i66:dqs1n" )
			)
			( pin "J4B1.164"
				( objectStatus "@baseboard_fab2_lib.baseboard_fab2(sch_1):page49_i66:dqs1p" )
			)
			( pin "J4B1.174"
				( objectStatus "@baseboard_fab2_lib.baseboard_fab2(sch_1):page49_i66:dqs2n" )
			)
			( pin "J4B1.175"
				( objectStatus "@baseboard_fab2_lib.baseboard_fab2(sch_1):page49_i66:dqs2p" )
			)
			( pin "J4B1.185"
				( objectStatus "@baseboard_fab2_lib.baseboard_fab2(sch_1):page49_i66:dqs3n" )
			)
			( pin "J4B1.186"
				( objectStatus "@baseboard_fab2_lib.baseboard_fab2(sch_1):page49_i66:dqs3p" )
			)
			( pin "J4B1.244"
				( objectStatus "@baseboard_fab2_lib.baseboard_fab2(sch_1):page49_i66:dqs4n" )
			)
			( pin "J4B1.245"
				( objectStatus "@baseboard_fab2_lib.baseboard_fab2(sch_1):page49_i66:dqs4p" )
			)
			( pin "J4B1.255"
				( objectStatus "@baseboard_fab2_lib.baseboard_fab2(sch_1):page49_i66:dqs5n" )
			)
			( pin "J4B1.256"
				( objectStatus "@baseboard_fab2_lib.baseboard_fab2(sch_1):page49_i66:dqs5p" )
			)
			( pin "J4B1.266"
				( objectStatus "@baseboard_fab2_lib.baseboard_fab2(sch_1):page49_i66:dqs6n" )
			)
			( pin "J4B1.267"
				( objectStatus "@baseboard_fab2_lib.baseboard_fab2(sch_1):page49_i66:dqs6p" )
			)
			( pin "J4B1.277"
				( objectStatus "@baseboard_fab2_lib.baseboard_fab2(sch_1):page49_i66:dqs7n" )
			)
			( pin "J4B1.278"
				( objectStatus "@baseboard_fab2_lib.baseboard_fab2(sch_1):page49_i66:dqs7p" )
			)
			( pin "J4B1.196"
				( objectStatus "@baseboard_fab2_lib.baseboard_fab2(sch_1):page49_i66:dqs8n" )
			)
			( pin "J4B1.197"
				( objectStatus "@baseboard_fab2_lib.baseboard_fab2(sch_1):page49_i66:dqs8p" )
			)
			( pin "J4B1.8"
				( objectStatus "@baseboard_fab2_lib.baseboard_fab2(sch_1):page49_i66:dqs9n" )
			)
			( pin "J4B1.7"
				( objectStatus "@baseboard_fab2_lib.baseboard_fab2(sch_1):page49_i66:dqs9p" )
			)
			( pin "J4B1.19"
				( objectStatus "@baseboard_fab2_lib.baseboard_fab2(sch_1):page49_i66:dqs10n" )
			)
			( pin "J4B1.18"
				( objectStatus "@baseboard_fab2_lib.baseboard_fab2(sch_1):page49_i66:dqs10p" )
			)
			( pin "J4B1.30"
				( objectStatus "@baseboard_fab2_lib.baseboard_fab2(sch_1):page49_i66:dqs11n" )
			)
			( pin "J4B1.29"
				( objectStatus "@baseboard_fab2_lib.baseboard_fab2(sch_1):page49_i66:dqs11p" )
			)
			( pin "J4B1.41"
				( objectStatus "@baseboard_fab2_lib.baseboard_fab2(sch_1):page49_i66:dqs12n" )
			)
			( pin "J4B1.40"
				( objectStatus "@baseboard_fab2_lib.baseboard_fab2(sch_1):page49_i66:dqs12p" )
			)
			( pin "J4B1.100"
				( objectStatus "@baseboard_fab2_lib.baseboard_fab2(sch_1):page49_i66:dqs13n" )
			)
			( pin "J4B1.99"
				( objectStatus "@baseboard_fab2_lib.baseboard_fab2(sch_1):page49_i66:dqs13p" )
			)
			( pin "J4B1.111"
				( objectStatus "@baseboard_fab2_lib.baseboard_fab2(sch_1):page49_i66:dqs14n" )
			)
			( pin "J4B1.110"
				( objectStatus "@baseboard_fab2_lib.baseboard_fab2(sch_1):page49_i66:dqs14p" )
			)
			( pin "J4B1.122"
				( objectStatus "@baseboard_fab2_lib.baseboard_fab2(sch_1):page49_i66:dqs15n" )
			)
			( pin "J4B1.121"
				( objectStatus "@baseboard_fab2_lib.baseboard_fab2(sch_1):page49_i66:dqs15p" )
			)
			( pin "J4B1.133"
				( objectStatus "@baseboard_fab2_lib.baseboard_fab2(sch_1):page49_i66:dqs16n" )
			)
			( pin "J4B1.132"
				( objectStatus "@baseboard_fab2_lib.baseboard_fab2(sch_1):page49_i66:dqs16p" )
			)
			( pin "J4B1.52"
				( objectStatus "@baseboard_fab2_lib.baseboard_fab2(sch_1):page49_i66:dqs17n" )
			)
			( pin "J4B1.51"
				( objectStatus "@baseboard_fab2_lib.baseboard_fab2(sch_1):page49_i66:dqs17p" )
			)
			( pin "J4B1.79"
				( objectStatus "@baseboard_fab2_lib.baseboard_fab2(sch_1):page49_i111:a0" )
			)
			( pin "J4B1.72"
				( objectStatus "@baseboard_fab2_lib.baseboard_fab2(sch_1):page49_i111:a1" )
			)
			( pin "J4B1.216"
				( objectStatus "@baseboard_fab2_lib.baseboard_fab2(sch_1):page49_i111:a2" )
			)
			( pin "J4B1.71"
				( objectStatus "@baseboard_fab2_lib.baseboard_fab2(sch_1):page49_i111:a3" )
			)
			( pin "J4B1.214"
				( objectStatus "@baseboard_fab2_lib.baseboard_fab2(sch_1):page49_i111:a4" )
			)
			( pin "J4B1.213"
				( objectStatus "@baseboard_fab2_lib.baseboard_fab2(sch_1):page49_i111:a5" )
			)
			( pin "J4B1.69"
				( objectStatus "@baseboard_fab2_lib.baseboard_fab2(sch_1):page49_i111:a6" )
			)
			( pin "J4B1.211"
				( objectStatus "@baseboard_fab2_lib.baseboard_fab2(sch_1):page49_i111:a7" )
			)
			( pin "J4B1.68"
				( objectStatus "@baseboard_fab2_lib.baseboard_fab2(sch_1):page49_i111:a8" )
			)
			( pin "J4B1.66"
				( objectStatus "@baseboard_fab2_lib.baseboard_fab2(sch_1):page49_i111:a9" )
			)
			( pin "J4B1.225"
				( objectStatus "@baseboard_fab2_lib.baseboard_fab2(sch_1):page49_i111:a10" )
			)
			( pin "J4B1.210"
				( objectStatus "@baseboard_fab2_lib.baseboard_fab2(sch_1):page49_i111:a11" )
			)
			( pin "J4B1.65"
				( objectStatus "@baseboard_fab2_lib.baseboard_fab2(sch_1):page49_i111:a12" )
			)
			( pin "J4B1.232"
				( objectStatus "@baseboard_fab2_lib.baseboard_fab2(sch_1):page49_i111:a13" )
			)
			( pin "J4B1.228"
				( objectStatus "@baseboard_fab2_lib.baseboard_fab2(sch_1):page49_i111:a14_we_n" )
			)
			( pin "J4B1.86"
				( objectStatus "@baseboard_fab2_lib.baseboard_fab2(sch_1):page49_i111:a15_cas_n" )
			)
			( pin "J4B1.82"
				( objectStatus "@baseboard_fab2_lib.baseboard_fab2(sch_1):page49_i111:a16_ras_n" )
			)
			( pin "J4B1.234"
				( objectStatus "@baseboard_fab2_lib.baseboard_fab2(sch_1):page49_i111:a17" )
			)
			( pin "J4B1.62"
				( objectStatus "@baseboard_fab2_lib.baseboard_fab2(sch_1):page49_i111:act_n" )
			)
			( pin "J4B1.208"
				( objectStatus "@baseboard_fab2_lib.baseboard_fab2(sch_1):page49_i111:alert_n" )
			)
			( pin "J4B1.81"
				( objectStatus "@baseboard_fab2_lib.baseboard_fab2(sch_1):page49_i111:ba(0)" )
			)
			( pin "J4B1.224"
				( objectStatus "@baseboard_fab2_lib.baseboard_fab2(sch_1):page49_i111:ba(1)" )
			)
			( pin "J4B1.63"
				( objectStatus "@baseboard_fab2_lib.baseboard_fab2(sch_1):page49_i111:bg(0)" )
			)
			( pin "J4B1.207"
				( objectStatus "@baseboard_fab2_lib.baseboard_fab2(sch_1):page49_i111:bg(1)" )
			)
			( pin "J4B1.235"
				( objectStatus "@baseboard_fab2_lib.baseboard_fab2(sch_1):page49_i111:c(2)" )
			)
			( pin "J4B1.49"
				( objectStatus "@baseboard_fab2_lib.baseboard_fab2(sch_1):page49_i111:cb(0)" )
			)
			( pin "J4B1.194"
				( objectStatus "@baseboard_fab2_lib.baseboard_fab2(sch_1):page49_i111:cb(1)" )
			)
			( pin "J4B1.56"
				( objectStatus "@baseboard_fab2_lib.baseboard_fab2(sch_1):page49_i111:cb(2)" )
			)
			( pin "J4B1.201"
				( objectStatus "@baseboard_fab2_lib.baseboard_fab2(sch_1):page49_i111:cb(3)" )
			)
			( pin "J4B1.47"
				( objectStatus "@baseboard_fab2_lib.baseboard_fab2(sch_1):page49_i111:cb(4)" )
			)
			( pin "J4B1.192"
				( objectStatus "@baseboard_fab2_lib.baseboard_fab2(sch_1):page49_i111:cb(5)" )
			)
			( pin "J4B1.54"
				( objectStatus "@baseboard_fab2_lib.baseboard_fab2(sch_1):page49_i111:cb(6)" )
			)
			( pin "J4B1.199"
				( objectStatus "@baseboard_fab2_lib.baseboard_fab2(sch_1):page49_i111:cb(7)" )
			)
			( pin "J4B1.75"
				( objectStatus "@baseboard_fab2_lib.baseboard_fab2(sch_1):page49_i111:ck0n" )
			)
			( pin "J4B1.74"
				( objectStatus "@baseboard_fab2_lib.baseboard_fab2(sch_1):page49_i111:ck0p" )
			)
			( pin "J4B1.219"
				( objectStatus "@baseboard_fab2_lib.baseboard_fab2(sch_1):page49_i111:ck1n" )
			)
			( pin "J4B1.218"
				( objectStatus "@baseboard_fab2_lib.baseboard_fab2(sch_1):page49_i111:ck1p" )
			)
			( pin "J4B1.60"
				( objectStatus "@baseboard_fab2_lib.baseboard_fab2(sch_1):page49_i111:cke(0)" )
			)
			( pin "J4B1.203"
				( objectStatus "@baseboard_fab2_lib.baseboard_fab2(sch_1):page49_i111:cke(1)" )
			)
			( pin "J4B1.5"
				( objectStatus "@baseboard_fab2_lib.baseboard_fab2(sch_1):page49_i111:dq(0)" )
			)
			( pin "J4B1.150"
				( objectStatus "@baseboard_fab2_lib.baseboard_fab2(sch_1):page49_i111:dq(1)" )
			)
			( pin "J4B1.12"
				( objectStatus "@baseboard_fab2_lib.baseboard_fab2(sch_1):page49_i111:dq(2)" )
			)
			( pin "J4B1.157"
				( objectStatus "@baseboard_fab2_lib.baseboard_fab2(sch_1):page49_i111:dq(3)" )
			)
			( pin "J4B1.3"
				( objectStatus "@baseboard_fab2_lib.baseboard_fab2(sch_1):page49_i111:dq(4)" )
			)
			( pin "J4B1.148"
				( objectStatus "@baseboard_fab2_lib.baseboard_fab2(sch_1):page49_i111:dq(5)" )
			)
			( pin "J4B1.10"
				( objectStatus "@baseboard_fab2_lib.baseboard_fab2(sch_1):page49_i111:dq(6)" )
			)
			( pin "J4B1.155"
				( objectStatus "@baseboard_fab2_lib.baseboard_fab2(sch_1):page49_i111:dq(7)" )
			)
			( pin "J4B1.16"
				( objectStatus "@baseboard_fab2_lib.baseboard_fab2(sch_1):page49_i111:dq(8)" )
			)
			( pin "J4B1.161"
				( objectStatus "@baseboard_fab2_lib.baseboard_fab2(sch_1):page49_i111:dq(9)" )
			)
			( pin "J4B1.23"
				( objectStatus "@baseboard_fab2_lib.baseboard_fab2(sch_1):page49_i111:dq(10)" )
			)
			( pin "J4B1.168"
				( objectStatus "@baseboard_fab2_lib.baseboard_fab2(sch_1):page49_i111:dq(11)" )
			)
			( pin "J4B1.14"
				( objectStatus "@baseboard_fab2_lib.baseboard_fab2(sch_1):page49_i111:dq(12)" )
			)
			( pin "J4B1.159"
				( objectStatus "@baseboard_fab2_lib.baseboard_fab2(sch_1):page49_i111:dq(13)" )
			)
			( pin "J4B1.21"
				( objectStatus "@baseboard_fab2_lib.baseboard_fab2(sch_1):page49_i111:dq(14)" )
			)
			( pin "J4B1.166"
				( objectStatus "@baseboard_fab2_lib.baseboard_fab2(sch_1):page49_i111:dq(15)" )
			)
			( pin "J4B1.27"
				( objectStatus "@baseboard_fab2_lib.baseboard_fab2(sch_1):page49_i111:dq(16)" )
			)
			( pin "J4B1.172"
				( objectStatus "@baseboard_fab2_lib.baseboard_fab2(sch_1):page49_i111:dq(17)" )
			)
			( pin "J4B1.34"
				( objectStatus "@baseboard_fab2_lib.baseboard_fab2(sch_1):page49_i111:dq(18)" )
			)
			( pin "J4B1.179"
				( objectStatus "@baseboard_fab2_lib.baseboard_fab2(sch_1):page49_i111:dq(19)" )
			)
			( pin "J4B1.25"
				( objectStatus "@baseboard_fab2_lib.baseboard_fab2(sch_1):page49_i111:dq(20)" )
			)
			( pin "J4B1.170"
				( objectStatus "@baseboard_fab2_lib.baseboard_fab2(sch_1):page49_i111:dq(21)" )
			)
			( pin "J4B1.32"
				( objectStatus "@baseboard_fab2_lib.baseboard_fab2(sch_1):page49_i111:dq(22)" )
			)
			( pin "J4B1.177"
				( objectStatus "@baseboard_fab2_lib.baseboard_fab2(sch_1):page49_i111:dq(23)" )
			)
			( pin "J4B1.38"
				( objectStatus "@baseboard_fab2_lib.baseboard_fab2(sch_1):page49_i111:dq(24)" )
			)
			( pin "J4B1.183"
				( objectStatus "@baseboard_fab2_lib.baseboard_fab2(sch_1):page49_i111:dq(25)" )
			)
			( pin "J4B1.45"
				( objectStatus "@baseboard_fab2_lib.baseboard_fab2(sch_1):page49_i111:dq(26)" )
			)
			( pin "J4B1.190"
				( objectStatus "@baseboard_fab2_lib.baseboard_fab2(sch_1):page49_i111:dq(27)" )
			)
			( pin "J4B1.36"
				( objectStatus "@baseboard_fab2_lib.baseboard_fab2(sch_1):page49_i111:dq(28)" )
			)
			( pin "J4B1.181"
				( objectStatus "@baseboard_fab2_lib.baseboard_fab2(sch_1):page49_i111:dq(29)" )
			)
			( pin "J4B1.43"
				( objectStatus "@baseboard_fab2_lib.baseboard_fab2(sch_1):page49_i111:dq(30)" )
			)
			( pin "J4B1.188"
				( objectStatus "@baseboard_fab2_lib.baseboard_fab2(sch_1):page49_i111:dq(31)" )
			)
			( pin "J4B1.97"
				( objectStatus "@baseboard_fab2_lib.baseboard_fab2(sch_1):page49_i111:dq(32)" )
			)
			( pin "J4B1.242"
				( objectStatus "@baseboard_fab2_lib.baseboard_fab2(sch_1):page49_i111:dq(33)" )
			)
			( pin "J4B1.104"
				( objectStatus "@baseboard_fab2_lib.baseboard_fab2(sch_1):page49_i111:dq(34)" )
			)
			( pin "J4B1.249"
				( objectStatus "@baseboard_fab2_lib.baseboard_fab2(sch_1):page49_i111:dq(35)" )
			)
			( pin "J4B1.95"
				( objectStatus "@baseboard_fab2_lib.baseboard_fab2(sch_1):page49_i111:dq(36)" )
			)
			( pin "J4B1.240"
				( objectStatus "@baseboard_fab2_lib.baseboard_fab2(sch_1):page49_i111:dq(37)" )
			)
			( pin "J4B1.102"
				( objectStatus "@baseboard_fab2_lib.baseboard_fab2(sch_1):page49_i111:dq(38)" )
			)
			( pin "J4B1.247"
				( objectStatus "@baseboard_fab2_lib.baseboard_fab2(sch_1):page49_i111:dq(39)" )
			)
			( pin "J4B1.108"
				( objectStatus "@baseboard_fab2_lib.baseboard_fab2(sch_1):page49_i111:dq(40)" )
			)
			( pin "J4B1.253"
				( objectStatus "@baseboard_fab2_lib.baseboard_fab2(sch_1):page49_i111:dq(41)" )
			)
			( pin "J4B1.115"
				( objectStatus "@baseboard_fab2_lib.baseboard_fab2(sch_1):page49_i111:dq(42)" )
			)
			( pin "J4B1.260"
				( objectStatus "@baseboard_fab2_lib.baseboard_fab2(sch_1):page49_i111:dq(43)" )
			)
			( pin "J4B1.106"
				( objectStatus "@baseboard_fab2_lib.baseboard_fab2(sch_1):page49_i111:dq(44)" )
			)
			( pin "J4B1.251"
				( objectStatus "@baseboard_fab2_lib.baseboard_fab2(sch_1):page49_i111:dq(45)" )
			)
			( pin "J4B1.113"
				( objectStatus "@baseboard_fab2_lib.baseboard_fab2(sch_1):page49_i111:dq(46)" )
			)
			( pin "J4B1.258"
				( objectStatus "@baseboard_fab2_lib.baseboard_fab2(sch_1):page49_i111:dq(47)" )
			)
			( pin "J4B1.119"
				( objectStatus "@baseboard_fab2_lib.baseboard_fab2(sch_1):page49_i111:dq(48)" )
			)
			( pin "J4B1.264"
				( objectStatus "@baseboard_fab2_lib.baseboard_fab2(sch_1):page49_i111:dq(49)" )
			)
			( pin "J4B1.126"
				( objectStatus "@baseboard_fab2_lib.baseboard_fab2(sch_1):page49_i111:dq(50)" )
			)
			( pin "J4B1.271"
				( objectStatus "@baseboard_fab2_lib.baseboard_fab2(sch_1):page49_i111:dq(51)" )
			)
			( pin "J4B1.117"
				( objectStatus "@baseboard_fab2_lib.baseboard_fab2(sch_1):page49_i111:dq(52)" )
			)
			( pin "J4B1.262"
				( objectStatus "@baseboard_fab2_lib.baseboard_fab2(sch_1):page49_i111:dq(53)" )
			)
			( pin "J4B1.124"
				( objectStatus "@baseboard_fab2_lib.baseboard_fab2(sch_1):page49_i111:dq(54)" )
			)
			( pin "J4B1.269"
				( objectStatus "@baseboard_fab2_lib.baseboard_fab2(sch_1):page49_i111:dq(55)" )
			)
			( pin "J4B1.130"
				( objectStatus "@baseboard_fab2_lib.baseboard_fab2(sch_1):page49_i111:dq(56)" )
			)
			( pin "J4B1.275"
				( objectStatus "@baseboard_fab2_lib.baseboard_fab2(sch_1):page49_i111:dq(57)" )
			)
			( pin "J4B1.137"
				( objectStatus "@baseboard_fab2_lib.baseboard_fab2(sch_1):page49_i111:dq(58)" )
			)
			( pin "J4B1.282"
				( objectStatus "@baseboard_fab2_lib.baseboard_fab2(sch_1):page49_i111:dq(59)" )
			)
			( pin "J4B1.128"
				( objectStatus "@baseboard_fab2_lib.baseboard_fab2(sch_1):page49_i111:dq(60)" )
			)
			( pin "J4B1.273"
				( objectStatus "@baseboard_fab2_lib.baseboard_fab2(sch_1):page49_i111:dq(61)" )
			)
			( pin "J4B1.135"
				( objectStatus "@baseboard_fab2_lib.baseboard_fab2(sch_1):page49_i111:dq(62)" )
			)
			( pin "J4B1.280"
				( objectStatus "@baseboard_fab2_lib.baseboard_fab2(sch_1):page49_i111:dq(63)" )
			)
			( pin "J4B1.78"
				( objectStatus "@baseboard_fab2_lib.baseboard_fab2(sch_1):page49_i111:event_n" )
			)
			( pin "J4B1.87"
				( objectStatus "@baseboard_fab2_lib.baseboard_fab2(sch_1):page49_i111:odt(0)" )
			)
			( pin "J4B1.91"
				( objectStatus "@baseboard_fab2_lib.baseboard_fab2(sch_1):page49_i111:odt(1)" )
			)
			( pin "J4B1.222"
				( objectStatus "@baseboard_fab2_lib.baseboard_fab2(sch_1):page49_i111:par" )
			)
			( pin "J4B1.58"
				( objectStatus "@baseboard_fab2_lib.baseboard_fab2(sch_1):page49_i111:reset_n" )
			)
			( pin "J4B1.205"
				( objectStatus "@baseboard_fab2_lib.baseboard_fab2(sch_1):page49_i111:rfu(0)" )
			)
			( pin "J4B1.227"
				( objectStatus "@baseboard_fab2_lib.baseboard_fab2(sch_1):page49_i111:rfu(1)" )
			)
			( pin "J4B1.144"
				( objectStatus "@baseboard_fab2_lib.baseboard_fab2(sch_1):page49_i111:rfu(2)" )
			)
			( pin "J4B1.84"
				( objectStatus "@baseboard_fab2_lib.baseboard_fab2(sch_1):page49_i111:s0_n" )
			)
			( pin "J4B1.89"
				( objectStatus "@baseboard_fab2_lib.baseboard_fab2(sch_1):page49_i111:s1_n" )
			)
			( pin "J4B1.93"
				( objectStatus "@baseboard_fab2_lib.baseboard_fab2(sch_1):page49_i111:s2_n_c(0)" )
			)
			( pin "J4B1.237"
				( objectStatus "@baseboard_fab2_lib.baseboard_fab2(sch_1):page49_i111:s3_n_c(1)" )
			)
			( pin "J4B1.139"
				( objectStatus "@baseboard_fab2_lib.baseboard_fab2(sch_1):page49_i111:sa(0)" )
			)
			( pin "J4B1.140"
				( objectStatus "@baseboard_fab2_lib.baseboard_fab2(sch_1):page49_i111:sa(1)" )
			)
			( pin "J4B1.238"
				( objectStatus "@baseboard_fab2_lib.baseboard_fab2(sch_1):page49_i111:sa(2)" )
			)
			( pin "J4B1.230"
				( objectStatus "@baseboard_fab2_lib.baseboard_fab2(sch_1):page49_i111:save_n_nc" )
			)
			( pin "J4B1.141"
				( objectStatus "@baseboard_fab2_lib.baseboard_fab2(sch_1):page49_i111:scl" )
			)
			( pin "J4B1.285"
				( objectStatus "@baseboard_fab2_lib.baseboard_fab2(sch_1):page49_i111:sda" )
			)
			( pin "J4B1.284"
				( objectStatus "@baseboard_fab2_lib.baseboard_fab2(sch_1):page49_i111:vddspd" )
			)
			( pin "J4B1.146"
				( objectStatus "@baseboard_fab2_lib.baseboard_fab2(sch_1):page49_i111:vrefca" )
			)
			( pin "J4B1.145"
				( objectStatus "@baseboard_fab2_lib.baseboard_fab2(sch_1):page49_i169:\12v\(0)" )
			)
			( pin "J4B1.1"
				( objectStatus "@baseboard_fab2_lib.baseboard_fab2(sch_1):page49_i169:\12v\(1)" )
			)
			( pin "J4B1.236"
				( objectStatus "@baseboard_fab2_lib.baseboard_fab2(sch_1):page49_i169:vdd(0)" )
			)
			( pin "J4B1.233"
				( objectStatus "@baseboard_fab2_lib.baseboard_fab2(sch_1):page49_i169:vdd(1)" )
			)
			( pin "J4B1.231"
				( objectStatus "@baseboard_fab2_lib.baseboard_fab2(sch_1):page49_i169:vdd(2)" )
			)
			( pin "J4B1.229"
				( objectStatus "@baseboard_fab2_lib.baseboard_fab2(sch_1):page49_i169:vdd(3)" )
			)
			( pin "J4B1.226"
				( objectStatus "@baseboard_fab2_lib.baseboard_fab2(sch_1):page49_i169:vdd(4)" )
			)
			( pin "J4B1.223"
				( objectStatus "@baseboard_fab2_lib.baseboard_fab2(sch_1):page49_i169:vdd(5)" )
			)
			( pin "J4B1.220"
				( objectStatus "@baseboard_fab2_lib.baseboard_fab2(sch_1):page49_i169:vdd(6)" )
			)
			( pin "J4B1.217"
				( objectStatus "@baseboard_fab2_lib.baseboard_fab2(sch_1):page49_i169:vdd(7)" )
			)
			( pin "J4B1.215"
				( objectStatus "@baseboard_fab2_lib.baseboard_fab2(sch_1):page49_i169:vdd(8)" )
			)
			( pin "J4B1.212"
				( objectStatus "@baseboard_fab2_lib.baseboard_fab2(sch_1):page49_i169:vdd(9)" )
			)
			( pin "J4B1.209"
				( objectStatus "@baseboard_fab2_lib.baseboard_fab2(sch_1):page49_i169:vdd(10)" )
			)
			( pin "J4B1.206"
				( objectStatus "@baseboard_fab2_lib.baseboard_fab2(sch_1):page49_i169:vdd(11)" )
			)
			( pin "J4B1.204"
				( objectStatus "@baseboard_fab2_lib.baseboard_fab2(sch_1):page49_i169:vdd(12)" )
			)
			( pin "J4B1.92"
				( objectStatus "@baseboard_fab2_lib.baseboard_fab2(sch_1):page49_i169:vdd(13)" )
			)
			( pin "J4B1.90"
				( objectStatus "@baseboard_fab2_lib.baseboard_fab2(sch_1):page49_i169:vdd(14)" )
			)
			( pin "J4B1.88"
				( objectStatus "@baseboard_fab2_lib.baseboard_fab2(sch_1):page49_i169:vdd(15)" )
			)
			( pin "J4B1.85"
				( objectStatus "@baseboard_fab2_lib.baseboard_fab2(sch_1):page49_i169:vdd(16)" )
			)
			( pin "J4B1.83"
				( objectStatus "@baseboard_fab2_lib.baseboard_fab2(sch_1):page49_i169:vdd(17)" )
			)
			( pin "J4B1.80"
				( objectStatus "@baseboard_fab2_lib.baseboard_fab2(sch_1):page49_i169:vdd(18)" )
			)
			( pin "J4B1.76"
				( objectStatus "@baseboard_fab2_lib.baseboard_fab2(sch_1):page49_i169:vdd(19)" )
			)
			( pin "J4B1.73"
				( objectStatus "@baseboard_fab2_lib.baseboard_fab2(sch_1):page49_i169:vdd(20)" )
			)
			( pin "J4B1.70"
				( objectStatus "@baseboard_fab2_lib.baseboard_fab2(sch_1):page49_i169:vdd(21)" )
			)
			( pin "J4B1.67"
				( objectStatus "@baseboard_fab2_lib.baseboard_fab2(sch_1):page49_i169:vdd(22)" )
			)
			( pin "J4B1.64"
				( objectStatus "@baseboard_fab2_lib.baseboard_fab2(sch_1):page49_i169:vdd(23)" )
			)
			( pin "J4B1.61"
				( objectStatus "@baseboard_fab2_lib.baseboard_fab2(sch_1):page49_i169:vdd(24)" )
			)
			( pin "J4B1.59"
				( objectStatus "@baseboard_fab2_lib.baseboard_fab2(sch_1):page49_i169:vdd(25)" )
			)
			( pin "J4B1.287"
				( objectStatus "@baseboard_fab2_lib.baseboard_fab2(sch_1):page49_i169:vpp(0)" )
			)
			( pin "J4B1.286"
				( objectStatus "@baseboard_fab2_lib.baseboard_fab2(sch_1):page49_i169:vpp(1)" )
			)
			( pin "J4B1.288"
				( objectStatus "@baseboard_fab2_lib.baseboard_fab2(sch_1):page49_i169:vpp(2)" )
			)
			( pin "J4B1.143"
				( objectStatus "@baseboard_fab2_lib.baseboard_fab2(sch_1):page49_i169:vpp(3)" )
			)
			( pin "J4B1.142"
				( objectStatus "@baseboard_fab2_lib.baseboard_fab2(sch_1):page49_i169:vpp(4)" )
			)
			( pin "J4B1.221"
				( objectStatus "@baseboard_fab2_lib.baseboard_fab2(sch_1):page49_i169:vtt(0)" )
			)
			( pin "J4B1.77"
				( objectStatus "@baseboard_fab2_lib.baseboard_fab2(sch_1):page49_i169:vtt(1)" )
			)
			( pin "C4B12.1"
				( objectStatus "@baseboard_fab2_lib.baseboard_fab2(sch_1):page49_i179:a" )
			)
			( pin "C4B12.2"
				( objectStatus "@baseboard_fab2_lib.baseboard_fab2(sch_1):page49_i179:b" )
			)
			( pin "J6M1.283"
				( objectStatus "@baseboard_fab2_lib.baseboard_fab2(sch_1):page50_i44:vss(0)" )
			)
			( pin "J6M1.281"
				( objectStatus "@baseboard_fab2_lib.baseboard_fab2(sch_1):page50_i44:vss(1)" )
			)
			( pin "J6M1.279"
				( objectStatus "@baseboard_fab2_lib.baseboard_fab2(sch_1):page50_i44:vss(2)" )
			)
			( pin "J6M1.276"
				( objectStatus "@baseboard_fab2_lib.baseboard_fab2(sch_1):page50_i44:vss(3)" )
			)
			( pin "J6M1.274"
				( objectStatus "@baseboard_fab2_lib.baseboard_fab2(sch_1):page50_i44:vss(4)" )
			)
			( pin "J6M1.272"
				( objectStatus "@baseboard_fab2_lib.baseboard_fab2(sch_1):page50_i44:vss(5)" )
			)
			( pin "J6M1.270"
				( objectStatus "@baseboard_fab2_lib.baseboard_fab2(sch_1):page50_i44:vss(6)" )
			)
			( pin "J6M1.268"
				( objectStatus "@baseboard_fab2_lib.baseboard_fab2(sch_1):page50_i44:vss(7)" )
			)
			( pin "J6M1.265"
				( objectStatus "@baseboard_fab2_lib.baseboard_fab2(sch_1):page50_i44:vss(8)" )
			)
			( pin "J6M1.263"
				( objectStatus "@baseboard_fab2_lib.baseboard_fab2(sch_1):page50_i44:vss(9)" )
			)
			( pin "J6M1.261"
				( objectStatus "@baseboard_fab2_lib.baseboard_fab2(sch_1):page50_i44:vss(10)" )
			)
			( pin "J6M1.259"
				( objectStatus "@baseboard_fab2_lib.baseboard_fab2(sch_1):page50_i44:vss(11)" )
			)
			( pin "J6M1.257"
				( objectStatus "@baseboard_fab2_lib.baseboard_fab2(sch_1):page50_i44:vss(12)" )
			)
			( pin "J6M1.254"
				( objectStatus "@baseboard_fab2_lib.baseboard_fab2(sch_1):page50_i44:vss(13)" )
			)
			( pin "J6M1.252"
				( objectStatus "@baseboard_fab2_lib.baseboard_fab2(sch_1):page50_i44:vss(14)" )
			)
			( pin "J6M1.250"
				( objectStatus "@baseboard_fab2_lib.baseboard_fab2(sch_1):page50_i44:vss(15)" )
			)
			( pin "J6M1.248"
				( objectStatus "@baseboard_fab2_lib.baseboard_fab2(sch_1):page50_i44:vss(16)" )
			)
			( pin "J6M1.246"
				( objectStatus "@baseboard_fab2_lib.baseboard_fab2(sch_1):page50_i44:vss(17)" )
			)
			( pin "J6M1.243"
				( objectStatus "@baseboard_fab2_lib.baseboard_fab2(sch_1):page50_i44:vss(18)" )
			)
			( pin "J6M1.241"
				( objectStatus "@baseboard_fab2_lib.baseboard_fab2(sch_1):page50_i44:vss(19)" )
			)
			( pin "J6M1.239"
				( objectStatus "@baseboard_fab2_lib.baseboard_fab2(sch_1):page50_i44:vss(20)" )
			)
			( pin "J6M1.202"
				( objectStatus "@baseboard_fab2_lib.baseboard_fab2(sch_1):page50_i44:vss(21)" )
			)
			( pin "J6M1.200"
				( objectStatus "@baseboard_fab2_lib.baseboard_fab2(sch_1):page50_i44:vss(22)" )
			)
			( pin "J6M1.198"
				( objectStatus "@baseboard_fab2_lib.baseboard_fab2(sch_1):page50_i44:vss(23)" )
			)
			( pin "J6M1.195"
				( objectStatus "@baseboard_fab2_lib.baseboard_fab2(sch_1):page50_i44:vss(24)" )
			)
			( pin "J6M1.193"
				( objectStatus "@baseboard_fab2_lib.baseboard_fab2(sch_1):page50_i44:vss(25)" )
			)
			( pin "J6M1.191"
				( objectStatus "@baseboard_fab2_lib.baseboard_fab2(sch_1):page50_i44:vss(26)" )
			)
			( pin "J6M1.189"
				( objectStatus "@baseboard_fab2_lib.baseboard_fab2(sch_1):page50_i44:vss(27)" )
			)
			( pin "J6M1.187"
				( objectStatus "@baseboard_fab2_lib.baseboard_fab2(sch_1):page50_i44:vss(28)" )
			)
			( pin "J6M1.184"
				( objectStatus "@baseboard_fab2_lib.baseboard_fab2(sch_1):page50_i44:vss(29)" )
			)
			( pin "J6M1.182"
				( objectStatus "@baseboard_fab2_lib.baseboard_fab2(sch_1):page50_i44:vss(30)" )
			)
			( pin "J6M1.180"
				( objectStatus "@baseboard_fab2_lib.baseboard_fab2(sch_1):page50_i44:vss(31)" )
			)
			( pin "J6M1.178"
				( objectStatus "@baseboard_fab2_lib.baseboard_fab2(sch_1):page50_i44:vss(32)" )
			)
			( pin "J6M1.176"
				( objectStatus "@baseboard_fab2_lib.baseboard_fab2(sch_1):page50_i44:vss(33)" )
			)
			( pin "J6M1.173"
				( objectStatus "@baseboard_fab2_lib.baseboard_fab2(sch_1):page50_i44:vss(34)" )
			)
			( pin "J6M1.171"
				( objectStatus "@baseboard_fab2_lib.baseboard_fab2(sch_1):page50_i44:vss(35)" )
			)
			( pin "J6M1.169"
				( objectStatus "@baseboard_fab2_lib.baseboard_fab2(sch_1):page50_i44:vss(36)" )
			)
			( pin "J6M1.167"
				( objectStatus "@baseboard_fab2_lib.baseboard_fab2(sch_1):page50_i44:vss(37)" )
			)
			( pin "J6M1.165"
				( objectStatus "@baseboard_fab2_lib.baseboard_fab2(sch_1):page50_i44:vss(38)" )
			)
			( pin "J6M1.162"
				( objectStatus "@baseboard_fab2_lib.baseboard_fab2(sch_1):page50_i44:vss(39)" )
			)
			( pin "J6M1.160"
				( objectStatus "@baseboard_fab2_lib.baseboard_fab2(sch_1):page50_i44:vss(40)" )
			)
			( pin "J6M1.158"
				( objectStatus "@baseboard_fab2_lib.baseboard_fab2(sch_1):page50_i44:vss(41)" )
			)
			( pin "J6M1.156"
				( objectStatus "@baseboard_fab2_lib.baseboard_fab2(sch_1):page50_i44:vss(42)" )
			)
			( pin "J6M1.154"
				( objectStatus "@baseboard_fab2_lib.baseboard_fab2(sch_1):page50_i44:vss(43)" )
			)
			( pin "J6M1.151"
				( objectStatus "@baseboard_fab2_lib.baseboard_fab2(sch_1):page50_i44:vss(44)" )
			)
			( pin "J6M1.149"
				( objectStatus "@baseboard_fab2_lib.baseboard_fab2(sch_1):page50_i44:vss(45)" )
			)
			( pin "J6M1.147"
				( objectStatus "@baseboard_fab2_lib.baseboard_fab2(sch_1):page50_i44:vss(46)" )
			)
			( pin "J6M1.138"
				( objectStatus "@baseboard_fab2_lib.baseboard_fab2(sch_1):page50_i44:vss(47)" )
			)
			( pin "J6M1.136"
				( objectStatus "@baseboard_fab2_lib.baseboard_fab2(sch_1):page50_i44:vss(48)" )
			)
			( pin "J6M1.134"
				( objectStatus "@baseboard_fab2_lib.baseboard_fab2(sch_1):page50_i44:vss(49)" )
			)
			( pin "J6M1.131"
				( objectStatus "@baseboard_fab2_lib.baseboard_fab2(sch_1):page50_i44:vss(50)" )
			)
			( pin "J6M1.129"
				( objectStatus "@baseboard_fab2_lib.baseboard_fab2(sch_1):page50_i44:vss(51)" )
			)
			( pin "J6M1.127"
				( objectStatus "@baseboard_fab2_lib.baseboard_fab2(sch_1):page50_i44:vss(52)" )
			)
			( pin "J6M1.125"
				( objectStatus "@baseboard_fab2_lib.baseboard_fab2(sch_1):page50_i44:vss(53)" )
			)
			( pin "J6M1.123"
				( objectStatus "@baseboard_fab2_lib.baseboard_fab2(sch_1):page50_i44:vss(54)" )
			)
			( pin "J6M1.120"
				( objectStatus "@baseboard_fab2_lib.baseboard_fab2(sch_1):page50_i44:vss(55)" )
			)
			( pin "J6M1.118"
				( objectStatus "@baseboard_fab2_lib.baseboard_fab2(sch_1):page50_i44:vss(56)" )
			)
			( pin "J6M1.116"
				( objectStatus "@baseboard_fab2_lib.baseboard_fab2(sch_1):page50_i44:vss(57)" )
			)
			( pin "J6M1.114"
				( objectStatus "@baseboard_fab2_lib.baseboard_fab2(sch_1):page50_i44:vss(58)" )
			)
			( pin "J6M1.112"
				( objectStatus "@baseboard_fab2_lib.baseboard_fab2(sch_1):page50_i44:vss(59)" )
			)
			( pin "J6M1.109"
				( objectStatus "@baseboard_fab2_lib.baseboard_fab2(sch_1):page50_i44:vss(60)" )
			)
			( pin "J6M1.107"
				( objectStatus "@baseboard_fab2_lib.baseboard_fab2(sch_1):page50_i44:vss(61)" )
			)
			( pin "J6M1.105"
				( objectStatus "@baseboard_fab2_lib.baseboard_fab2(sch_1):page50_i44:vss(62)" )
			)
			( pin "J6M1.103"
				( objectStatus "@baseboard_fab2_lib.baseboard_fab2(sch_1):page50_i44:vss(63)" )
			)
			( pin "J6M1.101"
				( objectStatus "@baseboard_fab2_lib.baseboard_fab2(sch_1):page50_i44:vss(64)" )
			)
			( pin "J6M1.98"
				( objectStatus "@baseboard_fab2_lib.baseboard_fab2(sch_1):page50_i44:vss(65)" )
			)
			( pin "J6M1.96"
				( objectStatus "@baseboard_fab2_lib.baseboard_fab2(sch_1):page50_i44:vss(66)" )
			)
			( pin "J6M1.94"
				( objectStatus "@baseboard_fab2_lib.baseboard_fab2(sch_1):page50_i44:vss(67)" )
			)
			( pin "J6M1.57"
				( objectStatus "@baseboard_fab2_lib.baseboard_fab2(sch_1):page50_i44:vss(68)" )
			)
			( pin "J6M1.55"
				( objectStatus "@baseboard_fab2_lib.baseboard_fab2(sch_1):page50_i44:vss(69)" )
			)
			( pin "J6M1.53"
				( objectStatus "@baseboard_fab2_lib.baseboard_fab2(sch_1):page50_i44:vss(70)" )
			)
			( pin "J6M1.50"
				( objectStatus "@baseboard_fab2_lib.baseboard_fab2(sch_1):page50_i44:vss(71)" )
			)
			( pin "J6M1.48"
				( objectStatus "@baseboard_fab2_lib.baseboard_fab2(sch_1):page50_i44:vss(72)" )
			)
			( pin "J6M1.46"
				( objectStatus "@baseboard_fab2_lib.baseboard_fab2(sch_1):page50_i44:vss(73)" )
			)
			( pin "J6M1.44"
				( objectStatus "@baseboard_fab2_lib.baseboard_fab2(sch_1):page50_i44:vss(74)" )
			)
			( pin "J6M1.42"
				( objectStatus "@baseboard_fab2_lib.baseboard_fab2(sch_1):page50_i44:vss(75)" )
			)
			( pin "J6M1.39"
				( objectStatus "@baseboard_fab2_lib.baseboard_fab2(sch_1):page50_i44:vss(76)" )
			)
			( pin "J6M1.37"
				( objectStatus "@baseboard_fab2_lib.baseboard_fab2(sch_1):page50_i44:vss(77)" )
			)
			( pin "J6M1.35"
				( objectStatus "@baseboard_fab2_lib.baseboard_fab2(sch_1):page50_i44:vss(78)" )
			)
			( pin "J6M1.33"
				( objectStatus "@baseboard_fab2_lib.baseboard_fab2(sch_1):page50_i44:vss(79)" )
			)
			( pin "J6M1.31"
				( objectStatus "@baseboard_fab2_lib.baseboard_fab2(sch_1):page50_i44:vss(80)" )
			)
			( pin "J6M1.28"
				( objectStatus "@baseboard_fab2_lib.baseboard_fab2(sch_1):page50_i44:vss(81)" )
			)
			( pin "J6M1.26"
				( objectStatus "@baseboard_fab2_lib.baseboard_fab2(sch_1):page50_i44:vss(82)" )
			)
			( pin "J6M1.24"
				( objectStatus "@baseboard_fab2_lib.baseboard_fab2(sch_1):page50_i44:vss(83)" )
			)
			( pin "J6M1.22"
				( objectStatus "@baseboard_fab2_lib.baseboard_fab2(sch_1):page50_i44:vss(84)" )
			)
			( pin "J6M1.20"
				( objectStatus "@baseboard_fab2_lib.baseboard_fab2(sch_1):page50_i44:vss(85)" )
			)
			( pin "J6M1.17"
				( objectStatus "@baseboard_fab2_lib.baseboard_fab2(sch_1):page50_i44:vss(86)" )
			)
			( pin "J6M1.15"
				( objectStatus "@baseboard_fab2_lib.baseboard_fab2(sch_1):page50_i44:vss(87)" )
			)
			( pin "J6M1.13"
				( objectStatus "@baseboard_fab2_lib.baseboard_fab2(sch_1):page50_i44:vss(88)" )
			)
			( pin "J6M1.11"
				( objectStatus "@baseboard_fab2_lib.baseboard_fab2(sch_1):page50_i44:vss(89)" )
			)
			( pin "J6M1.9"
				( objectStatus "@baseboard_fab2_lib.baseboard_fab2(sch_1):page50_i44:vss(90)" )
			)
			( pin "J6M1.6"
				( objectStatus "@baseboard_fab2_lib.baseboard_fab2(sch_1):page50_i44:vss(91)" )
			)
			( pin "J6M1.4"
				( objectStatus "@baseboard_fab2_lib.baseboard_fab2(sch_1):page50_i44:vss(92)" )
			)
			( pin "J6M1.2"
				( objectStatus "@baseboard_fab2_lib.baseboard_fab2(sch_1):page50_i44:vss(93)" )
			)
			( pin "J6M1.152"
				( objectStatus "@baseboard_fab2_lib.baseboard_fab2(sch_1):page50_i46:dqs0n" )
			)
			( pin "J6M1.153"
				( objectStatus "@baseboard_fab2_lib.baseboard_fab2(sch_1):page50_i46:dqs0p" )
			)
			( pin "J6M1.163"
				( objectStatus "@baseboard_fab2_lib.baseboard_fab2(sch_1):page50_i46:dqs1n" )
			)
			( pin "J6M1.164"
				( objectStatus "@baseboard_fab2_lib.baseboard_fab2(sch_1):page50_i46:dqs1p" )
			)
			( pin "J6M1.174"
				( objectStatus "@baseboard_fab2_lib.baseboard_fab2(sch_1):page50_i46:dqs2n" )
			)
			( pin "J6M1.175"
				( objectStatus "@baseboard_fab2_lib.baseboard_fab2(sch_1):page50_i46:dqs2p" )
			)
			( pin "J6M1.185"
				( objectStatus "@baseboard_fab2_lib.baseboard_fab2(sch_1):page50_i46:dqs3n" )
			)
			( pin "J6M1.186"
				( objectStatus "@baseboard_fab2_lib.baseboard_fab2(sch_1):page50_i46:dqs3p" )
			)
			( pin "J6M1.244"
				( objectStatus "@baseboard_fab2_lib.baseboard_fab2(sch_1):page50_i46:dqs4n" )
			)
			( pin "J6M1.245"
				( objectStatus "@baseboard_fab2_lib.baseboard_fab2(sch_1):page50_i46:dqs4p" )
			)
			( pin "J6M1.255"
				( objectStatus "@baseboard_fab2_lib.baseboard_fab2(sch_1):page50_i46:dqs5n" )
			)
			( pin "J6M1.256"
				( objectStatus "@baseboard_fab2_lib.baseboard_fab2(sch_1):page50_i46:dqs5p" )
			)
			( pin "J6M1.266"
				( objectStatus "@baseboard_fab2_lib.baseboard_fab2(sch_1):page50_i46:dqs6n" )
			)
			( pin "J6M1.267"
				( objectStatus "@baseboard_fab2_lib.baseboard_fab2(sch_1):page50_i46:dqs6p" )
			)
			( pin "J6M1.277"
				( objectStatus "@baseboard_fab2_lib.baseboard_fab2(sch_1):page50_i46:dqs7n" )
			)
			( pin "J6M1.278"
				( objectStatus "@baseboard_fab2_lib.baseboard_fab2(sch_1):page50_i46:dqs7p" )
			)
			( pin "J6M1.196"
				( objectStatus "@baseboard_fab2_lib.baseboard_fab2(sch_1):page50_i46:dqs8n" )
			)
			( pin "J6M1.197"
				( objectStatus "@baseboard_fab2_lib.baseboard_fab2(sch_1):page50_i46:dqs8p" )
			)
			( pin "J6M1.8"
				( objectStatus "@baseboard_fab2_lib.baseboard_fab2(sch_1):page50_i46:dqs9n" )
			)
			( pin "J6M1.7"
				( objectStatus "@baseboard_fab2_lib.baseboard_fab2(sch_1):page50_i46:dqs9p" )
			)
			( pin "J6M1.19"
				( objectStatus "@baseboard_fab2_lib.baseboard_fab2(sch_1):page50_i46:dqs10n" )
			)
			( pin "J6M1.18"
				( objectStatus "@baseboard_fab2_lib.baseboard_fab2(sch_1):page50_i46:dqs10p" )
			)
			( pin "J6M1.30"
				( objectStatus "@baseboard_fab2_lib.baseboard_fab2(sch_1):page50_i46:dqs11n" )
			)
			( pin "J6M1.29"
				( objectStatus "@baseboard_fab2_lib.baseboard_fab2(sch_1):page50_i46:dqs11p" )
			)
			( pin "J6M1.41"
				( objectStatus "@baseboard_fab2_lib.baseboard_fab2(sch_1):page50_i46:dqs12n" )
			)
			( pin "J6M1.40"
				( objectStatus "@baseboard_fab2_lib.baseboard_fab2(sch_1):page50_i46:dqs12p" )
			)
			( pin "J6M1.100"
				( objectStatus "@baseboard_fab2_lib.baseboard_fab2(sch_1):page50_i46:dqs13n" )
			)
			( pin "J6M1.99"
				( objectStatus "@baseboard_fab2_lib.baseboard_fab2(sch_1):page50_i46:dqs13p" )
			)
			( pin "J6M1.111"
				( objectStatus "@baseboard_fab2_lib.baseboard_fab2(sch_1):page50_i46:dqs14n" )
			)
			( pin "J6M1.110"
				( objectStatus "@baseboard_fab2_lib.baseboard_fab2(sch_1):page50_i46:dqs14p" )
			)
			( pin "J6M1.122"
				( objectStatus "@baseboard_fab2_lib.baseboard_fab2(sch_1):page50_i46:dqs15n" )
			)
			( pin "J6M1.121"
				( objectStatus "@baseboard_fab2_lib.baseboard_fab2(sch_1):page50_i46:dqs15p" )
			)
			( pin "J6M1.133"
				( objectStatus "@baseboard_fab2_lib.baseboard_fab2(sch_1):page50_i46:dqs16n" )
			)
			( pin "J6M1.132"
				( objectStatus "@baseboard_fab2_lib.baseboard_fab2(sch_1):page50_i46:dqs16p" )
			)
			( pin "J6M1.52"
				( objectStatus "@baseboard_fab2_lib.baseboard_fab2(sch_1):page50_i46:dqs17n" )
			)
			( pin "J6M1.51"
				( objectStatus "@baseboard_fab2_lib.baseboard_fab2(sch_1):page50_i46:dqs17p" )
			)
			( pin "J6M1.145"
				( objectStatus "@baseboard_fab2_lib.baseboard_fab2(sch_1):page50_i50:\12v\(0)" )
			)
			( pin "J6M1.1"
				( objectStatus "@baseboard_fab2_lib.baseboard_fab2(sch_1):page50_i50:\12v\(1)" )
			)
			( pin "J6M1.236"
				( objectStatus "@baseboard_fab2_lib.baseboard_fab2(sch_1):page50_i50:vdd(0)" )
			)
			( pin "J6M1.233"
				( objectStatus "@baseboard_fab2_lib.baseboard_fab2(sch_1):page50_i50:vdd(1)" )
			)
			( pin "J6M1.231"
				( objectStatus "@baseboard_fab2_lib.baseboard_fab2(sch_1):page50_i50:vdd(2)" )
			)
			( pin "J6M1.229"
				( objectStatus "@baseboard_fab2_lib.baseboard_fab2(sch_1):page50_i50:vdd(3)" )
			)
			( pin "J6M1.226"
				( objectStatus "@baseboard_fab2_lib.baseboard_fab2(sch_1):page50_i50:vdd(4)" )
			)
			( pin "J6M1.223"
				( objectStatus "@baseboard_fab2_lib.baseboard_fab2(sch_1):page50_i50:vdd(5)" )
			)
			( pin "J6M1.220"
				( objectStatus "@baseboard_fab2_lib.baseboard_fab2(sch_1):page50_i50:vdd(6)" )
			)
			( pin "J6M1.217"
				( objectStatus "@baseboard_fab2_lib.baseboard_fab2(sch_1):page50_i50:vdd(7)" )
			)
			( pin "J6M1.215"
				( objectStatus "@baseboard_fab2_lib.baseboard_fab2(sch_1):page50_i50:vdd(8)" )
			)
			( pin "J6M1.212"
				( objectStatus "@baseboard_fab2_lib.baseboard_fab2(sch_1):page50_i50:vdd(9)" )
			)
			( pin "J6M1.209"
				( objectStatus "@baseboard_fab2_lib.baseboard_fab2(sch_1):page50_i50:vdd(10)" )
			)
			( pin "J6M1.206"
				( objectStatus "@baseboard_fab2_lib.baseboard_fab2(sch_1):page50_i50:vdd(11)" )
			)
			( pin "J6M1.204"
				( objectStatus "@baseboard_fab2_lib.baseboard_fab2(sch_1):page50_i50:vdd(12)" )
			)
			( pin "J6M1.92"
				( objectStatus "@baseboard_fab2_lib.baseboard_fab2(sch_1):page50_i50:vdd(13)" )
			)
			( pin "J6M1.90"
				( objectStatus "@baseboard_fab2_lib.baseboard_fab2(sch_1):page50_i50:vdd(14)" )
			)
			( pin "J6M1.88"
				( objectStatus "@baseboard_fab2_lib.baseboard_fab2(sch_1):page50_i50:vdd(15)" )
			)
			( pin "J6M1.85"
				( objectStatus "@baseboard_fab2_lib.baseboard_fab2(sch_1):page50_i50:vdd(16)" )
			)
			( pin "J6M1.83"
				( objectStatus "@baseboard_fab2_lib.baseboard_fab2(sch_1):page50_i50:vdd(17)" )
			)
			( pin "J6M1.80"
				( objectStatus "@baseboard_fab2_lib.baseboard_fab2(sch_1):page50_i50:vdd(18)" )
			)
			( pin "J6M1.76"
				( objectStatus "@baseboard_fab2_lib.baseboard_fab2(sch_1):page50_i50:vdd(19)" )
			)
			( pin "J6M1.73"
				( objectStatus "@baseboard_fab2_lib.baseboard_fab2(sch_1):page50_i50:vdd(20)" )
			)
			( pin "J6M1.70"
				( objectStatus "@baseboard_fab2_lib.baseboard_fab2(sch_1):page50_i50:vdd(21)" )
			)
			( pin "J6M1.67"
				( objectStatus "@baseboard_fab2_lib.baseboard_fab2(sch_1):page50_i50:vdd(22)" )
			)
			( pin "J6M1.64"
				( objectStatus "@baseboard_fab2_lib.baseboard_fab2(sch_1):page50_i50:vdd(23)" )
			)
			( pin "J6M1.61"
				( objectStatus "@baseboard_fab2_lib.baseboard_fab2(sch_1):page50_i50:vdd(24)" )
			)
			( pin "J6M1.59"
				( objectStatus "@baseboard_fab2_lib.baseboard_fab2(sch_1):page50_i50:vdd(25)" )
			)
			( pin "J6M1.287"
				( objectStatus "@baseboard_fab2_lib.baseboard_fab2(sch_1):page50_i50:vpp(0)" )
			)
			( pin "J6M1.286"
				( objectStatus "@baseboard_fab2_lib.baseboard_fab2(sch_1):page50_i50:vpp(1)" )
			)
			( pin "J6M1.288"
				( objectStatus "@baseboard_fab2_lib.baseboard_fab2(sch_1):page50_i50:vpp(2)" )
			)
			( pin "J6M1.143"
				( objectStatus "@baseboard_fab2_lib.baseboard_fab2(sch_1):page50_i50:vpp(3)" )
			)
			( pin "J6M1.142"
				( objectStatus "@baseboard_fab2_lib.baseboard_fab2(sch_1):page50_i50:vpp(4)" )
			)
			( pin "J6M1.221"
				( objectStatus "@baseboard_fab2_lib.baseboard_fab2(sch_1):page50_i50:vtt(0)" )
			)
			( pin "J6M1.77"
				( objectStatus "@baseboard_fab2_lib.baseboard_fab2(sch_1):page50_i50:vtt(1)" )
			)
			( pin "J6M1.79"
				( objectStatus "@baseboard_fab2_lib.baseboard_fab2(sch_1):page50_i158:a0" )
			)
			( pin "J6M1.72"
				( objectStatus "@baseboard_fab2_lib.baseboard_fab2(sch_1):page50_i158:a1" )
			)
			( pin "J6M1.216"
				( objectStatus "@baseboard_fab2_lib.baseboard_fab2(sch_1):page50_i158:a2" )
			)
			( pin "J6M1.71"
				( objectStatus "@baseboard_fab2_lib.baseboard_fab2(sch_1):page50_i158:a3" )
			)
			( pin "J6M1.214"
				( objectStatus "@baseboard_fab2_lib.baseboard_fab2(sch_1):page50_i158:a4" )
			)
			( pin "J6M1.213"
				( objectStatus "@baseboard_fab2_lib.baseboard_fab2(sch_1):page50_i158:a5" )
			)
			( pin "J6M1.69"
				( objectStatus "@baseboard_fab2_lib.baseboard_fab2(sch_1):page50_i158:a6" )
			)
			( pin "J6M1.211"
				( objectStatus "@baseboard_fab2_lib.baseboard_fab2(sch_1):page50_i158:a7" )
			)
			( pin "J6M1.68"
				( objectStatus "@baseboard_fab2_lib.baseboard_fab2(sch_1):page50_i158:a8" )
			)
			( pin "J6M1.66"
				( objectStatus "@baseboard_fab2_lib.baseboard_fab2(sch_1):page50_i158:a9" )
			)
			( pin "J6M1.225"
				( objectStatus "@baseboard_fab2_lib.baseboard_fab2(sch_1):page50_i158:a10" )
			)
			( pin "J6M1.210"
				( objectStatus "@baseboard_fab2_lib.baseboard_fab2(sch_1):page50_i158:a11" )
			)
			( pin "J6M1.65"
				( objectStatus "@baseboard_fab2_lib.baseboard_fab2(sch_1):page50_i158:a12" )
			)
			( pin "J6M1.232"
				( objectStatus "@baseboard_fab2_lib.baseboard_fab2(sch_1):page50_i158:a13" )
			)
			( pin "J6M1.228"
				( objectStatus "@baseboard_fab2_lib.baseboard_fab2(sch_1):page50_i158:a14_we_n" )
			)
			( pin "J6M1.86"
				( objectStatus "@baseboard_fab2_lib.baseboard_fab2(sch_1):page50_i158:a15_cas_n" )
			)
			( pin "J6M1.82"
				( objectStatus "@baseboard_fab2_lib.baseboard_fab2(sch_1):page50_i158:a16_ras_n" )
			)
			( pin "J6M1.234"
				( objectStatus "@baseboard_fab2_lib.baseboard_fab2(sch_1):page50_i158:a17" )
			)
			( pin "J6M1.62"
				( objectStatus "@baseboard_fab2_lib.baseboard_fab2(sch_1):page50_i158:act_n" )
			)
			( pin "J6M1.208"
				( objectStatus "@baseboard_fab2_lib.baseboard_fab2(sch_1):page50_i158:alert_n" )
			)
			( pin "J6M1.81"
				( objectStatus "@baseboard_fab2_lib.baseboard_fab2(sch_1):page50_i158:ba(0)" )
			)
			( pin "J6M1.224"
				( objectStatus "@baseboard_fab2_lib.baseboard_fab2(sch_1):page50_i158:ba(1)" )
			)
			( pin "J6M1.63"
				( objectStatus "@baseboard_fab2_lib.baseboard_fab2(sch_1):page50_i158:bg(0)" )
			)
			( pin "J6M1.207"
				( objectStatus "@baseboard_fab2_lib.baseboard_fab2(sch_1):page50_i158:bg(1)" )
			)
			( pin "J6M1.235"
				( objectStatus "@baseboard_fab2_lib.baseboard_fab2(sch_1):page50_i158:c(2)" )
			)
			( pin "J6M1.49"
				( objectStatus "@baseboard_fab2_lib.baseboard_fab2(sch_1):page50_i158:cb(0)" )
			)
			( pin "J6M1.194"
				( objectStatus "@baseboard_fab2_lib.baseboard_fab2(sch_1):page50_i158:cb(1)" )
			)
			( pin "J6M1.56"
				( objectStatus "@baseboard_fab2_lib.baseboard_fab2(sch_1):page50_i158:cb(2)" )
			)
			( pin "J6M1.201"
				( objectStatus "@baseboard_fab2_lib.baseboard_fab2(sch_1):page50_i158:cb(3)" )
			)
			( pin "J6M1.47"
				( objectStatus "@baseboard_fab2_lib.baseboard_fab2(sch_1):page50_i158:cb(4)" )
			)
			( pin "J6M1.192"
				( objectStatus "@baseboard_fab2_lib.baseboard_fab2(sch_1):page50_i158:cb(5)" )
			)
			( pin "J6M1.54"
				( objectStatus "@baseboard_fab2_lib.baseboard_fab2(sch_1):page50_i158:cb(6)" )
			)
			( pin "J6M1.199"
				( objectStatus "@baseboard_fab2_lib.baseboard_fab2(sch_1):page50_i158:cb(7)" )
			)
			( pin "J6M1.75"
				( objectStatus "@baseboard_fab2_lib.baseboard_fab2(sch_1):page50_i158:ck0n" )
			)
			( pin "J6M1.74"
				( objectStatus "@baseboard_fab2_lib.baseboard_fab2(sch_1):page50_i158:ck0p" )
			)
			( pin "J6M1.219"
				( objectStatus "@baseboard_fab2_lib.baseboard_fab2(sch_1):page50_i158:ck1n" )
			)
			( pin "J6M1.218"
				( objectStatus "@baseboard_fab2_lib.baseboard_fab2(sch_1):page50_i158:ck1p" )
			)
			( pin "J6M1.60"
				( objectStatus "@baseboard_fab2_lib.baseboard_fab2(sch_1):page50_i158:cke(0)" )
			)
			( pin "J6M1.203"
				( objectStatus "@baseboard_fab2_lib.baseboard_fab2(sch_1):page50_i158:cke(1)" )
			)
			( pin "J6M1.5"
				( objectStatus "@baseboard_fab2_lib.baseboard_fab2(sch_1):page50_i158:dq(0)" )
			)
			( pin "J6M1.150"
				( objectStatus "@baseboard_fab2_lib.baseboard_fab2(sch_1):page50_i158:dq(1)" )
			)
			( pin "J6M1.12"
				( objectStatus "@baseboard_fab2_lib.baseboard_fab2(sch_1):page50_i158:dq(2)" )
			)
			( pin "J6M1.157"
				( objectStatus "@baseboard_fab2_lib.baseboard_fab2(sch_1):page50_i158:dq(3)" )
			)
			( pin "J6M1.3"
				( objectStatus "@baseboard_fab2_lib.baseboard_fab2(sch_1):page50_i158:dq(4)" )
			)
			( pin "J6M1.148"
				( objectStatus "@baseboard_fab2_lib.baseboard_fab2(sch_1):page50_i158:dq(5)" )
			)
			( pin "J6M1.10"
				( objectStatus "@baseboard_fab2_lib.baseboard_fab2(sch_1):page50_i158:dq(6)" )
			)
			( pin "J6M1.155"
				( objectStatus "@baseboard_fab2_lib.baseboard_fab2(sch_1):page50_i158:dq(7)" )
			)
			( pin "J6M1.16"
				( objectStatus "@baseboard_fab2_lib.baseboard_fab2(sch_1):page50_i158:dq(8)" )
			)
			( pin "J6M1.161"
				( objectStatus "@baseboard_fab2_lib.baseboard_fab2(sch_1):page50_i158:dq(9)" )
			)
			( pin "J6M1.23"
				( objectStatus "@baseboard_fab2_lib.baseboard_fab2(sch_1):page50_i158:dq(10)" )
			)
			( pin "J6M1.168"
				( objectStatus "@baseboard_fab2_lib.baseboard_fab2(sch_1):page50_i158:dq(11)" )
			)
			( pin "J6M1.14"
				( objectStatus "@baseboard_fab2_lib.baseboard_fab2(sch_1):page50_i158:dq(12)" )
			)
			( pin "J6M1.159"
				( objectStatus "@baseboard_fab2_lib.baseboard_fab2(sch_1):page50_i158:dq(13)" )
			)
			( pin "J6M1.21"
				( objectStatus "@baseboard_fab2_lib.baseboard_fab2(sch_1):page50_i158:dq(14)" )
			)
			( pin "J6M1.166"
				( objectStatus "@baseboard_fab2_lib.baseboard_fab2(sch_1):page50_i158:dq(15)" )
			)
			( pin "J6M1.27"
				( objectStatus "@baseboard_fab2_lib.baseboard_fab2(sch_1):page50_i158:dq(16)" )
			)
			( pin "J6M1.172"
				( objectStatus "@baseboard_fab2_lib.baseboard_fab2(sch_1):page50_i158:dq(17)" )
			)
			( pin "J6M1.34"
				( objectStatus "@baseboard_fab2_lib.baseboard_fab2(sch_1):page50_i158:dq(18)" )
			)
			( pin "J6M1.179"
				( objectStatus "@baseboard_fab2_lib.baseboard_fab2(sch_1):page50_i158:dq(19)" )
			)
			( pin "J6M1.25"
				( objectStatus "@baseboard_fab2_lib.baseboard_fab2(sch_1):page50_i158:dq(20)" )
			)
			( pin "J6M1.170"
				( objectStatus "@baseboard_fab2_lib.baseboard_fab2(sch_1):page50_i158:dq(21)" )
			)
			( pin "J6M1.32"
				( objectStatus "@baseboard_fab2_lib.baseboard_fab2(sch_1):page50_i158:dq(22)" )
			)
			( pin "J6M1.177"
				( objectStatus "@baseboard_fab2_lib.baseboard_fab2(sch_1):page50_i158:dq(23)" )
			)
			( pin "J6M1.38"
				( objectStatus "@baseboard_fab2_lib.baseboard_fab2(sch_1):page50_i158:dq(24)" )
			)
			( pin "J6M1.183"
				( objectStatus "@baseboard_fab2_lib.baseboard_fab2(sch_1):page50_i158:dq(25)" )
			)
			( pin "J6M1.45"
				( objectStatus "@baseboard_fab2_lib.baseboard_fab2(sch_1):page50_i158:dq(26)" )
			)
			( pin "J6M1.190"
				( objectStatus "@baseboard_fab2_lib.baseboard_fab2(sch_1):page50_i158:dq(27)" )
			)
			( pin "J6M1.36"
				( objectStatus "@baseboard_fab2_lib.baseboard_fab2(sch_1):page50_i158:dq(28)" )
			)
			( pin "J6M1.181"
				( objectStatus "@baseboard_fab2_lib.baseboard_fab2(sch_1):page50_i158:dq(29)" )
			)
			( pin "J6M1.43"
				( objectStatus "@baseboard_fab2_lib.baseboard_fab2(sch_1):page50_i158:dq(30)" )
			)
			( pin "J6M1.188"
				( objectStatus "@baseboard_fab2_lib.baseboard_fab2(sch_1):page50_i158:dq(31)" )
			)
			( pin "J6M1.97"
				( objectStatus "@baseboard_fab2_lib.baseboard_fab2(sch_1):page50_i158:dq(32)" )
			)
			( pin "J6M1.242"
				( objectStatus "@baseboard_fab2_lib.baseboard_fab2(sch_1):page50_i158:dq(33)" )
			)
			( pin "J6M1.104"
				( objectStatus "@baseboard_fab2_lib.baseboard_fab2(sch_1):page50_i158:dq(34)" )
			)
			( pin "J6M1.249"
				( objectStatus "@baseboard_fab2_lib.baseboard_fab2(sch_1):page50_i158:dq(35)" )
			)
			( pin "J6M1.95"
				( objectStatus "@baseboard_fab2_lib.baseboard_fab2(sch_1):page50_i158:dq(36)" )
			)
			( pin "J6M1.240"
				( objectStatus "@baseboard_fab2_lib.baseboard_fab2(sch_1):page50_i158:dq(37)" )
			)
			( pin "J6M1.102"
				( objectStatus "@baseboard_fab2_lib.baseboard_fab2(sch_1):page50_i158:dq(38)" )
			)
			( pin "J6M1.247"
				( objectStatus "@baseboard_fab2_lib.baseboard_fab2(sch_1):page50_i158:dq(39)" )
			)
			( pin "J6M1.108"
				( objectStatus "@baseboard_fab2_lib.baseboard_fab2(sch_1):page50_i158:dq(40)" )
			)
			( pin "J6M1.253"
				( objectStatus "@baseboard_fab2_lib.baseboard_fab2(sch_1):page50_i158:dq(41)" )
			)
			( pin "J6M1.115"
				( objectStatus "@baseboard_fab2_lib.baseboard_fab2(sch_1):page50_i158:dq(42)" )
			)
			( pin "J6M1.260"
				( objectStatus "@baseboard_fab2_lib.baseboard_fab2(sch_1):page50_i158:dq(43)" )
			)
			( pin "J6M1.106"
				( objectStatus "@baseboard_fab2_lib.baseboard_fab2(sch_1):page50_i158:dq(44)" )
			)
			( pin "J6M1.251"
				( objectStatus "@baseboard_fab2_lib.baseboard_fab2(sch_1):page50_i158:dq(45)" )
			)
			( pin "J6M1.113"
				( objectStatus "@baseboard_fab2_lib.baseboard_fab2(sch_1):page50_i158:dq(46)" )
			)
			( pin "J6M1.258"
				( objectStatus "@baseboard_fab2_lib.baseboard_fab2(sch_1):page50_i158:dq(47)" )
			)
			( pin "J6M1.119"
				( objectStatus "@baseboard_fab2_lib.baseboard_fab2(sch_1):page50_i158:dq(48)" )
			)
			( pin "J6M1.264"
				( objectStatus "@baseboard_fab2_lib.baseboard_fab2(sch_1):page50_i158:dq(49)" )
			)
			( pin "J6M1.126"
				( objectStatus "@baseboard_fab2_lib.baseboard_fab2(sch_1):page50_i158:dq(50)" )
			)
			( pin "J6M1.271"
				( objectStatus "@baseboard_fab2_lib.baseboard_fab2(sch_1):page50_i158:dq(51)" )
			)
			( pin "J6M1.117"
				( objectStatus "@baseboard_fab2_lib.baseboard_fab2(sch_1):page50_i158:dq(52)" )
			)
			( pin "J6M1.262"
				( objectStatus "@baseboard_fab2_lib.baseboard_fab2(sch_1):page50_i158:dq(53)" )
			)
			( pin "J6M1.124"
				( objectStatus "@baseboard_fab2_lib.baseboard_fab2(sch_1):page50_i158:dq(54)" )
			)
			( pin "J6M1.269"
				( objectStatus "@baseboard_fab2_lib.baseboard_fab2(sch_1):page50_i158:dq(55)" )
			)
			( pin "J6M1.130"
				( objectStatus "@baseboard_fab2_lib.baseboard_fab2(sch_1):page50_i158:dq(56)" )
			)
			( pin "J6M1.275"
				( objectStatus "@baseboard_fab2_lib.baseboard_fab2(sch_1):page50_i158:dq(57)" )
			)
			( pin "J6M1.137"
				( objectStatus "@baseboard_fab2_lib.baseboard_fab2(sch_1):page50_i158:dq(58)" )
			)
			( pin "J6M1.282"
				( objectStatus "@baseboard_fab2_lib.baseboard_fab2(sch_1):page50_i158:dq(59)" )
			)
			( pin "J6M1.128"
				( objectStatus "@baseboard_fab2_lib.baseboard_fab2(sch_1):page50_i158:dq(60)" )
			)
			( pin "J6M1.273"
				( objectStatus "@baseboard_fab2_lib.baseboard_fab2(sch_1):page50_i158:dq(61)" )
			)
			( pin "J6M1.135"
				( objectStatus "@baseboard_fab2_lib.baseboard_fab2(sch_1):page50_i158:dq(62)" )
			)
			( pin "J6M1.280"
				( objectStatus "@baseboard_fab2_lib.baseboard_fab2(sch_1):page50_i158:dq(63)" )
			)
			( pin "J6M1.78"
				( objectStatus "@baseboard_fab2_lib.baseboard_fab2(sch_1):page50_i158:event_n" )
			)
			( pin "J6M1.87"
				( objectStatus "@baseboard_fab2_lib.baseboard_fab2(sch_1):page50_i158:odt(0)" )
			)
			( pin "J6M1.91"
				( objectStatus "@baseboard_fab2_lib.baseboard_fab2(sch_1):page50_i158:odt(1)" )
			)
			( pin "J6M1.222"
				( objectStatus "@baseboard_fab2_lib.baseboard_fab2(sch_1):page50_i158:par" )
			)
			( pin "J6M1.58"
				( objectStatus "@baseboard_fab2_lib.baseboard_fab2(sch_1):page50_i158:reset_n" )
			)
			( pin "J6M1.205"
				( objectStatus "@baseboard_fab2_lib.baseboard_fab2(sch_1):page50_i158:rfu(0)" )
			)
			( pin "J6M1.227"
				( objectStatus "@baseboard_fab2_lib.baseboard_fab2(sch_1):page50_i158:rfu(1)" )
			)
			( pin "J6M1.144"
				( objectStatus "@baseboard_fab2_lib.baseboard_fab2(sch_1):page50_i158:rfu(2)" )
			)
			( pin "J6M1.84"
				( objectStatus "@baseboard_fab2_lib.baseboard_fab2(sch_1):page50_i158:s0_n" )
			)
			( pin "J6M1.89"
				( objectStatus "@baseboard_fab2_lib.baseboard_fab2(sch_1):page50_i158:s1_n" )
			)
			( pin "J6M1.93"
				( objectStatus "@baseboard_fab2_lib.baseboard_fab2(sch_1):page50_i158:s2_n_c(0)" )
			)
			( pin "J6M1.237"
				( objectStatus "@baseboard_fab2_lib.baseboard_fab2(sch_1):page50_i158:s3_n_c(1)" )
			)
			( pin "J6M1.139"
				( objectStatus "@baseboard_fab2_lib.baseboard_fab2(sch_1):page50_i158:sa(0)" )
			)
			( pin "J6M1.140"
				( objectStatus "@baseboard_fab2_lib.baseboard_fab2(sch_1):page50_i158:sa(1)" )
			)
			( pin "J6M1.238"
				( objectStatus "@baseboard_fab2_lib.baseboard_fab2(sch_1):page50_i158:sa(2)" )
			)
			( pin "J6M1.230"
				( objectStatus "@baseboard_fab2_lib.baseboard_fab2(sch_1):page50_i158:save_n_nc" )
			)
			( pin "J6M1.141"
				( objectStatus "@baseboard_fab2_lib.baseboard_fab2(sch_1):page50_i158:scl" )
			)
			( pin "J6M1.285"
				( objectStatus "@baseboard_fab2_lib.baseboard_fab2(sch_1):page50_i158:sda" )
			)
			( pin "J6M1.284"
				( objectStatus "@baseboard_fab2_lib.baseboard_fab2(sch_1):page50_i158:vddspd" )
			)
			( pin "J6M1.146"
				( objectStatus "@baseboard_fab2_lib.baseboard_fab2(sch_1):page50_i158:vrefca" )
			)
			( pin "C6M1.1"
				( objectStatus "@baseboard_fab2_lib.baseboard_fab2(sch_1):page50_i177:a" )
			)
			( pin "C6M1.2"
				( objectStatus "@baseboard_fab2_lib.baseboard_fab2(sch_1):page50_i177:b" )
			)
			( pin "J4A2.283"
				( objectStatus "@baseboard_fab2_lib.baseboard_fab2(sch_1):page51_i43:vss(0)" )
			)
			( pin "J4A2.281"
				( objectStatus "@baseboard_fab2_lib.baseboard_fab2(sch_1):page51_i43:vss(1)" )
			)
			( pin "J4A2.279"
				( objectStatus "@baseboard_fab2_lib.baseboard_fab2(sch_1):page51_i43:vss(2)" )
			)
			( pin "J4A2.276"
				( objectStatus "@baseboard_fab2_lib.baseboard_fab2(sch_1):page51_i43:vss(3)" )
			)
			( pin "J4A2.274"
				( objectStatus "@baseboard_fab2_lib.baseboard_fab2(sch_1):page51_i43:vss(4)" )
			)
			( pin "J4A2.272"
				( objectStatus "@baseboard_fab2_lib.baseboard_fab2(sch_1):page51_i43:vss(5)" )
			)
			( pin "J4A2.270"
				( objectStatus "@baseboard_fab2_lib.baseboard_fab2(sch_1):page51_i43:vss(6)" )
			)
			( pin "J4A2.268"
				( objectStatus "@baseboard_fab2_lib.baseboard_fab2(sch_1):page51_i43:vss(7)" )
			)
			( pin "J4A2.265"
				( objectStatus "@baseboard_fab2_lib.baseboard_fab2(sch_1):page51_i43:vss(8)" )
			)
			( pin "J4A2.263"
				( objectStatus "@baseboard_fab2_lib.baseboard_fab2(sch_1):page51_i43:vss(9)" )
			)
			( pin "J4A2.261"
				( objectStatus "@baseboard_fab2_lib.baseboard_fab2(sch_1):page51_i43:vss(10)" )
			)
			( pin "J4A2.259"
				( objectStatus "@baseboard_fab2_lib.baseboard_fab2(sch_1):page51_i43:vss(11)" )
			)
			( pin "J4A2.257"
				( objectStatus "@baseboard_fab2_lib.baseboard_fab2(sch_1):page51_i43:vss(12)" )
			)
			( pin "J4A2.254"
				( objectStatus "@baseboard_fab2_lib.baseboard_fab2(sch_1):page51_i43:vss(13)" )
			)
			( pin "J4A2.252"
				( objectStatus "@baseboard_fab2_lib.baseboard_fab2(sch_1):page51_i43:vss(14)" )
			)
			( pin "J4A2.250"
				( objectStatus "@baseboard_fab2_lib.baseboard_fab2(sch_1):page51_i43:vss(15)" )
			)
			( pin "J4A2.248"
				( objectStatus "@baseboard_fab2_lib.baseboard_fab2(sch_1):page51_i43:vss(16)" )
			)
			( pin "J4A2.246"
				( objectStatus "@baseboard_fab2_lib.baseboard_fab2(sch_1):page51_i43:vss(17)" )
			)
			( pin "J4A2.243"
				( objectStatus "@baseboard_fab2_lib.baseboard_fab2(sch_1):page51_i43:vss(18)" )
			)
			( pin "J4A2.241"
				( objectStatus "@baseboard_fab2_lib.baseboard_fab2(sch_1):page51_i43:vss(19)" )
			)
			( pin "J4A2.239"
				( objectStatus "@baseboard_fab2_lib.baseboard_fab2(sch_1):page51_i43:vss(20)" )
			)
			( pin "J4A2.202"
				( objectStatus "@baseboard_fab2_lib.baseboard_fab2(sch_1):page51_i43:vss(21)" )
			)
			( pin "J4A2.200"
				( objectStatus "@baseboard_fab2_lib.baseboard_fab2(sch_1):page51_i43:vss(22)" )
			)
			( pin "J4A2.198"
				( objectStatus "@baseboard_fab2_lib.baseboard_fab2(sch_1):page51_i43:vss(23)" )
			)
			( pin "J4A2.195"
				( objectStatus "@baseboard_fab2_lib.baseboard_fab2(sch_1):page51_i43:vss(24)" )
			)
			( pin "J4A2.193"
				( objectStatus "@baseboard_fab2_lib.baseboard_fab2(sch_1):page51_i43:vss(25)" )
			)
			( pin "J4A2.191"
				( objectStatus "@baseboard_fab2_lib.baseboard_fab2(sch_1):page51_i43:vss(26)" )
			)
			( pin "J4A2.189"
				( objectStatus "@baseboard_fab2_lib.baseboard_fab2(sch_1):page51_i43:vss(27)" )
			)
			( pin "J4A2.187"
				( objectStatus "@baseboard_fab2_lib.baseboard_fab2(sch_1):page51_i43:vss(28)" )
			)
			( pin "J4A2.184"
				( objectStatus "@baseboard_fab2_lib.baseboard_fab2(sch_1):page51_i43:vss(29)" )
			)
			( pin "J4A2.182"
				( objectStatus "@baseboard_fab2_lib.baseboard_fab2(sch_1):page51_i43:vss(30)" )
			)
			( pin "J4A2.180"
				( objectStatus "@baseboard_fab2_lib.baseboard_fab2(sch_1):page51_i43:vss(31)" )
			)
			( pin "J4A2.178"
				( objectStatus "@baseboard_fab2_lib.baseboard_fab2(sch_1):page51_i43:vss(32)" )
			)
			( pin "J4A2.176"
				( objectStatus "@baseboard_fab2_lib.baseboard_fab2(sch_1):page51_i43:vss(33)" )
			)
			( pin "J4A2.173"
				( objectStatus "@baseboard_fab2_lib.baseboard_fab2(sch_1):page51_i43:vss(34)" )
			)
			( pin "J4A2.171"
				( objectStatus "@baseboard_fab2_lib.baseboard_fab2(sch_1):page51_i43:vss(35)" )
			)
			( pin "J4A2.169"
				( objectStatus "@baseboard_fab2_lib.baseboard_fab2(sch_1):page51_i43:vss(36)" )
			)
			( pin "J4A2.167"
				( objectStatus "@baseboard_fab2_lib.baseboard_fab2(sch_1):page51_i43:vss(37)" )
			)
			( pin "J4A2.165"
				( objectStatus "@baseboard_fab2_lib.baseboard_fab2(sch_1):page51_i43:vss(38)" )
			)
			( pin "J4A2.162"
				( objectStatus "@baseboard_fab2_lib.baseboard_fab2(sch_1):page51_i43:vss(39)" )
			)
			( pin "J4A2.160"
				( objectStatus "@baseboard_fab2_lib.baseboard_fab2(sch_1):page51_i43:vss(40)" )
			)
			( pin "J4A2.158"
				( objectStatus "@baseboard_fab2_lib.baseboard_fab2(sch_1):page51_i43:vss(41)" )
			)
			( pin "J4A2.156"
				( objectStatus "@baseboard_fab2_lib.baseboard_fab2(sch_1):page51_i43:vss(42)" )
			)
			( pin "J4A2.154"
				( objectStatus "@baseboard_fab2_lib.baseboard_fab2(sch_1):page51_i43:vss(43)" )
			)
			( pin "J4A2.151"
				( objectStatus "@baseboard_fab2_lib.baseboard_fab2(sch_1):page51_i43:vss(44)" )
			)
			( pin "J4A2.149"
				( objectStatus "@baseboard_fab2_lib.baseboard_fab2(sch_1):page51_i43:vss(45)" )
			)
			( pin "J4A2.147"
				( objectStatus "@baseboard_fab2_lib.baseboard_fab2(sch_1):page51_i43:vss(46)" )
			)
			( pin "J4A2.138"
				( objectStatus "@baseboard_fab2_lib.baseboard_fab2(sch_1):page51_i43:vss(47)" )
			)
			( pin "J4A2.136"
				( objectStatus "@baseboard_fab2_lib.baseboard_fab2(sch_1):page51_i43:vss(48)" )
			)
			( pin "J4A2.134"
				( objectStatus "@baseboard_fab2_lib.baseboard_fab2(sch_1):page51_i43:vss(49)" )
			)
			( pin "J4A2.131"
				( objectStatus "@baseboard_fab2_lib.baseboard_fab2(sch_1):page51_i43:vss(50)" )
			)
			( pin "J4A2.129"
				( objectStatus "@baseboard_fab2_lib.baseboard_fab2(sch_1):page51_i43:vss(51)" )
			)
			( pin "J4A2.127"
				( objectStatus "@baseboard_fab2_lib.baseboard_fab2(sch_1):page51_i43:vss(52)" )
			)
			( pin "J4A2.125"
				( objectStatus "@baseboard_fab2_lib.baseboard_fab2(sch_1):page51_i43:vss(53)" )
			)
			( pin "J4A2.123"
				( objectStatus "@baseboard_fab2_lib.baseboard_fab2(sch_1):page51_i43:vss(54)" )
			)
			( pin "J4A2.120"
				( objectStatus "@baseboard_fab2_lib.baseboard_fab2(sch_1):page51_i43:vss(55)" )
			)
			( pin "J4A2.118"
				( objectStatus "@baseboard_fab2_lib.baseboard_fab2(sch_1):page51_i43:vss(56)" )
			)
			( pin "J4A2.116"
				( objectStatus "@baseboard_fab2_lib.baseboard_fab2(sch_1):page51_i43:vss(57)" )
			)
			( pin "J4A2.114"
				( objectStatus "@baseboard_fab2_lib.baseboard_fab2(sch_1):page51_i43:vss(58)" )
			)
			( pin "J4A2.112"
				( objectStatus "@baseboard_fab2_lib.baseboard_fab2(sch_1):page51_i43:vss(59)" )
			)
			( pin "J4A2.109"
				( objectStatus "@baseboard_fab2_lib.baseboard_fab2(sch_1):page51_i43:vss(60)" )
			)
			( pin "J4A2.107"
				( objectStatus "@baseboard_fab2_lib.baseboard_fab2(sch_1):page51_i43:vss(61)" )
			)
			( pin "J4A2.105"
				( objectStatus "@baseboard_fab2_lib.baseboard_fab2(sch_1):page51_i43:vss(62)" )
			)
			( pin "J4A2.103"
				( objectStatus "@baseboard_fab2_lib.baseboard_fab2(sch_1):page51_i43:vss(63)" )
			)
			( pin "J4A2.101"
				( objectStatus "@baseboard_fab2_lib.baseboard_fab2(sch_1):page51_i43:vss(64)" )
			)
			( pin "J4A2.98"
				( objectStatus "@baseboard_fab2_lib.baseboard_fab2(sch_1):page51_i43:vss(65)" )
			)
			( pin "J4A2.96"
				( objectStatus "@baseboard_fab2_lib.baseboard_fab2(sch_1):page51_i43:vss(66)" )
			)
			( pin "J4A2.94"
				( objectStatus "@baseboard_fab2_lib.baseboard_fab2(sch_1):page51_i43:vss(67)" )
			)
			( pin "J4A2.57"
				( objectStatus "@baseboard_fab2_lib.baseboard_fab2(sch_1):page51_i43:vss(68)" )
			)
			( pin "J4A2.55"
				( objectStatus "@baseboard_fab2_lib.baseboard_fab2(sch_1):page51_i43:vss(69)" )
			)
			( pin "J4A2.53"
				( objectStatus "@baseboard_fab2_lib.baseboard_fab2(sch_1):page51_i43:vss(70)" )
			)
			( pin "J4A2.50"
				( objectStatus "@baseboard_fab2_lib.baseboard_fab2(sch_1):page51_i43:vss(71)" )
			)
			( pin "J4A2.48"
				( objectStatus "@baseboard_fab2_lib.baseboard_fab2(sch_1):page51_i43:vss(72)" )
			)
			( pin "J4A2.46"
				( objectStatus "@baseboard_fab2_lib.baseboard_fab2(sch_1):page51_i43:vss(73)" )
			)
			( pin "J4A2.44"
				( objectStatus "@baseboard_fab2_lib.baseboard_fab2(sch_1):page51_i43:vss(74)" )
			)
			( pin "J4A2.42"
				( objectStatus "@baseboard_fab2_lib.baseboard_fab2(sch_1):page51_i43:vss(75)" )
			)
			( pin "J4A2.39"
				( objectStatus "@baseboard_fab2_lib.baseboard_fab2(sch_1):page51_i43:vss(76)" )
			)
			( pin "J4A2.37"
				( objectStatus "@baseboard_fab2_lib.baseboard_fab2(sch_1):page51_i43:vss(77)" )
			)
			( pin "J4A2.35"
				( objectStatus "@baseboard_fab2_lib.baseboard_fab2(sch_1):page51_i43:vss(78)" )
			)
			( pin "J4A2.33"
				( objectStatus "@baseboard_fab2_lib.baseboard_fab2(sch_1):page51_i43:vss(79)" )
			)
			( pin "J4A2.31"
				( objectStatus "@baseboard_fab2_lib.baseboard_fab2(sch_1):page51_i43:vss(80)" )
			)
			( pin "J4A2.28"
				( objectStatus "@baseboard_fab2_lib.baseboard_fab2(sch_1):page51_i43:vss(81)" )
			)
			( pin "J4A2.26"
				( objectStatus "@baseboard_fab2_lib.baseboard_fab2(sch_1):page51_i43:vss(82)" )
			)
			( pin "J4A2.24"
				( objectStatus "@baseboard_fab2_lib.baseboard_fab2(sch_1):page51_i43:vss(83)" )
			)
			( pin "J4A2.22"
				( objectStatus "@baseboard_fab2_lib.baseboard_fab2(sch_1):page51_i43:vss(84)" )
			)
			( pin "J4A2.20"
				( objectStatus "@baseboard_fab2_lib.baseboard_fab2(sch_1):page51_i43:vss(85)" )
			)
			( pin "J4A2.17"
				( objectStatus "@baseboard_fab2_lib.baseboard_fab2(sch_1):page51_i43:vss(86)" )
			)
			( pin "J4A2.15"
				( objectStatus "@baseboard_fab2_lib.baseboard_fab2(sch_1):page51_i43:vss(87)" )
			)
			( pin "J4A2.13"
				( objectStatus "@baseboard_fab2_lib.baseboard_fab2(sch_1):page51_i43:vss(88)" )
			)
			( pin "J4A2.11"
				( objectStatus "@baseboard_fab2_lib.baseboard_fab2(sch_1):page51_i43:vss(89)" )
			)
			( pin "J4A2.9"
				( objectStatus "@baseboard_fab2_lib.baseboard_fab2(sch_1):page51_i43:vss(90)" )
			)
			( pin "J4A2.6"
				( objectStatus "@baseboard_fab2_lib.baseboard_fab2(sch_1):page51_i43:vss(91)" )
			)
			( pin "J4A2.4"
				( objectStatus "@baseboard_fab2_lib.baseboard_fab2(sch_1):page51_i43:vss(92)" )
			)
			( pin "J4A2.2"
				( objectStatus "@baseboard_fab2_lib.baseboard_fab2(sch_1):page51_i43:vss(93)" )
			)
			( pin "J4A2.152"
				( objectStatus "@baseboard_fab2_lib.baseboard_fab2(sch_1):page51_i66:dqs0n" )
			)
			( pin "J4A2.153"
				( objectStatus "@baseboard_fab2_lib.baseboard_fab2(sch_1):page51_i66:dqs0p" )
			)
			( pin "J4A2.163"
				( objectStatus "@baseboard_fab2_lib.baseboard_fab2(sch_1):page51_i66:dqs1n" )
			)
			( pin "J4A2.164"
				( objectStatus "@baseboard_fab2_lib.baseboard_fab2(sch_1):page51_i66:dqs1p" )
			)
			( pin "J4A2.174"
				( objectStatus "@baseboard_fab2_lib.baseboard_fab2(sch_1):page51_i66:dqs2n" )
			)
			( pin "J4A2.175"
				( objectStatus "@baseboard_fab2_lib.baseboard_fab2(sch_1):page51_i66:dqs2p" )
			)
			( pin "J4A2.185"
				( objectStatus "@baseboard_fab2_lib.baseboard_fab2(sch_1):page51_i66:dqs3n" )
			)
			( pin "J4A2.186"
				( objectStatus "@baseboard_fab2_lib.baseboard_fab2(sch_1):page51_i66:dqs3p" )
			)
			( pin "J4A2.244"
				( objectStatus "@baseboard_fab2_lib.baseboard_fab2(sch_1):page51_i66:dqs4n" )
			)
			( pin "J4A2.245"
				( objectStatus "@baseboard_fab2_lib.baseboard_fab2(sch_1):page51_i66:dqs4p" )
			)
			( pin "J4A2.255"
				( objectStatus "@baseboard_fab2_lib.baseboard_fab2(sch_1):page51_i66:dqs5n" )
			)
			( pin "J4A2.256"
				( objectStatus "@baseboard_fab2_lib.baseboard_fab2(sch_1):page51_i66:dqs5p" )
			)
			( pin "J4A2.266"
				( objectStatus "@baseboard_fab2_lib.baseboard_fab2(sch_1):page51_i66:dqs6n" )
			)
			( pin "J4A2.267"
				( objectStatus "@baseboard_fab2_lib.baseboard_fab2(sch_1):page51_i66:dqs6p" )
			)
			( pin "J4A2.277"
				( objectStatus "@baseboard_fab2_lib.baseboard_fab2(sch_1):page51_i66:dqs7n" )
			)
			( pin "J4A2.278"
				( objectStatus "@baseboard_fab2_lib.baseboard_fab2(sch_1):page51_i66:dqs7p" )
			)
			( pin "J4A2.196"
				( objectStatus "@baseboard_fab2_lib.baseboard_fab2(sch_1):page51_i66:dqs8n" )
			)
			( pin "J4A2.197"
				( objectStatus "@baseboard_fab2_lib.baseboard_fab2(sch_1):page51_i66:dqs8p" )
			)
			( pin "J4A2.8"
				( objectStatus "@baseboard_fab2_lib.baseboard_fab2(sch_1):page51_i66:dqs9n" )
			)
			( pin "J4A2.7"
				( objectStatus "@baseboard_fab2_lib.baseboard_fab2(sch_1):page51_i66:dqs9p" )
			)
			( pin "J4A2.19"
				( objectStatus "@baseboard_fab2_lib.baseboard_fab2(sch_1):page51_i66:dqs10n" )
			)
			( pin "J4A2.18"
				( objectStatus "@baseboard_fab2_lib.baseboard_fab2(sch_1):page51_i66:dqs10p" )
			)
			( pin "J4A2.30"
				( objectStatus "@baseboard_fab2_lib.baseboard_fab2(sch_1):page51_i66:dqs11n" )
			)
			( pin "J4A2.29"
				( objectStatus "@baseboard_fab2_lib.baseboard_fab2(sch_1):page51_i66:dqs11p" )
			)
			( pin "J4A2.41"
				( objectStatus "@baseboard_fab2_lib.baseboard_fab2(sch_1):page51_i66:dqs12n" )
			)
			( pin "J4A2.40"
				( objectStatus "@baseboard_fab2_lib.baseboard_fab2(sch_1):page51_i66:dqs12p" )
			)
			( pin "J4A2.100"
				( objectStatus "@baseboard_fab2_lib.baseboard_fab2(sch_1):page51_i66:dqs13n" )
			)
			( pin "J4A2.99"
				( objectStatus "@baseboard_fab2_lib.baseboard_fab2(sch_1):page51_i66:dqs13p" )
			)
			( pin "J4A2.111"
				( objectStatus "@baseboard_fab2_lib.baseboard_fab2(sch_1):page51_i66:dqs14n" )
			)
			( pin "J4A2.110"
				( objectStatus "@baseboard_fab2_lib.baseboard_fab2(sch_1):page51_i66:dqs14p" )
			)
			( pin "J4A2.122"
				( objectStatus "@baseboard_fab2_lib.baseboard_fab2(sch_1):page51_i66:dqs15n" )
			)
			( pin "J4A2.121"
				( objectStatus "@baseboard_fab2_lib.baseboard_fab2(sch_1):page51_i66:dqs15p" )
			)
			( pin "J4A2.133"
				( objectStatus "@baseboard_fab2_lib.baseboard_fab2(sch_1):page51_i66:dqs16n" )
			)
			( pin "J4A2.132"
				( objectStatus "@baseboard_fab2_lib.baseboard_fab2(sch_1):page51_i66:dqs16p" )
			)
			( pin "J4A2.52"
				( objectStatus "@baseboard_fab2_lib.baseboard_fab2(sch_1):page51_i66:dqs17n" )
			)
			( pin "J4A2.51"
				( objectStatus "@baseboard_fab2_lib.baseboard_fab2(sch_1):page51_i66:dqs17p" )
			)
			( pin "J4A2.79"
				( objectStatus "@baseboard_fab2_lib.baseboard_fab2(sch_1):page51_i111:a0" )
			)
			( pin "J4A2.72"
				( objectStatus "@baseboard_fab2_lib.baseboard_fab2(sch_1):page51_i111:a1" )
			)
			( pin "J4A2.216"
				( objectStatus "@baseboard_fab2_lib.baseboard_fab2(sch_1):page51_i111:a2" )
			)
			( pin "J4A2.71"
				( objectStatus "@baseboard_fab2_lib.baseboard_fab2(sch_1):page51_i111:a3" )
			)
			( pin "J4A2.214"
				( objectStatus "@baseboard_fab2_lib.baseboard_fab2(sch_1):page51_i111:a4" )
			)
			( pin "J4A2.213"
				( objectStatus "@baseboard_fab2_lib.baseboard_fab2(sch_1):page51_i111:a5" )
			)
			( pin "J4A2.69"
				( objectStatus "@baseboard_fab2_lib.baseboard_fab2(sch_1):page51_i111:a6" )
			)
			( pin "J4A2.211"
				( objectStatus "@baseboard_fab2_lib.baseboard_fab2(sch_1):page51_i111:a7" )
			)
			( pin "J4A2.68"
				( objectStatus "@baseboard_fab2_lib.baseboard_fab2(sch_1):page51_i111:a8" )
			)
			( pin "J4A2.66"
				( objectStatus "@baseboard_fab2_lib.baseboard_fab2(sch_1):page51_i111:a9" )
			)
			( pin "J4A2.225"
				( objectStatus "@baseboard_fab2_lib.baseboard_fab2(sch_1):page51_i111:a10" )
			)
			( pin "J4A2.210"
				( objectStatus "@baseboard_fab2_lib.baseboard_fab2(sch_1):page51_i111:a11" )
			)
			( pin "J4A2.65"
				( objectStatus "@baseboard_fab2_lib.baseboard_fab2(sch_1):page51_i111:a12" )
			)
			( pin "J4A2.232"
				( objectStatus "@baseboard_fab2_lib.baseboard_fab2(sch_1):page51_i111:a13" )
			)
			( pin "J4A2.228"
				( objectStatus "@baseboard_fab2_lib.baseboard_fab2(sch_1):page51_i111:a14_we_n" )
			)
			( pin "J4A2.86"
				( objectStatus "@baseboard_fab2_lib.baseboard_fab2(sch_1):page51_i111:a15_cas_n" )
			)
			( pin "J4A2.82"
				( objectStatus "@baseboard_fab2_lib.baseboard_fab2(sch_1):page51_i111:a16_ras_n" )
			)
			( pin "J4A2.234"
				( objectStatus "@baseboard_fab2_lib.baseboard_fab2(sch_1):page51_i111:a17" )
			)
			( pin "J4A2.62"
				( objectStatus "@baseboard_fab2_lib.baseboard_fab2(sch_1):page51_i111:act_n" )
			)
			( pin "J4A2.208"
				( objectStatus "@baseboard_fab2_lib.baseboard_fab2(sch_1):page51_i111:alert_n" )
			)
			( pin "J4A2.81"
				( objectStatus "@baseboard_fab2_lib.baseboard_fab2(sch_1):page51_i111:ba(0)" )
			)
			( pin "J4A2.224"
				( objectStatus "@baseboard_fab2_lib.baseboard_fab2(sch_1):page51_i111:ba(1)" )
			)
			( pin "J4A2.63"
				( objectStatus "@baseboard_fab2_lib.baseboard_fab2(sch_1):page51_i111:bg(0)" )
			)
			( pin "J4A2.207"
				( objectStatus "@baseboard_fab2_lib.baseboard_fab2(sch_1):page51_i111:bg(1)" )
			)
			( pin "J4A2.235"
				( objectStatus "@baseboard_fab2_lib.baseboard_fab2(sch_1):page51_i111:c(2)" )
			)
			( pin "J4A2.49"
				( objectStatus "@baseboard_fab2_lib.baseboard_fab2(sch_1):page51_i111:cb(0)" )
			)
			( pin "J4A2.194"
				( objectStatus "@baseboard_fab2_lib.baseboard_fab2(sch_1):page51_i111:cb(1)" )
			)
			( pin "J4A2.56"
				( objectStatus "@baseboard_fab2_lib.baseboard_fab2(sch_1):page51_i111:cb(2)" )
			)
			( pin "J4A2.201"
				( objectStatus "@baseboard_fab2_lib.baseboard_fab2(sch_1):page51_i111:cb(3)" )
			)
			( pin "J4A2.47"
				( objectStatus "@baseboard_fab2_lib.baseboard_fab2(sch_1):page51_i111:cb(4)" )
			)
			( pin "J4A2.192"
				( objectStatus "@baseboard_fab2_lib.baseboard_fab2(sch_1):page51_i111:cb(5)" )
			)
			( pin "J4A2.54"
				( objectStatus "@baseboard_fab2_lib.baseboard_fab2(sch_1):page51_i111:cb(6)" )
			)
			( pin "J4A2.199"
				( objectStatus "@baseboard_fab2_lib.baseboard_fab2(sch_1):page51_i111:cb(7)" )
			)
			( pin "J4A2.75"
				( objectStatus "@baseboard_fab2_lib.baseboard_fab2(sch_1):page51_i111:ck0n" )
			)
			( pin "J4A2.74"
				( objectStatus "@baseboard_fab2_lib.baseboard_fab2(sch_1):page51_i111:ck0p" )
			)
			( pin "J4A2.219"
				( objectStatus "@baseboard_fab2_lib.baseboard_fab2(sch_1):page51_i111:ck1n" )
			)
			( pin "J4A2.218"
				( objectStatus "@baseboard_fab2_lib.baseboard_fab2(sch_1):page51_i111:ck1p" )
			)
			( pin "J4A2.60"
				( objectStatus "@baseboard_fab2_lib.baseboard_fab2(sch_1):page51_i111:cke(0)" )
			)
			( pin "J4A2.203"
				( objectStatus "@baseboard_fab2_lib.baseboard_fab2(sch_1):page51_i111:cke(1)" )
			)
			( pin "J4A2.5"
				( objectStatus "@baseboard_fab2_lib.baseboard_fab2(sch_1):page51_i111:dq(0)" )
			)
			( pin "J4A2.150"
				( objectStatus "@baseboard_fab2_lib.baseboard_fab2(sch_1):page51_i111:dq(1)" )
			)
			( pin "J4A2.12"
				( objectStatus "@baseboard_fab2_lib.baseboard_fab2(sch_1):page51_i111:dq(2)" )
			)
			( pin "J4A2.157"
				( objectStatus "@baseboard_fab2_lib.baseboard_fab2(sch_1):page51_i111:dq(3)" )
			)
			( pin "J4A2.3"
				( objectStatus "@baseboard_fab2_lib.baseboard_fab2(sch_1):page51_i111:dq(4)" )
			)
			( pin "J4A2.148"
				( objectStatus "@baseboard_fab2_lib.baseboard_fab2(sch_1):page51_i111:dq(5)" )
			)
			( pin "J4A2.10"
				( objectStatus "@baseboard_fab2_lib.baseboard_fab2(sch_1):page51_i111:dq(6)" )
			)
			( pin "J4A2.155"
				( objectStatus "@baseboard_fab2_lib.baseboard_fab2(sch_1):page51_i111:dq(7)" )
			)
			( pin "J4A2.16"
				( objectStatus "@baseboard_fab2_lib.baseboard_fab2(sch_1):page51_i111:dq(8)" )
			)
			( pin "J4A2.161"
				( objectStatus "@baseboard_fab2_lib.baseboard_fab2(sch_1):page51_i111:dq(9)" )
			)
			( pin "J4A2.23"
				( objectStatus "@baseboard_fab2_lib.baseboard_fab2(sch_1):page51_i111:dq(10)" )
			)
			( pin "J4A2.168"
				( objectStatus "@baseboard_fab2_lib.baseboard_fab2(sch_1):page51_i111:dq(11)" )
			)
			( pin "J4A2.14"
				( objectStatus "@baseboard_fab2_lib.baseboard_fab2(sch_1):page51_i111:dq(12)" )
			)
			( pin "J4A2.159"
				( objectStatus "@baseboard_fab2_lib.baseboard_fab2(sch_1):page51_i111:dq(13)" )
			)
			( pin "J4A2.21"
				( objectStatus "@baseboard_fab2_lib.baseboard_fab2(sch_1):page51_i111:dq(14)" )
			)
			( pin "J4A2.166"
				( objectStatus "@baseboard_fab2_lib.baseboard_fab2(sch_1):page51_i111:dq(15)" )
			)
			( pin "J4A2.27"
				( objectStatus "@baseboard_fab2_lib.baseboard_fab2(sch_1):page51_i111:dq(16)" )
			)
			( pin "J4A2.172"
				( objectStatus "@baseboard_fab2_lib.baseboard_fab2(sch_1):page51_i111:dq(17)" )
			)
			( pin "J4A2.34"
				( objectStatus "@baseboard_fab2_lib.baseboard_fab2(sch_1):page51_i111:dq(18)" )
			)
			( pin "J4A2.179"
				( objectStatus "@baseboard_fab2_lib.baseboard_fab2(sch_1):page51_i111:dq(19)" )
			)
			( pin "J4A2.25"
				( objectStatus "@baseboard_fab2_lib.baseboard_fab2(sch_1):page51_i111:dq(20)" )
			)
			( pin "J4A2.170"
				( objectStatus "@baseboard_fab2_lib.baseboard_fab2(sch_1):page51_i111:dq(21)" )
			)
			( pin "J4A2.32"
				( objectStatus "@baseboard_fab2_lib.baseboard_fab2(sch_1):page51_i111:dq(22)" )
			)
			( pin "J4A2.177"
				( objectStatus "@baseboard_fab2_lib.baseboard_fab2(sch_1):page51_i111:dq(23)" )
			)
			( pin "J4A2.38"
				( objectStatus "@baseboard_fab2_lib.baseboard_fab2(sch_1):page51_i111:dq(24)" )
			)
			( pin "J4A2.183"
				( objectStatus "@baseboard_fab2_lib.baseboard_fab2(sch_1):page51_i111:dq(25)" )
			)
			( pin "J4A2.45"
				( objectStatus "@baseboard_fab2_lib.baseboard_fab2(sch_1):page51_i111:dq(26)" )
			)
			( pin "J4A2.190"
				( objectStatus "@baseboard_fab2_lib.baseboard_fab2(sch_1):page51_i111:dq(27)" )
			)
			( pin "J4A2.36"
				( objectStatus "@baseboard_fab2_lib.baseboard_fab2(sch_1):page51_i111:dq(28)" )
			)
			( pin "J4A2.181"
				( objectStatus "@baseboard_fab2_lib.baseboard_fab2(sch_1):page51_i111:dq(29)" )
			)
			( pin "J4A2.43"
				( objectStatus "@baseboard_fab2_lib.baseboard_fab2(sch_1):page51_i111:dq(30)" )
			)
			( pin "J4A2.188"
				( objectStatus "@baseboard_fab2_lib.baseboard_fab2(sch_1):page51_i111:dq(31)" )
			)
			( pin "J4A2.97"
				( objectStatus "@baseboard_fab2_lib.baseboard_fab2(sch_1):page51_i111:dq(32)" )
			)
			( pin "J4A2.242"
				( objectStatus "@baseboard_fab2_lib.baseboard_fab2(sch_1):page51_i111:dq(33)" )
			)
			( pin "J4A2.104"
				( objectStatus "@baseboard_fab2_lib.baseboard_fab2(sch_1):page51_i111:dq(34)" )
			)
			( pin "J4A2.249"
				( objectStatus "@baseboard_fab2_lib.baseboard_fab2(sch_1):page51_i111:dq(35)" )
			)
			( pin "J4A2.95"
				( objectStatus "@baseboard_fab2_lib.baseboard_fab2(sch_1):page51_i111:dq(36)" )
			)
			( pin "J4A2.240"
				( objectStatus "@baseboard_fab2_lib.baseboard_fab2(sch_1):page51_i111:dq(37)" )
			)
			( pin "J4A2.102"
				( objectStatus "@baseboard_fab2_lib.baseboard_fab2(sch_1):page51_i111:dq(38)" )
			)
			( pin "J4A2.247"
				( objectStatus "@baseboard_fab2_lib.baseboard_fab2(sch_1):page51_i111:dq(39)" )
			)
			( pin "J4A2.108"
				( objectStatus "@baseboard_fab2_lib.baseboard_fab2(sch_1):page51_i111:dq(40)" )
			)
			( pin "J4A2.253"
				( objectStatus "@baseboard_fab2_lib.baseboard_fab2(sch_1):page51_i111:dq(41)" )
			)
			( pin "J4A2.115"
				( objectStatus "@baseboard_fab2_lib.baseboard_fab2(sch_1):page51_i111:dq(42)" )
			)
			( pin "J4A2.260"
				( objectStatus "@baseboard_fab2_lib.baseboard_fab2(sch_1):page51_i111:dq(43)" )
			)
			( pin "J4A2.106"
				( objectStatus "@baseboard_fab2_lib.baseboard_fab2(sch_1):page51_i111:dq(44)" )
			)
			( pin "J4A2.251"
				( objectStatus "@baseboard_fab2_lib.baseboard_fab2(sch_1):page51_i111:dq(45)" )
			)
			( pin "J4A2.113"
				( objectStatus "@baseboard_fab2_lib.baseboard_fab2(sch_1):page51_i111:dq(46)" )
			)
			( pin "J4A2.258"
				( objectStatus "@baseboard_fab2_lib.baseboard_fab2(sch_1):page51_i111:dq(47)" )
			)
			( pin "J4A2.119"
				( objectStatus "@baseboard_fab2_lib.baseboard_fab2(sch_1):page51_i111:dq(48)" )
			)
			( pin "J4A2.264"
				( objectStatus "@baseboard_fab2_lib.baseboard_fab2(sch_1):page51_i111:dq(49)" )
			)
			( pin "J4A2.126"
				( objectStatus "@baseboard_fab2_lib.baseboard_fab2(sch_1):page51_i111:dq(50)" )
			)
			( pin "J4A2.271"
				( objectStatus "@baseboard_fab2_lib.baseboard_fab2(sch_1):page51_i111:dq(51)" )
			)
			( pin "J4A2.117"
				( objectStatus "@baseboard_fab2_lib.baseboard_fab2(sch_1):page51_i111:dq(52)" )
			)
			( pin "J4A2.262"
				( objectStatus "@baseboard_fab2_lib.baseboard_fab2(sch_1):page51_i111:dq(53)" )
			)
			( pin "J4A2.124"
				( objectStatus "@baseboard_fab2_lib.baseboard_fab2(sch_1):page51_i111:dq(54)" )
			)
			( pin "J4A2.269"
				( objectStatus "@baseboard_fab2_lib.baseboard_fab2(sch_1):page51_i111:dq(55)" )
			)
			( pin "J4A2.130"
				( objectStatus "@baseboard_fab2_lib.baseboard_fab2(sch_1):page51_i111:dq(56)" )
			)
			( pin "J4A2.275"
				( objectStatus "@baseboard_fab2_lib.baseboard_fab2(sch_1):page51_i111:dq(57)" )
			)
			( pin "J4A2.137"
				( objectStatus "@baseboard_fab2_lib.baseboard_fab2(sch_1):page51_i111:dq(58)" )
			)
			( pin "J4A2.282"
				( objectStatus "@baseboard_fab2_lib.baseboard_fab2(sch_1):page51_i111:dq(59)" )
			)
			( pin "J4A2.128"
				( objectStatus "@baseboard_fab2_lib.baseboard_fab2(sch_1):page51_i111:dq(60)" )
			)
			( pin "J4A2.273"
				( objectStatus "@baseboard_fab2_lib.baseboard_fab2(sch_1):page51_i111:dq(61)" )
			)
			( pin "J4A2.135"
				( objectStatus "@baseboard_fab2_lib.baseboard_fab2(sch_1):page51_i111:dq(62)" )
			)
			( pin "J4A2.280"
				( objectStatus "@baseboard_fab2_lib.baseboard_fab2(sch_1):page51_i111:dq(63)" )
			)
			( pin "J4A2.78"
				( objectStatus "@baseboard_fab2_lib.baseboard_fab2(sch_1):page51_i111:event_n" )
			)
			( pin "J4A2.87"
				( objectStatus "@baseboard_fab2_lib.baseboard_fab2(sch_1):page51_i111:odt(0)" )
			)
			( pin "J4A2.91"
				( objectStatus "@baseboard_fab2_lib.baseboard_fab2(sch_1):page51_i111:odt(1)" )
			)
			( pin "J4A2.222"
				( objectStatus "@baseboard_fab2_lib.baseboard_fab2(sch_1):page51_i111:par" )
			)
			( pin "J4A2.58"
				( objectStatus "@baseboard_fab2_lib.baseboard_fab2(sch_1):page51_i111:reset_n" )
			)
			( pin "J4A2.205"
				( objectStatus "@baseboard_fab2_lib.baseboard_fab2(sch_1):page51_i111:rfu(0)" )
			)
			( pin "J4A2.227"
				( objectStatus "@baseboard_fab2_lib.baseboard_fab2(sch_1):page51_i111:rfu(1)" )
			)
			( pin "J4A2.144"
				( objectStatus "@baseboard_fab2_lib.baseboard_fab2(sch_1):page51_i111:rfu(2)" )
			)
			( pin "J4A2.84"
				( objectStatus "@baseboard_fab2_lib.baseboard_fab2(sch_1):page51_i111:s0_n" )
			)
			( pin "J4A2.89"
				( objectStatus "@baseboard_fab2_lib.baseboard_fab2(sch_1):page51_i111:s1_n" )
			)
			( pin "J4A2.93"
				( objectStatus "@baseboard_fab2_lib.baseboard_fab2(sch_1):page51_i111:s2_n_c(0)" )
			)
			( pin "J4A2.237"
				( objectStatus "@baseboard_fab2_lib.baseboard_fab2(sch_1):page51_i111:s3_n_c(1)" )
			)
			( pin "J4A2.139"
				( objectStatus "@baseboard_fab2_lib.baseboard_fab2(sch_1):page51_i111:sa(0)" )
			)
			( pin "J4A2.140"
				( objectStatus "@baseboard_fab2_lib.baseboard_fab2(sch_1):page51_i111:sa(1)" )
			)
			( pin "J4A2.238"
				( objectStatus "@baseboard_fab2_lib.baseboard_fab2(sch_1):page51_i111:sa(2)" )
			)
			( pin "J4A2.230"
				( objectStatus "@baseboard_fab2_lib.baseboard_fab2(sch_1):page51_i111:save_n_nc" )
			)
			( pin "J4A2.141"
				( objectStatus "@baseboard_fab2_lib.baseboard_fab2(sch_1):page51_i111:scl" )
			)
			( pin "J4A2.285"
				( objectStatus "@baseboard_fab2_lib.baseboard_fab2(sch_1):page51_i111:sda" )
			)
			( pin "J4A2.284"
				( objectStatus "@baseboard_fab2_lib.baseboard_fab2(sch_1):page51_i111:vddspd" )
			)
			( pin "J4A2.146"
				( objectStatus "@baseboard_fab2_lib.baseboard_fab2(sch_1):page51_i111:vrefca" )
			)
			( pin "J4A2.145"
				( objectStatus "@baseboard_fab2_lib.baseboard_fab2(sch_1):page51_i167:\12v\(0)" )
			)
			( pin "J4A2.1"
				( objectStatus "@baseboard_fab2_lib.baseboard_fab2(sch_1):page51_i167:\12v\(1)" )
			)
			( pin "J4A2.236"
				( objectStatus "@baseboard_fab2_lib.baseboard_fab2(sch_1):page51_i167:vdd(0)" )
			)
			( pin "J4A2.233"
				( objectStatus "@baseboard_fab2_lib.baseboard_fab2(sch_1):page51_i167:vdd(1)" )
			)
			( pin "J4A2.231"
				( objectStatus "@baseboard_fab2_lib.baseboard_fab2(sch_1):page51_i167:vdd(2)" )
			)
			( pin "J4A2.229"
				( objectStatus "@baseboard_fab2_lib.baseboard_fab2(sch_1):page51_i167:vdd(3)" )
			)
			( pin "J4A2.226"
				( objectStatus "@baseboard_fab2_lib.baseboard_fab2(sch_1):page51_i167:vdd(4)" )
			)
			( pin "J4A2.223"
				( objectStatus "@baseboard_fab2_lib.baseboard_fab2(sch_1):page51_i167:vdd(5)" )
			)
			( pin "J4A2.220"
				( objectStatus "@baseboard_fab2_lib.baseboard_fab2(sch_1):page51_i167:vdd(6)" )
			)
			( pin "J4A2.217"
				( objectStatus "@baseboard_fab2_lib.baseboard_fab2(sch_1):page51_i167:vdd(7)" )
			)
			( pin "J4A2.215"
				( objectStatus "@baseboard_fab2_lib.baseboard_fab2(sch_1):page51_i167:vdd(8)" )
			)
			( pin "J4A2.212"
				( objectStatus "@baseboard_fab2_lib.baseboard_fab2(sch_1):page51_i167:vdd(9)" )
			)
			( pin "J4A2.209"
				( objectStatus "@baseboard_fab2_lib.baseboard_fab2(sch_1):page51_i167:vdd(10)" )
			)
			( pin "J4A2.206"
				( objectStatus "@baseboard_fab2_lib.baseboard_fab2(sch_1):page51_i167:vdd(11)" )
			)
			( pin "J4A2.204"
				( objectStatus "@baseboard_fab2_lib.baseboard_fab2(sch_1):page51_i167:vdd(12)" )
			)
			( pin "J4A2.92"
				( objectStatus "@baseboard_fab2_lib.baseboard_fab2(sch_1):page51_i167:vdd(13)" )
			)
			( pin "J4A2.90"
				( objectStatus "@baseboard_fab2_lib.baseboard_fab2(sch_1):page51_i167:vdd(14)" )
			)
			( pin "J4A2.88"
				( objectStatus "@baseboard_fab2_lib.baseboard_fab2(sch_1):page51_i167:vdd(15)" )
			)
			( pin "J4A2.85"
				( objectStatus "@baseboard_fab2_lib.baseboard_fab2(sch_1):page51_i167:vdd(16)" )
			)
			( pin "J4A2.83"
				( objectStatus "@baseboard_fab2_lib.baseboard_fab2(sch_1):page51_i167:vdd(17)" )
			)
			( pin "J4A2.80"
				( objectStatus "@baseboard_fab2_lib.baseboard_fab2(sch_1):page51_i167:vdd(18)" )
			)
			( pin "J4A2.76"
				( objectStatus "@baseboard_fab2_lib.baseboard_fab2(sch_1):page51_i167:vdd(19)" )
			)
			( pin "J4A2.73"
				( objectStatus "@baseboard_fab2_lib.baseboard_fab2(sch_1):page51_i167:vdd(20)" )
			)
			( pin "J4A2.70"
				( objectStatus "@baseboard_fab2_lib.baseboard_fab2(sch_1):page51_i167:vdd(21)" )
			)
			( pin "J4A2.67"
				( objectStatus "@baseboard_fab2_lib.baseboard_fab2(sch_1):page51_i167:vdd(22)" )
			)
			( pin "J4A2.64"
				( objectStatus "@baseboard_fab2_lib.baseboard_fab2(sch_1):page51_i167:vdd(23)" )
			)
			( pin "J4A2.61"
				( objectStatus "@baseboard_fab2_lib.baseboard_fab2(sch_1):page51_i167:vdd(24)" )
			)
			( pin "J4A2.59"
				( objectStatus "@baseboard_fab2_lib.baseboard_fab2(sch_1):page51_i167:vdd(25)" )
			)
			( pin "J4A2.287"
				( objectStatus "@baseboard_fab2_lib.baseboard_fab2(sch_1):page51_i167:vpp(0)" )
			)
			( pin "J4A2.286"
				( objectStatus "@baseboard_fab2_lib.baseboard_fab2(sch_1):page51_i167:vpp(1)" )
			)
			( pin "J4A2.288"
				( objectStatus "@baseboard_fab2_lib.baseboard_fab2(sch_1):page51_i167:vpp(2)" )
			)
			( pin "J4A2.143"
				( objectStatus "@baseboard_fab2_lib.baseboard_fab2(sch_1):page51_i167:vpp(3)" )
			)
			( pin "J4A2.142"
				( objectStatus "@baseboard_fab2_lib.baseboard_fab2(sch_1):page51_i167:vpp(4)" )
			)
			( pin "J4A2.221"
				( objectStatus "@baseboard_fab2_lib.baseboard_fab2(sch_1):page51_i167:vtt(0)" )
			)
			( pin "J4A2.77"
				( objectStatus "@baseboard_fab2_lib.baseboard_fab2(sch_1):page51_i167:vtt(1)" )
			)
			( pin "C6L6.1"
				( objectStatus "@baseboard_fab2_lib.baseboard_fab2(sch_1):page51_i175:a" )
			)
			( pin "C6L6.2"
				( objectStatus "@baseboard_fab2_lib.baseboard_fab2(sch_1):page51_i175:b" )
			)
			( pin "C4A18.1"
				( objectStatus "@baseboard_fab2_lib.baseboard_fab2(sch_1):page52_i3:a" )
			)
			( pin "C4A18.2"
				( objectStatus "@baseboard_fab2_lib.baseboard_fab2(sch_1):page52_i3:b" )
			)
			( pin "J6L2.79"
				( objectStatus "@baseboard_fab2_lib.baseboard_fab2(sch_1):page52_i12:a0" )
			)
			( pin "J6L2.72"
				( objectStatus "@baseboard_fab2_lib.baseboard_fab2(sch_1):page52_i12:a1" )
			)
			( pin "J6L2.216"
				( objectStatus "@baseboard_fab2_lib.baseboard_fab2(sch_1):page52_i12:a2" )
			)
			( pin "J6L2.71"
				( objectStatus "@baseboard_fab2_lib.baseboard_fab2(sch_1):page52_i12:a3" )
			)
			( pin "J6L2.214"
				( objectStatus "@baseboard_fab2_lib.baseboard_fab2(sch_1):page52_i12:a4" )
			)
			( pin "J6L2.213"
				( objectStatus "@baseboard_fab2_lib.baseboard_fab2(sch_1):page52_i12:a5" )
			)
			( pin "J6L2.69"
				( objectStatus "@baseboard_fab2_lib.baseboard_fab2(sch_1):page52_i12:a6" )
			)
			( pin "J6L2.211"
				( objectStatus "@baseboard_fab2_lib.baseboard_fab2(sch_1):page52_i12:a7" )
			)
			( pin "J6L2.68"
				( objectStatus "@baseboard_fab2_lib.baseboard_fab2(sch_1):page52_i12:a8" )
			)
			( pin "J6L2.66"
				( objectStatus "@baseboard_fab2_lib.baseboard_fab2(sch_1):page52_i12:a9" )
			)
			( pin "J6L2.225"
				( objectStatus "@baseboard_fab2_lib.baseboard_fab2(sch_1):page52_i12:a10" )
			)
			( pin "J6L2.210"
				( objectStatus "@baseboard_fab2_lib.baseboard_fab2(sch_1):page52_i12:a11" )
			)
			( pin "J6L2.65"
				( objectStatus "@baseboard_fab2_lib.baseboard_fab2(sch_1):page52_i12:a12" )
			)
			( pin "J6L2.232"
				( objectStatus "@baseboard_fab2_lib.baseboard_fab2(sch_1):page52_i12:a13" )
			)
			( pin "J6L2.228"
				( objectStatus "@baseboard_fab2_lib.baseboard_fab2(sch_1):page52_i12:a14_we_n" )
			)
			( pin "J6L2.86"
				( objectStatus "@baseboard_fab2_lib.baseboard_fab2(sch_1):page52_i12:a15_cas_n" )
			)
			( pin "J6L2.82"
				( objectStatus "@baseboard_fab2_lib.baseboard_fab2(sch_1):page52_i12:a16_ras_n" )
			)
			( pin "J6L2.234"
				( objectStatus "@baseboard_fab2_lib.baseboard_fab2(sch_1):page52_i12:a17" )
			)
			( pin "J6L2.62"
				( objectStatus "@baseboard_fab2_lib.baseboard_fab2(sch_1):page52_i12:act_n" )
			)
			( pin "J6L2.208"
				( objectStatus "@baseboard_fab2_lib.baseboard_fab2(sch_1):page52_i12:alert_n" )
			)
			( pin "J6L2.81"
				( objectStatus "@baseboard_fab2_lib.baseboard_fab2(sch_1):page52_i12:ba(0)" )
			)
			( pin "J6L2.224"
				( objectStatus "@baseboard_fab2_lib.baseboard_fab2(sch_1):page52_i12:ba(1)" )
			)
			( pin "J6L2.63"
				( objectStatus "@baseboard_fab2_lib.baseboard_fab2(sch_1):page52_i12:bg(0)" )
			)
			( pin "J6L2.207"
				( objectStatus "@baseboard_fab2_lib.baseboard_fab2(sch_1):page52_i12:bg(1)" )
			)
			( pin "J6L2.235"
				( objectStatus "@baseboard_fab2_lib.baseboard_fab2(sch_1):page52_i12:c(2)" )
			)
			( pin "J6L2.49"
				( objectStatus "@baseboard_fab2_lib.baseboard_fab2(sch_1):page52_i12:cb(0)" )
			)
			( pin "J6L2.194"
				( objectStatus "@baseboard_fab2_lib.baseboard_fab2(sch_1):page52_i12:cb(1)" )
			)
			( pin "J6L2.56"
				( objectStatus "@baseboard_fab2_lib.baseboard_fab2(sch_1):page52_i12:cb(2)" )
			)
			( pin "J6L2.201"
				( objectStatus "@baseboard_fab2_lib.baseboard_fab2(sch_1):page52_i12:cb(3)" )
			)
			( pin "J6L2.47"
				( objectStatus "@baseboard_fab2_lib.baseboard_fab2(sch_1):page52_i12:cb(4)" )
			)
			( pin "J6L2.192"
				( objectStatus "@baseboard_fab2_lib.baseboard_fab2(sch_1):page52_i12:cb(5)" )
			)
			( pin "J6L2.54"
				( objectStatus "@baseboard_fab2_lib.baseboard_fab2(sch_1):page52_i12:cb(6)" )
			)
			( pin "J6L2.199"
				( objectStatus "@baseboard_fab2_lib.baseboard_fab2(sch_1):page52_i12:cb(7)" )
			)
			( pin "J6L2.75"
				( objectStatus "@baseboard_fab2_lib.baseboard_fab2(sch_1):page52_i12:ck0n" )
			)
			( pin "J6L2.74"
				( objectStatus "@baseboard_fab2_lib.baseboard_fab2(sch_1):page52_i12:ck0p" )
			)
			( pin "J6L2.219"
				( objectStatus "@baseboard_fab2_lib.baseboard_fab2(sch_1):page52_i12:ck1n" )
			)
			( pin "J6L2.218"
				( objectStatus "@baseboard_fab2_lib.baseboard_fab2(sch_1):page52_i12:ck1p" )
			)
			( pin "J6L2.60"
				( objectStatus "@baseboard_fab2_lib.baseboard_fab2(sch_1):page52_i12:cke(0)" )
			)
			( pin "J6L2.203"
				( objectStatus "@baseboard_fab2_lib.baseboard_fab2(sch_1):page52_i12:cke(1)" )
			)
			( pin "J6L2.5"
				( objectStatus "@baseboard_fab2_lib.baseboard_fab2(sch_1):page52_i12:dq(0)" )
			)
			( pin "J6L2.150"
				( objectStatus "@baseboard_fab2_lib.baseboard_fab2(sch_1):page52_i12:dq(1)" )
			)
			( pin "J6L2.12"
				( objectStatus "@baseboard_fab2_lib.baseboard_fab2(sch_1):page52_i12:dq(2)" )
			)
			( pin "J6L2.157"
				( objectStatus "@baseboard_fab2_lib.baseboard_fab2(sch_1):page52_i12:dq(3)" )
			)
			( pin "J6L2.3"
				( objectStatus "@baseboard_fab2_lib.baseboard_fab2(sch_1):page52_i12:dq(4)" )
			)
			( pin "J6L2.148"
				( objectStatus "@baseboard_fab2_lib.baseboard_fab2(sch_1):page52_i12:dq(5)" )
			)
			( pin "J6L2.10"
				( objectStatus "@baseboard_fab2_lib.baseboard_fab2(sch_1):page52_i12:dq(6)" )
			)
			( pin "J6L2.155"
				( objectStatus "@baseboard_fab2_lib.baseboard_fab2(sch_1):page52_i12:dq(7)" )
			)
			( pin "J6L2.16"
				( objectStatus "@baseboard_fab2_lib.baseboard_fab2(sch_1):page52_i12:dq(8)" )
			)
			( pin "J6L2.161"
				( objectStatus "@baseboard_fab2_lib.baseboard_fab2(sch_1):page52_i12:dq(9)" )
			)
			( pin "J6L2.23"
				( objectStatus "@baseboard_fab2_lib.baseboard_fab2(sch_1):page52_i12:dq(10)" )
			)
			( pin "J6L2.168"
				( objectStatus "@baseboard_fab2_lib.baseboard_fab2(sch_1):page52_i12:dq(11)" )
			)
			( pin "J6L2.14"
				( objectStatus "@baseboard_fab2_lib.baseboard_fab2(sch_1):page52_i12:dq(12)" )
			)
			( pin "J6L2.159"
				( objectStatus "@baseboard_fab2_lib.baseboard_fab2(sch_1):page52_i12:dq(13)" )
			)
			( pin "J6L2.21"
				( objectStatus "@baseboard_fab2_lib.baseboard_fab2(sch_1):page52_i12:dq(14)" )
			)
			( pin "J6L2.166"
				( objectStatus "@baseboard_fab2_lib.baseboard_fab2(sch_1):page52_i12:dq(15)" )
			)
			( pin "J6L2.27"
				( objectStatus "@baseboard_fab2_lib.baseboard_fab2(sch_1):page52_i12:dq(16)" )
			)
			( pin "J6L2.172"
				( objectStatus "@baseboard_fab2_lib.baseboard_fab2(sch_1):page52_i12:dq(17)" )
			)
			( pin "J6L2.34"
				( objectStatus "@baseboard_fab2_lib.baseboard_fab2(sch_1):page52_i12:dq(18)" )
			)
			( pin "J6L2.179"
				( objectStatus "@baseboard_fab2_lib.baseboard_fab2(sch_1):page52_i12:dq(19)" )
			)
			( pin "J6L2.25"
				( objectStatus "@baseboard_fab2_lib.baseboard_fab2(sch_1):page52_i12:dq(20)" )
			)
			( pin "J6L2.170"
				( objectStatus "@baseboard_fab2_lib.baseboard_fab2(sch_1):page52_i12:dq(21)" )
			)
			( pin "J6L2.32"
				( objectStatus "@baseboard_fab2_lib.baseboard_fab2(sch_1):page52_i12:dq(22)" )
			)
			( pin "J6L2.177"
				( objectStatus "@baseboard_fab2_lib.baseboard_fab2(sch_1):page52_i12:dq(23)" )
			)
			( pin "J6L2.38"
				( objectStatus "@baseboard_fab2_lib.baseboard_fab2(sch_1):page52_i12:dq(24)" )
			)
			( pin "J6L2.183"
				( objectStatus "@baseboard_fab2_lib.baseboard_fab2(sch_1):page52_i12:dq(25)" )
			)
			( pin "J6L2.45"
				( objectStatus "@baseboard_fab2_lib.baseboard_fab2(sch_1):page52_i12:dq(26)" )
			)
			( pin "J6L2.190"
				( objectStatus "@baseboard_fab2_lib.baseboard_fab2(sch_1):page52_i12:dq(27)" )
			)
			( pin "J6L2.36"
				( objectStatus "@baseboard_fab2_lib.baseboard_fab2(sch_1):page52_i12:dq(28)" )
			)
			( pin "J6L2.181"
				( objectStatus "@baseboard_fab2_lib.baseboard_fab2(sch_1):page52_i12:dq(29)" )
			)
			( pin "J6L2.43"
				( objectStatus "@baseboard_fab2_lib.baseboard_fab2(sch_1):page52_i12:dq(30)" )
			)
			( pin "J6L2.188"
				( objectStatus "@baseboard_fab2_lib.baseboard_fab2(sch_1):page52_i12:dq(31)" )
			)
			( pin "J6L2.97"
				( objectStatus "@baseboard_fab2_lib.baseboard_fab2(sch_1):page52_i12:dq(32)" )
			)
			( pin "J6L2.242"
				( objectStatus "@baseboard_fab2_lib.baseboard_fab2(sch_1):page52_i12:dq(33)" )
			)
			( pin "J6L2.104"
				( objectStatus "@baseboard_fab2_lib.baseboard_fab2(sch_1):page52_i12:dq(34)" )
			)
			( pin "J6L2.249"
				( objectStatus "@baseboard_fab2_lib.baseboard_fab2(sch_1):page52_i12:dq(35)" )
			)
			( pin "J6L2.95"
				( objectStatus "@baseboard_fab2_lib.baseboard_fab2(sch_1):page52_i12:dq(36)" )
			)
			( pin "J6L2.240"
				( objectStatus "@baseboard_fab2_lib.baseboard_fab2(sch_1):page52_i12:dq(37)" )
			)
			( pin "J6L2.102"
				( objectStatus "@baseboard_fab2_lib.baseboard_fab2(sch_1):page52_i12:dq(38)" )
			)
			( pin "J6L2.247"
				( objectStatus "@baseboard_fab2_lib.baseboard_fab2(sch_1):page52_i12:dq(39)" )
			)
			( pin "J6L2.108"
				( objectStatus "@baseboard_fab2_lib.baseboard_fab2(sch_1):page52_i12:dq(40)" )
			)
			( pin "J6L2.253"
				( objectStatus "@baseboard_fab2_lib.baseboard_fab2(sch_1):page52_i12:dq(41)" )
			)
			( pin "J6L2.115"
				( objectStatus "@baseboard_fab2_lib.baseboard_fab2(sch_1):page52_i12:dq(42)" )
			)
			( pin "J6L2.260"
				( objectStatus "@baseboard_fab2_lib.baseboard_fab2(sch_1):page52_i12:dq(43)" )
			)
			( pin "J6L2.106"
				( objectStatus "@baseboard_fab2_lib.baseboard_fab2(sch_1):page52_i12:dq(44)" )
			)
			( pin "J6L2.251"
				( objectStatus "@baseboard_fab2_lib.baseboard_fab2(sch_1):page52_i12:dq(45)" )
			)
			( pin "J6L2.113"
				( objectStatus "@baseboard_fab2_lib.baseboard_fab2(sch_1):page52_i12:dq(46)" )
			)
			( pin "J6L2.258"
				( objectStatus "@baseboard_fab2_lib.baseboard_fab2(sch_1):page52_i12:dq(47)" )
			)
			( pin "J6L2.119"
				( objectStatus "@baseboard_fab2_lib.baseboard_fab2(sch_1):page52_i12:dq(48)" )
			)
			( pin "J6L2.264"
				( objectStatus "@baseboard_fab2_lib.baseboard_fab2(sch_1):page52_i12:dq(49)" )
			)
			( pin "J6L2.126"
				( objectStatus "@baseboard_fab2_lib.baseboard_fab2(sch_1):page52_i12:dq(50)" )
			)
			( pin "J6L2.271"
				( objectStatus "@baseboard_fab2_lib.baseboard_fab2(sch_1):page52_i12:dq(51)" )
			)
			( pin "J6L2.117"
				( objectStatus "@baseboard_fab2_lib.baseboard_fab2(sch_1):page52_i12:dq(52)" )
			)
			( pin "J6L2.262"
				( objectStatus "@baseboard_fab2_lib.baseboard_fab2(sch_1):page52_i12:dq(53)" )
			)
			( pin "J6L2.124"
				( objectStatus "@baseboard_fab2_lib.baseboard_fab2(sch_1):page52_i12:dq(54)" )
			)
			( pin "J6L2.269"
				( objectStatus "@baseboard_fab2_lib.baseboard_fab2(sch_1):page52_i12:dq(55)" )
			)
			( pin "J6L2.130"
				( objectStatus "@baseboard_fab2_lib.baseboard_fab2(sch_1):page52_i12:dq(56)" )
			)
			( pin "J6L2.275"
				( objectStatus "@baseboard_fab2_lib.baseboard_fab2(sch_1):page52_i12:dq(57)" )
			)
			( pin "J6L2.137"
				( objectStatus "@baseboard_fab2_lib.baseboard_fab2(sch_1):page52_i12:dq(58)" )
			)
			( pin "J6L2.282"
				( objectStatus "@baseboard_fab2_lib.baseboard_fab2(sch_1):page52_i12:dq(59)" )
			)
			( pin "J6L2.128"
				( objectStatus "@baseboard_fab2_lib.baseboard_fab2(sch_1):page52_i12:dq(60)" )
			)
			( pin "J6L2.273"
				( objectStatus "@baseboard_fab2_lib.baseboard_fab2(sch_1):page52_i12:dq(61)" )
			)
			( pin "J6L2.135"
				( objectStatus "@baseboard_fab2_lib.baseboard_fab2(sch_1):page52_i12:dq(62)" )
			)
			( pin "J6L2.280"
				( objectStatus "@baseboard_fab2_lib.baseboard_fab2(sch_1):page52_i12:dq(63)" )
			)
			( pin "J6L2.78"
				( objectStatus "@baseboard_fab2_lib.baseboard_fab2(sch_1):page52_i12:event_n" )
			)
			( pin "J6L2.87"
				( objectStatus "@baseboard_fab2_lib.baseboard_fab2(sch_1):page52_i12:odt(0)" )
			)
			( pin "J6L2.91"
				( objectStatus "@baseboard_fab2_lib.baseboard_fab2(sch_1):page52_i12:odt(1)" )
			)
			( pin "J6L2.222"
				( objectStatus "@baseboard_fab2_lib.baseboard_fab2(sch_1):page52_i12:par" )
			)
			( pin "J6L2.58"
				( objectStatus "@baseboard_fab2_lib.baseboard_fab2(sch_1):page52_i12:reset_n" )
			)
			( pin "J6L2.205"
				( objectStatus "@baseboard_fab2_lib.baseboard_fab2(sch_1):page52_i12:rfu(0)" )
			)
			( pin "J6L2.227"
				( objectStatus "@baseboard_fab2_lib.baseboard_fab2(sch_1):page52_i12:rfu(1)" )
			)
			( pin "J6L2.144"
				( objectStatus "@baseboard_fab2_lib.baseboard_fab2(sch_1):page52_i12:rfu(2)" )
			)
			( pin "J6L2.84"
				( objectStatus "@baseboard_fab2_lib.baseboard_fab2(sch_1):page52_i12:s0_n" )
			)
			( pin "J6L2.89"
				( objectStatus "@baseboard_fab2_lib.baseboard_fab2(sch_1):page52_i12:s1_n" )
			)
			( pin "J6L2.93"
				( objectStatus "@baseboard_fab2_lib.baseboard_fab2(sch_1):page52_i12:s2_n_c(0)" )
			)
			( pin "J6L2.237"
				( objectStatus "@baseboard_fab2_lib.baseboard_fab2(sch_1):page52_i12:s3_n_c(1)" )
			)
			( pin "J6L2.139"
				( objectStatus "@baseboard_fab2_lib.baseboard_fab2(sch_1):page52_i12:sa(0)" )
			)
			( pin "J6L2.140"
				( objectStatus "@baseboard_fab2_lib.baseboard_fab2(sch_1):page52_i12:sa(1)" )
			)
			( pin "J6L2.238"
				( objectStatus "@baseboard_fab2_lib.baseboard_fab2(sch_1):page52_i12:sa(2)" )
			)
			( pin "J6L2.230"
				( objectStatus "@baseboard_fab2_lib.baseboard_fab2(sch_1):page52_i12:save_n_nc" )
			)
			( pin "J6L2.141"
				( objectStatus "@baseboard_fab2_lib.baseboard_fab2(sch_1):page52_i12:scl" )
			)
			( pin "J6L2.285"
				( objectStatus "@baseboard_fab2_lib.baseboard_fab2(sch_1):page52_i12:sda" )
			)
			( pin "J6L2.284"
				( objectStatus "@baseboard_fab2_lib.baseboard_fab2(sch_1):page52_i12:vddspd" )
			)
			( pin "J6L2.146"
				( objectStatus "@baseboard_fab2_lib.baseboard_fab2(sch_1):page52_i12:vrefca" )
			)
			( pin "J6L2.145"
				( objectStatus "@baseboard_fab2_lib.baseboard_fab2(sch_1):page52_i55:\12v\(0)" )
			)
			( pin "J6L2.1"
				( objectStatus "@baseboard_fab2_lib.baseboard_fab2(sch_1):page52_i55:\12v\(1)" )
			)
			( pin "J6L2.236"
				( objectStatus "@baseboard_fab2_lib.baseboard_fab2(sch_1):page52_i55:vdd(0)" )
			)
			( pin "J6L2.233"
				( objectStatus "@baseboard_fab2_lib.baseboard_fab2(sch_1):page52_i55:vdd(1)" )
			)
			( pin "J6L2.231"
				( objectStatus "@baseboard_fab2_lib.baseboard_fab2(sch_1):page52_i55:vdd(2)" )
			)
			( pin "J6L2.229"
				( objectStatus "@baseboard_fab2_lib.baseboard_fab2(sch_1):page52_i55:vdd(3)" )
			)
			( pin "J6L2.226"
				( objectStatus "@baseboard_fab2_lib.baseboard_fab2(sch_1):page52_i55:vdd(4)" )
			)
			( pin "J6L2.223"
				( objectStatus "@baseboard_fab2_lib.baseboard_fab2(sch_1):page52_i55:vdd(5)" )
			)
			( pin "J6L2.220"
				( objectStatus "@baseboard_fab2_lib.baseboard_fab2(sch_1):page52_i55:vdd(6)" )
			)
			( pin "J6L2.217"
				( objectStatus "@baseboard_fab2_lib.baseboard_fab2(sch_1):page52_i55:vdd(7)" )
			)
			( pin "J6L2.215"
				( objectStatus "@baseboard_fab2_lib.baseboard_fab2(sch_1):page52_i55:vdd(8)" )
			)
			( pin "J6L2.212"
				( objectStatus "@baseboard_fab2_lib.baseboard_fab2(sch_1):page52_i55:vdd(9)" )
			)
			( pin "J6L2.209"
				( objectStatus "@baseboard_fab2_lib.baseboard_fab2(sch_1):page52_i55:vdd(10)" )
			)
			( pin "J6L2.206"
				( objectStatus "@baseboard_fab2_lib.baseboard_fab2(sch_1):page52_i55:vdd(11)" )
			)
			( pin "J6L2.204"
				( objectStatus "@baseboard_fab2_lib.baseboard_fab2(sch_1):page52_i55:vdd(12)" )
			)
			( pin "J6L2.92"
				( objectStatus "@baseboard_fab2_lib.baseboard_fab2(sch_1):page52_i55:vdd(13)" )
			)
			( pin "J6L2.90"
				( objectStatus "@baseboard_fab2_lib.baseboard_fab2(sch_1):page52_i55:vdd(14)" )
			)
			( pin "J6L2.88"
				( objectStatus "@baseboard_fab2_lib.baseboard_fab2(sch_1):page52_i55:vdd(15)" )
			)
			( pin "J6L2.85"
				( objectStatus "@baseboard_fab2_lib.baseboard_fab2(sch_1):page52_i55:vdd(16)" )
			)
			( pin "J6L2.83"
				( objectStatus "@baseboard_fab2_lib.baseboard_fab2(sch_1):page52_i55:vdd(17)" )
			)
			( pin "J6L2.80"
				( objectStatus "@baseboard_fab2_lib.baseboard_fab2(sch_1):page52_i55:vdd(18)" )
			)
			( pin "J6L2.76"
				( objectStatus "@baseboard_fab2_lib.baseboard_fab2(sch_1):page52_i55:vdd(19)" )
			)
			( pin "J6L2.73"
				( objectStatus "@baseboard_fab2_lib.baseboard_fab2(sch_1):page52_i55:vdd(20)" )
			)
			( pin "J6L2.70"
				( objectStatus "@baseboard_fab2_lib.baseboard_fab2(sch_1):page52_i55:vdd(21)" )
			)
			( pin "J6L2.67"
				( objectStatus "@baseboard_fab2_lib.baseboard_fab2(sch_1):page52_i55:vdd(22)" )
			)
			( pin "J6L2.64"
				( objectStatus "@baseboard_fab2_lib.baseboard_fab2(sch_1):page52_i55:vdd(23)" )
			)
			( pin "J6L2.61"
				( objectStatus "@baseboard_fab2_lib.baseboard_fab2(sch_1):page52_i55:vdd(24)" )
			)
			( pin "J6L2.59"
				( objectStatus "@baseboard_fab2_lib.baseboard_fab2(sch_1):page52_i55:vdd(25)" )
			)
			( pin "J6L2.287"
				( objectStatus "@baseboard_fab2_lib.baseboard_fab2(sch_1):page52_i55:vpp(0)" )
			)
			( pin "J6L2.286"
				( objectStatus "@baseboard_fab2_lib.baseboard_fab2(sch_1):page52_i55:vpp(1)" )
			)
			( pin "J6L2.288"
				( objectStatus "@baseboard_fab2_lib.baseboard_fab2(sch_1):page52_i55:vpp(2)" )
			)
			( pin "J6L2.143"
				( objectStatus "@baseboard_fab2_lib.baseboard_fab2(sch_1):page52_i55:vpp(3)" )
			)
			( pin "J6L2.142"
				( objectStatus "@baseboard_fab2_lib.baseboard_fab2(sch_1):page52_i55:vpp(4)" )
			)
			( pin "J6L2.221"
				( objectStatus "@baseboard_fab2_lib.baseboard_fab2(sch_1):page52_i55:vtt(0)" )
			)
			( pin "J6L2.77"
				( objectStatus "@baseboard_fab2_lib.baseboard_fab2(sch_1):page52_i55:vtt(1)" )
			)
			( pin "J6L2.152"
				( objectStatus "@baseboard_fab2_lib.baseboard_fab2(sch_1):page52_i100:dqs0n" )
			)
			( pin "J6L2.153"
				( objectStatus "@baseboard_fab2_lib.baseboard_fab2(sch_1):page52_i100:dqs0p" )
			)
			( pin "J6L2.163"
				( objectStatus "@baseboard_fab2_lib.baseboard_fab2(sch_1):page52_i100:dqs1n" )
			)
			( pin "J6L2.164"
				( objectStatus "@baseboard_fab2_lib.baseboard_fab2(sch_1):page52_i100:dqs1p" )
			)
			( pin "J6L2.174"
				( objectStatus "@baseboard_fab2_lib.baseboard_fab2(sch_1):page52_i100:dqs2n" )
			)
			( pin "J6L2.175"
				( objectStatus "@baseboard_fab2_lib.baseboard_fab2(sch_1):page52_i100:dqs2p" )
			)
			( pin "J6L2.185"
				( objectStatus "@baseboard_fab2_lib.baseboard_fab2(sch_1):page52_i100:dqs3n" )
			)
			( pin "J6L2.186"
				( objectStatus "@baseboard_fab2_lib.baseboard_fab2(sch_1):page52_i100:dqs3p" )
			)
			( pin "J6L2.244"
				( objectStatus "@baseboard_fab2_lib.baseboard_fab2(sch_1):page52_i100:dqs4n" )
			)
			( pin "J6L2.245"
				( objectStatus "@baseboard_fab2_lib.baseboard_fab2(sch_1):page52_i100:dqs4p" )
			)
			( pin "J6L2.255"
				( objectStatus "@baseboard_fab2_lib.baseboard_fab2(sch_1):page52_i100:dqs5n" )
			)
			( pin "J6L2.256"
				( objectStatus "@baseboard_fab2_lib.baseboard_fab2(sch_1):page52_i100:dqs5p" )
			)
			( pin "J6L2.266"
				( objectStatus "@baseboard_fab2_lib.baseboard_fab2(sch_1):page52_i100:dqs6n" )
			)
			( pin "J6L2.267"
				( objectStatus "@baseboard_fab2_lib.baseboard_fab2(sch_1):page52_i100:dqs6p" )
			)
			( pin "J6L2.277"
				( objectStatus "@baseboard_fab2_lib.baseboard_fab2(sch_1):page52_i100:dqs7n" )
			)
			( pin "J6L2.278"
				( objectStatus "@baseboard_fab2_lib.baseboard_fab2(sch_1):page52_i100:dqs7p" )
			)
			( pin "J6L2.196"
				( objectStatus "@baseboard_fab2_lib.baseboard_fab2(sch_1):page52_i100:dqs8n" )
			)
			( pin "J6L2.197"
				( objectStatus "@baseboard_fab2_lib.baseboard_fab2(sch_1):page52_i100:dqs8p" )
			)
			( pin "J6L2.8"
				( objectStatus "@baseboard_fab2_lib.baseboard_fab2(sch_1):page52_i100:dqs9n" )
			)
			( pin "J6L2.7"
				( objectStatus "@baseboard_fab2_lib.baseboard_fab2(sch_1):page52_i100:dqs9p" )
			)
			( pin "J6L2.19"
				( objectStatus "@baseboard_fab2_lib.baseboard_fab2(sch_1):page52_i100:dqs10n" )
			)
			( pin "J6L2.18"
				( objectStatus "@baseboard_fab2_lib.baseboard_fab2(sch_1):page52_i100:dqs10p" )
			)
			( pin "J6L2.30"
				( objectStatus "@baseboard_fab2_lib.baseboard_fab2(sch_1):page52_i100:dqs11n" )
			)
			( pin "J6L2.29"
				( objectStatus "@baseboard_fab2_lib.baseboard_fab2(sch_1):page52_i100:dqs11p" )
			)
			( pin "J6L2.41"
				( objectStatus "@baseboard_fab2_lib.baseboard_fab2(sch_1):page52_i100:dqs12n" )
			)
			( pin "J6L2.40"
				( objectStatus "@baseboard_fab2_lib.baseboard_fab2(sch_1):page52_i100:dqs12p" )
			)
			( pin "J6L2.100"
				( objectStatus "@baseboard_fab2_lib.baseboard_fab2(sch_1):page52_i100:dqs13n" )
			)
			( pin "J6L2.99"
				( objectStatus "@baseboard_fab2_lib.baseboard_fab2(sch_1):page52_i100:dqs13p" )
			)
			( pin "J6L2.111"
				( objectStatus "@baseboard_fab2_lib.baseboard_fab2(sch_1):page52_i100:dqs14n" )
			)
			( pin "J6L2.110"
				( objectStatus "@baseboard_fab2_lib.baseboard_fab2(sch_1):page52_i100:dqs14p" )
			)
			( pin "J6L2.122"
				( objectStatus "@baseboard_fab2_lib.baseboard_fab2(sch_1):page52_i100:dqs15n" )
			)
			( pin "J6L2.121"
				( objectStatus "@baseboard_fab2_lib.baseboard_fab2(sch_1):page52_i100:dqs15p" )
			)
			( pin "J6L2.133"
				( objectStatus "@baseboard_fab2_lib.baseboard_fab2(sch_1):page52_i100:dqs16n" )
			)
			( pin "J6L2.132"
				( objectStatus "@baseboard_fab2_lib.baseboard_fab2(sch_1):page52_i100:dqs16p" )
			)
			( pin "J6L2.52"
				( objectStatus "@baseboard_fab2_lib.baseboard_fab2(sch_1):page52_i100:dqs17n" )
			)
			( pin "J6L2.51"
				( objectStatus "@baseboard_fab2_lib.baseboard_fab2(sch_1):page52_i100:dqs17p" )
			)
			( pin "J6L2.283"
				( objectStatus "@baseboard_fab2_lib.baseboard_fab2(sch_1):page52_i138:vss(0)" )
			)
			( pin "J6L2.281"
				( objectStatus "@baseboard_fab2_lib.baseboard_fab2(sch_1):page52_i138:vss(1)" )
			)
			( pin "J6L2.279"
				( objectStatus "@baseboard_fab2_lib.baseboard_fab2(sch_1):page52_i138:vss(2)" )
			)
			( pin "J6L2.276"
				( objectStatus "@baseboard_fab2_lib.baseboard_fab2(sch_1):page52_i138:vss(3)" )
			)
			( pin "J6L2.274"
				( objectStatus "@baseboard_fab2_lib.baseboard_fab2(sch_1):page52_i138:vss(4)" )
			)
			( pin "J6L2.272"
				( objectStatus "@baseboard_fab2_lib.baseboard_fab2(sch_1):page52_i138:vss(5)" )
			)
			( pin "J6L2.270"
				( objectStatus "@baseboard_fab2_lib.baseboard_fab2(sch_1):page52_i138:vss(6)" )
			)
			( pin "J6L2.268"
				( objectStatus "@baseboard_fab2_lib.baseboard_fab2(sch_1):page52_i138:vss(7)" )
			)
			( pin "J6L2.265"
				( objectStatus "@baseboard_fab2_lib.baseboard_fab2(sch_1):page52_i138:vss(8)" )
			)
			( pin "J6L2.263"
				( objectStatus "@baseboard_fab2_lib.baseboard_fab2(sch_1):page52_i138:vss(9)" )
			)
			( pin "J6L2.261"
				( objectStatus "@baseboard_fab2_lib.baseboard_fab2(sch_1):page52_i138:vss(10)" )
			)
			( pin "J6L2.259"
				( objectStatus "@baseboard_fab2_lib.baseboard_fab2(sch_1):page52_i138:vss(11)" )
			)
			( pin "J6L2.257"
				( objectStatus "@baseboard_fab2_lib.baseboard_fab2(sch_1):page52_i138:vss(12)" )
			)
			( pin "J6L2.254"
				( objectStatus "@baseboard_fab2_lib.baseboard_fab2(sch_1):page52_i138:vss(13)" )
			)
			( pin "J6L2.252"
				( objectStatus "@baseboard_fab2_lib.baseboard_fab2(sch_1):page52_i138:vss(14)" )
			)
			( pin "J6L2.250"
				( objectStatus "@baseboard_fab2_lib.baseboard_fab2(sch_1):page52_i138:vss(15)" )
			)
			( pin "J6L2.248"
				( objectStatus "@baseboard_fab2_lib.baseboard_fab2(sch_1):page52_i138:vss(16)" )
			)
			( pin "J6L2.246"
				( objectStatus "@baseboard_fab2_lib.baseboard_fab2(sch_1):page52_i138:vss(17)" )
			)
			( pin "J6L2.243"
				( objectStatus "@baseboard_fab2_lib.baseboard_fab2(sch_1):page52_i138:vss(18)" )
			)
			( pin "J6L2.241"
				( objectStatus "@baseboard_fab2_lib.baseboard_fab2(sch_1):page52_i138:vss(19)" )
			)
			( pin "J6L2.239"
				( objectStatus "@baseboard_fab2_lib.baseboard_fab2(sch_1):page52_i138:vss(20)" )
			)
			( pin "J6L2.202"
				( objectStatus "@baseboard_fab2_lib.baseboard_fab2(sch_1):page52_i138:vss(21)" )
			)
			( pin "J6L2.200"
				( objectStatus "@baseboard_fab2_lib.baseboard_fab2(sch_1):page52_i138:vss(22)" )
			)
			( pin "J6L2.198"
				( objectStatus "@baseboard_fab2_lib.baseboard_fab2(sch_1):page52_i138:vss(23)" )
			)
			( pin "J6L2.195"
				( objectStatus "@baseboard_fab2_lib.baseboard_fab2(sch_1):page52_i138:vss(24)" )
			)
			( pin "J6L2.193"
				( objectStatus "@baseboard_fab2_lib.baseboard_fab2(sch_1):page52_i138:vss(25)" )
			)
			( pin "J6L2.191"
				( objectStatus "@baseboard_fab2_lib.baseboard_fab2(sch_1):page52_i138:vss(26)" )
			)
			( pin "J6L2.189"
				( objectStatus "@baseboard_fab2_lib.baseboard_fab2(sch_1):page52_i138:vss(27)" )
			)
			( pin "J6L2.187"
				( objectStatus "@baseboard_fab2_lib.baseboard_fab2(sch_1):page52_i138:vss(28)" )
			)
			( pin "J6L2.184"
				( objectStatus "@baseboard_fab2_lib.baseboard_fab2(sch_1):page52_i138:vss(29)" )
			)
			( pin "J6L2.182"
				( objectStatus "@baseboard_fab2_lib.baseboard_fab2(sch_1):page52_i138:vss(30)" )
			)
			( pin "J6L2.180"
				( objectStatus "@baseboard_fab2_lib.baseboard_fab2(sch_1):page52_i138:vss(31)" )
			)
			( pin "J6L2.178"
				( objectStatus "@baseboard_fab2_lib.baseboard_fab2(sch_1):page52_i138:vss(32)" )
			)
			( pin "J6L2.176"
				( objectStatus "@baseboard_fab2_lib.baseboard_fab2(sch_1):page52_i138:vss(33)" )
			)
			( pin "J6L2.173"
				( objectStatus "@baseboard_fab2_lib.baseboard_fab2(sch_1):page52_i138:vss(34)" )
			)
			( pin "J6L2.171"
				( objectStatus "@baseboard_fab2_lib.baseboard_fab2(sch_1):page52_i138:vss(35)" )
			)
			( pin "J6L2.169"
				( objectStatus "@baseboard_fab2_lib.baseboard_fab2(sch_1):page52_i138:vss(36)" )
			)
			( pin "J6L2.167"
				( objectStatus "@baseboard_fab2_lib.baseboard_fab2(sch_1):page52_i138:vss(37)" )
			)
			( pin "J6L2.165"
				( objectStatus "@baseboard_fab2_lib.baseboard_fab2(sch_1):page52_i138:vss(38)" )
			)
			( pin "J6L2.162"
				( objectStatus "@baseboard_fab2_lib.baseboard_fab2(sch_1):page52_i138:vss(39)" )
			)
			( pin "J6L2.160"
				( objectStatus "@baseboard_fab2_lib.baseboard_fab2(sch_1):page52_i138:vss(40)" )
			)
			( pin "J6L2.158"
				( objectStatus "@baseboard_fab2_lib.baseboard_fab2(sch_1):page52_i138:vss(41)" )
			)
			( pin "J6L2.156"
				( objectStatus "@baseboard_fab2_lib.baseboard_fab2(sch_1):page52_i138:vss(42)" )
			)
			( pin "J6L2.154"
				( objectStatus "@baseboard_fab2_lib.baseboard_fab2(sch_1):page52_i138:vss(43)" )
			)
			( pin "J6L2.151"
				( objectStatus "@baseboard_fab2_lib.baseboard_fab2(sch_1):page52_i138:vss(44)" )
			)
			( pin "J6L2.149"
				( objectStatus "@baseboard_fab2_lib.baseboard_fab2(sch_1):page52_i138:vss(45)" )
			)
			( pin "J6L2.147"
				( objectStatus "@baseboard_fab2_lib.baseboard_fab2(sch_1):page52_i138:vss(46)" )
			)
			( pin "J6L2.138"
				( objectStatus "@baseboard_fab2_lib.baseboard_fab2(sch_1):page52_i138:vss(47)" )
			)
			( pin "J6L2.136"
				( objectStatus "@baseboard_fab2_lib.baseboard_fab2(sch_1):page52_i138:vss(48)" )
			)
			( pin "J6L2.134"
				( objectStatus "@baseboard_fab2_lib.baseboard_fab2(sch_1):page52_i138:vss(49)" )
			)
			( pin "J6L2.131"
				( objectStatus "@baseboard_fab2_lib.baseboard_fab2(sch_1):page52_i138:vss(50)" )
			)
			( pin "J6L2.129"
				( objectStatus "@baseboard_fab2_lib.baseboard_fab2(sch_1):page52_i138:vss(51)" )
			)
			( pin "J6L2.127"
				( objectStatus "@baseboard_fab2_lib.baseboard_fab2(sch_1):page52_i138:vss(52)" )
			)
			( pin "J6L2.125"
				( objectStatus "@baseboard_fab2_lib.baseboard_fab2(sch_1):page52_i138:vss(53)" )
			)
			( pin "J6L2.123"
				( objectStatus "@baseboard_fab2_lib.baseboard_fab2(sch_1):page52_i138:vss(54)" )
			)
			( pin "J6L2.120"
				( objectStatus "@baseboard_fab2_lib.baseboard_fab2(sch_1):page52_i138:vss(55)" )
			)
			( pin "J6L2.118"
				( objectStatus "@baseboard_fab2_lib.baseboard_fab2(sch_1):page52_i138:vss(56)" )
			)
			( pin "J6L2.116"
				( objectStatus "@baseboard_fab2_lib.baseboard_fab2(sch_1):page52_i138:vss(57)" )
			)
			( pin "J6L2.114"
				( objectStatus "@baseboard_fab2_lib.baseboard_fab2(sch_1):page52_i138:vss(58)" )
			)
			( pin "J6L2.112"
				( objectStatus "@baseboard_fab2_lib.baseboard_fab2(sch_1):page52_i138:vss(59)" )
			)
			( pin "J6L2.109"
				( objectStatus "@baseboard_fab2_lib.baseboard_fab2(sch_1):page52_i138:vss(60)" )
			)
			( pin "J6L2.107"
				( objectStatus "@baseboard_fab2_lib.baseboard_fab2(sch_1):page52_i138:vss(61)" )
			)
			( pin "J6L2.105"
				( objectStatus "@baseboard_fab2_lib.baseboard_fab2(sch_1):page52_i138:vss(62)" )
			)
			( pin "J6L2.103"
				( objectStatus "@baseboard_fab2_lib.baseboard_fab2(sch_1):page52_i138:vss(63)" )
			)
			( pin "J6L2.101"
				( objectStatus "@baseboard_fab2_lib.baseboard_fab2(sch_1):page52_i138:vss(64)" )
			)
			( pin "J6L2.98"
				( objectStatus "@baseboard_fab2_lib.baseboard_fab2(sch_1):page52_i138:vss(65)" )
			)
			( pin "J6L2.96"
				( objectStatus "@baseboard_fab2_lib.baseboard_fab2(sch_1):page52_i138:vss(66)" )
			)
			( pin "J6L2.94"
				( objectStatus "@baseboard_fab2_lib.baseboard_fab2(sch_1):page52_i138:vss(67)" )
			)
			( pin "J6L2.57"
				( objectStatus "@baseboard_fab2_lib.baseboard_fab2(sch_1):page52_i138:vss(68)" )
			)
			( pin "J6L2.55"
				( objectStatus "@baseboard_fab2_lib.baseboard_fab2(sch_1):page52_i138:vss(69)" )
			)
			( pin "J6L2.53"
				( objectStatus "@baseboard_fab2_lib.baseboard_fab2(sch_1):page52_i138:vss(70)" )
			)
			( pin "J6L2.50"
				( objectStatus "@baseboard_fab2_lib.baseboard_fab2(sch_1):page52_i138:vss(71)" )
			)
			( pin "J6L2.48"
				( objectStatus "@baseboard_fab2_lib.baseboard_fab2(sch_1):page52_i138:vss(72)" )
			)
			( pin "J6L2.46"
				( objectStatus "@baseboard_fab2_lib.baseboard_fab2(sch_1):page52_i138:vss(73)" )
			)
			( pin "J6L2.44"
				( objectStatus "@baseboard_fab2_lib.baseboard_fab2(sch_1):page52_i138:vss(74)" )
			)
			( pin "J6L2.42"
				( objectStatus "@baseboard_fab2_lib.baseboard_fab2(sch_1):page52_i138:vss(75)" )
			)
			( pin "J6L2.39"
				( objectStatus "@baseboard_fab2_lib.baseboard_fab2(sch_1):page52_i138:vss(76)" )
			)
			( pin "J6L2.37"
				( objectStatus "@baseboard_fab2_lib.baseboard_fab2(sch_1):page52_i138:vss(77)" )
			)
			( pin "J6L2.35"
				( objectStatus "@baseboard_fab2_lib.baseboard_fab2(sch_1):page52_i138:vss(78)" )
			)
			( pin "J6L2.33"
				( objectStatus "@baseboard_fab2_lib.baseboard_fab2(sch_1):page52_i138:vss(79)" )
			)
			( pin "J6L2.31"
				( objectStatus "@baseboard_fab2_lib.baseboard_fab2(sch_1):page52_i138:vss(80)" )
			)
			( pin "J6L2.28"
				( objectStatus "@baseboard_fab2_lib.baseboard_fab2(sch_1):page52_i138:vss(81)" )
			)
			( pin "J6L2.26"
				( objectStatus "@baseboard_fab2_lib.baseboard_fab2(sch_1):page52_i138:vss(82)" )
			)
			( pin "J6L2.24"
				( objectStatus "@baseboard_fab2_lib.baseboard_fab2(sch_1):page52_i138:vss(83)" )
			)
			( pin "J6L2.22"
				( objectStatus "@baseboard_fab2_lib.baseboard_fab2(sch_1):page52_i138:vss(84)" )
			)
			( pin "J6L2.20"
				( objectStatus "@baseboard_fab2_lib.baseboard_fab2(sch_1):page52_i138:vss(85)" )
			)
			( pin "J6L2.17"
				( objectStatus "@baseboard_fab2_lib.baseboard_fab2(sch_1):page52_i138:vss(86)" )
			)
			( pin "J6L2.15"
				( objectStatus "@baseboard_fab2_lib.baseboard_fab2(sch_1):page52_i138:vss(87)" )
			)
			( pin "J6L2.13"
				( objectStatus "@baseboard_fab2_lib.baseboard_fab2(sch_1):page52_i138:vss(88)" )
			)
			( pin "J6L2.11"
				( objectStatus "@baseboard_fab2_lib.baseboard_fab2(sch_1):page52_i138:vss(89)" )
			)
			( pin "J6L2.9"
				( objectStatus "@baseboard_fab2_lib.baseboard_fab2(sch_1):page52_i138:vss(90)" )
			)
			( pin "J6L2.6"
				( objectStatus "@baseboard_fab2_lib.baseboard_fab2(sch_1):page52_i138:vss(91)" )
			)
			( pin "J6L2.4"
				( objectStatus "@baseboard_fab2_lib.baseboard_fab2(sch_1):page52_i138:vss(92)" )
			)
			( pin "J6L2.2"
				( objectStatus "@baseboard_fab2_lib.baseboard_fab2(sch_1):page52_i138:vss(93)" )
			)
			( pin "J4A1.283"
				( objectStatus "@baseboard_fab2_lib.baseboard_fab2(sch_1):page53_i43:vss(0)" )
			)
			( pin "J4A1.281"
				( objectStatus "@baseboard_fab2_lib.baseboard_fab2(sch_1):page53_i43:vss(1)" )
			)
			( pin "J4A1.279"
				( objectStatus "@baseboard_fab2_lib.baseboard_fab2(sch_1):page53_i43:vss(2)" )
			)
			( pin "J4A1.276"
				( objectStatus "@baseboard_fab2_lib.baseboard_fab2(sch_1):page53_i43:vss(3)" )
			)
			( pin "J4A1.274"
				( objectStatus "@baseboard_fab2_lib.baseboard_fab2(sch_1):page53_i43:vss(4)" )
			)
			( pin "J4A1.272"
				( objectStatus "@baseboard_fab2_lib.baseboard_fab2(sch_1):page53_i43:vss(5)" )
			)
			( pin "J4A1.270"
				( objectStatus "@baseboard_fab2_lib.baseboard_fab2(sch_1):page53_i43:vss(6)" )
			)
			( pin "J4A1.268"
				( objectStatus "@baseboard_fab2_lib.baseboard_fab2(sch_1):page53_i43:vss(7)" )
			)
			( pin "J4A1.265"
				( objectStatus "@baseboard_fab2_lib.baseboard_fab2(sch_1):page53_i43:vss(8)" )
			)
			( pin "J4A1.263"
				( objectStatus "@baseboard_fab2_lib.baseboard_fab2(sch_1):page53_i43:vss(9)" )
			)
			( pin "J4A1.261"
				( objectStatus "@baseboard_fab2_lib.baseboard_fab2(sch_1):page53_i43:vss(10)" )
			)
			( pin "J4A1.259"
				( objectStatus "@baseboard_fab2_lib.baseboard_fab2(sch_1):page53_i43:vss(11)" )
			)
			( pin "J4A1.257"
				( objectStatus "@baseboard_fab2_lib.baseboard_fab2(sch_1):page53_i43:vss(12)" )
			)
			( pin "J4A1.254"
				( objectStatus "@baseboard_fab2_lib.baseboard_fab2(sch_1):page53_i43:vss(13)" )
			)
			( pin "J4A1.252"
				( objectStatus "@baseboard_fab2_lib.baseboard_fab2(sch_1):page53_i43:vss(14)" )
			)
			( pin "J4A1.250"
				( objectStatus "@baseboard_fab2_lib.baseboard_fab2(sch_1):page53_i43:vss(15)" )
			)
			( pin "J4A1.248"
				( objectStatus "@baseboard_fab2_lib.baseboard_fab2(sch_1):page53_i43:vss(16)" )
			)
			( pin "J4A1.246"
				( objectStatus "@baseboard_fab2_lib.baseboard_fab2(sch_1):page53_i43:vss(17)" )
			)
			( pin "J4A1.243"
				( objectStatus "@baseboard_fab2_lib.baseboard_fab2(sch_1):page53_i43:vss(18)" )
			)
			( pin "J4A1.241"
				( objectStatus "@baseboard_fab2_lib.baseboard_fab2(sch_1):page53_i43:vss(19)" )
			)
			( pin "J4A1.239"
				( objectStatus "@baseboard_fab2_lib.baseboard_fab2(sch_1):page53_i43:vss(20)" )
			)
			( pin "J4A1.202"
				( objectStatus "@baseboard_fab2_lib.baseboard_fab2(sch_1):page53_i43:vss(21)" )
			)
			( pin "J4A1.200"
				( objectStatus "@baseboard_fab2_lib.baseboard_fab2(sch_1):page53_i43:vss(22)" )
			)
			( pin "J4A1.198"
				( objectStatus "@baseboard_fab2_lib.baseboard_fab2(sch_1):page53_i43:vss(23)" )
			)
			( pin "J4A1.195"
				( objectStatus "@baseboard_fab2_lib.baseboard_fab2(sch_1):page53_i43:vss(24)" )
			)
			( pin "J4A1.193"
				( objectStatus "@baseboard_fab2_lib.baseboard_fab2(sch_1):page53_i43:vss(25)" )
			)
			( pin "J4A1.191"
				( objectStatus "@baseboard_fab2_lib.baseboard_fab2(sch_1):page53_i43:vss(26)" )
			)
			( pin "J4A1.189"
				( objectStatus "@baseboard_fab2_lib.baseboard_fab2(sch_1):page53_i43:vss(27)" )
			)
			( pin "J4A1.187"
				( objectStatus "@baseboard_fab2_lib.baseboard_fab2(sch_1):page53_i43:vss(28)" )
			)
			( pin "J4A1.184"
				( objectStatus "@baseboard_fab2_lib.baseboard_fab2(sch_1):page53_i43:vss(29)" )
			)
			( pin "J4A1.182"
				( objectStatus "@baseboard_fab2_lib.baseboard_fab2(sch_1):page53_i43:vss(30)" )
			)
			( pin "J4A1.180"
				( objectStatus "@baseboard_fab2_lib.baseboard_fab2(sch_1):page53_i43:vss(31)" )
			)
			( pin "J4A1.178"
				( objectStatus "@baseboard_fab2_lib.baseboard_fab2(sch_1):page53_i43:vss(32)" )
			)
			( pin "J4A1.176"
				( objectStatus "@baseboard_fab2_lib.baseboard_fab2(sch_1):page53_i43:vss(33)" )
			)
			( pin "J4A1.173"
				( objectStatus "@baseboard_fab2_lib.baseboard_fab2(sch_1):page53_i43:vss(34)" )
			)
			( pin "J4A1.171"
				( objectStatus "@baseboard_fab2_lib.baseboard_fab2(sch_1):page53_i43:vss(35)" )
			)
			( pin "J4A1.169"
				( objectStatus "@baseboard_fab2_lib.baseboard_fab2(sch_1):page53_i43:vss(36)" )
			)
			( pin "J4A1.167"
				( objectStatus "@baseboard_fab2_lib.baseboard_fab2(sch_1):page53_i43:vss(37)" )
			)
			( pin "J4A1.165"
				( objectStatus "@baseboard_fab2_lib.baseboard_fab2(sch_1):page53_i43:vss(38)" )
			)
			( pin "J4A1.162"
				( objectStatus "@baseboard_fab2_lib.baseboard_fab2(sch_1):page53_i43:vss(39)" )
			)
			( pin "J4A1.160"
				( objectStatus "@baseboard_fab2_lib.baseboard_fab2(sch_1):page53_i43:vss(40)" )
			)
			( pin "J4A1.158"
				( objectStatus "@baseboard_fab2_lib.baseboard_fab2(sch_1):page53_i43:vss(41)" )
			)
			( pin "J4A1.156"
				( objectStatus "@baseboard_fab2_lib.baseboard_fab2(sch_1):page53_i43:vss(42)" )
			)
			( pin "J4A1.154"
				( objectStatus "@baseboard_fab2_lib.baseboard_fab2(sch_1):page53_i43:vss(43)" )
			)
			( pin "J4A1.151"
				( objectStatus "@baseboard_fab2_lib.baseboard_fab2(sch_1):page53_i43:vss(44)" )
			)
			( pin "J4A1.149"
				( objectStatus "@baseboard_fab2_lib.baseboard_fab2(sch_1):page53_i43:vss(45)" )
			)
			( pin "J4A1.147"
				( objectStatus "@baseboard_fab2_lib.baseboard_fab2(sch_1):page53_i43:vss(46)" )
			)
			( pin "J4A1.138"
				( objectStatus "@baseboard_fab2_lib.baseboard_fab2(sch_1):page53_i43:vss(47)" )
			)
			( pin "J4A1.136"
				( objectStatus "@baseboard_fab2_lib.baseboard_fab2(sch_1):page53_i43:vss(48)" )
			)
			( pin "J4A1.134"
				( objectStatus "@baseboard_fab2_lib.baseboard_fab2(sch_1):page53_i43:vss(49)" )
			)
			( pin "J4A1.131"
				( objectStatus "@baseboard_fab2_lib.baseboard_fab2(sch_1):page53_i43:vss(50)" )
			)
			( pin "J4A1.129"
				( objectStatus "@baseboard_fab2_lib.baseboard_fab2(sch_1):page53_i43:vss(51)" )
			)
			( pin "J4A1.127"
				( objectStatus "@baseboard_fab2_lib.baseboard_fab2(sch_1):page53_i43:vss(52)" )
			)
			( pin "J4A1.125"
				( objectStatus "@baseboard_fab2_lib.baseboard_fab2(sch_1):page53_i43:vss(53)" )
			)
			( pin "J4A1.123"
				( objectStatus "@baseboard_fab2_lib.baseboard_fab2(sch_1):page53_i43:vss(54)" )
			)
			( pin "J4A1.120"
				( objectStatus "@baseboard_fab2_lib.baseboard_fab2(sch_1):page53_i43:vss(55)" )
			)
			( pin "J4A1.118"
				( objectStatus "@baseboard_fab2_lib.baseboard_fab2(sch_1):page53_i43:vss(56)" )
			)
			( pin "J4A1.116"
				( objectStatus "@baseboard_fab2_lib.baseboard_fab2(sch_1):page53_i43:vss(57)" )
			)
			( pin "J4A1.114"
				( objectStatus "@baseboard_fab2_lib.baseboard_fab2(sch_1):page53_i43:vss(58)" )
			)
			( pin "J4A1.112"
				( objectStatus "@baseboard_fab2_lib.baseboard_fab2(sch_1):page53_i43:vss(59)" )
			)
			( pin "J4A1.109"
				( objectStatus "@baseboard_fab2_lib.baseboard_fab2(sch_1):page53_i43:vss(60)" )
			)
			( pin "J4A1.107"
				( objectStatus "@baseboard_fab2_lib.baseboard_fab2(sch_1):page53_i43:vss(61)" )
			)
			( pin "J4A1.105"
				( objectStatus "@baseboard_fab2_lib.baseboard_fab2(sch_1):page53_i43:vss(62)" )
			)
			( pin "J4A1.103"
				( objectStatus "@baseboard_fab2_lib.baseboard_fab2(sch_1):page53_i43:vss(63)" )
			)
			( pin "J4A1.101"
				( objectStatus "@baseboard_fab2_lib.baseboard_fab2(sch_1):page53_i43:vss(64)" )
			)
			( pin "J4A1.98"
				( objectStatus "@baseboard_fab2_lib.baseboard_fab2(sch_1):page53_i43:vss(65)" )
			)
			( pin "J4A1.96"
				( objectStatus "@baseboard_fab2_lib.baseboard_fab2(sch_1):page53_i43:vss(66)" )
			)
			( pin "J4A1.94"
				( objectStatus "@baseboard_fab2_lib.baseboard_fab2(sch_1):page53_i43:vss(67)" )
			)
			( pin "J4A1.57"
				( objectStatus "@baseboard_fab2_lib.baseboard_fab2(sch_1):page53_i43:vss(68)" )
			)
			( pin "J4A1.55"
				( objectStatus "@baseboard_fab2_lib.baseboard_fab2(sch_1):page53_i43:vss(69)" )
			)
			( pin "J4A1.53"
				( objectStatus "@baseboard_fab2_lib.baseboard_fab2(sch_1):page53_i43:vss(70)" )
			)
			( pin "J4A1.50"
				( objectStatus "@baseboard_fab2_lib.baseboard_fab2(sch_1):page53_i43:vss(71)" )
			)
			( pin "J4A1.48"
				( objectStatus "@baseboard_fab2_lib.baseboard_fab2(sch_1):page53_i43:vss(72)" )
			)
			( pin "J4A1.46"
				( objectStatus "@baseboard_fab2_lib.baseboard_fab2(sch_1):page53_i43:vss(73)" )
			)
			( pin "J4A1.44"
				( objectStatus "@baseboard_fab2_lib.baseboard_fab2(sch_1):page53_i43:vss(74)" )
			)
			( pin "J4A1.42"
				( objectStatus "@baseboard_fab2_lib.baseboard_fab2(sch_1):page53_i43:vss(75)" )
			)
			( pin "J4A1.39"
				( objectStatus "@baseboard_fab2_lib.baseboard_fab2(sch_1):page53_i43:vss(76)" )
			)
			( pin "J4A1.37"
				( objectStatus "@baseboard_fab2_lib.baseboard_fab2(sch_1):page53_i43:vss(77)" )
			)
			( pin "J4A1.35"
				( objectStatus "@baseboard_fab2_lib.baseboard_fab2(sch_1):page53_i43:vss(78)" )
			)
			( pin "J4A1.33"
				( objectStatus "@baseboard_fab2_lib.baseboard_fab2(sch_1):page53_i43:vss(79)" )
			)
			( pin "J4A1.31"
				( objectStatus "@baseboard_fab2_lib.baseboard_fab2(sch_1):page53_i43:vss(80)" )
			)
			( pin "J4A1.28"
				( objectStatus "@baseboard_fab2_lib.baseboard_fab2(sch_1):page53_i43:vss(81)" )
			)
			( pin "J4A1.26"
				( objectStatus "@baseboard_fab2_lib.baseboard_fab2(sch_1):page53_i43:vss(82)" )
			)
			( pin "J4A1.24"
				( objectStatus "@baseboard_fab2_lib.baseboard_fab2(sch_1):page53_i43:vss(83)" )
			)
			( pin "J4A1.22"
				( objectStatus "@baseboard_fab2_lib.baseboard_fab2(sch_1):page53_i43:vss(84)" )
			)
			( pin "J4A1.20"
				( objectStatus "@baseboard_fab2_lib.baseboard_fab2(sch_1):page53_i43:vss(85)" )
			)
			( pin "J4A1.17"
				( objectStatus "@baseboard_fab2_lib.baseboard_fab2(sch_1):page53_i43:vss(86)" )
			)
			( pin "J4A1.15"
				( objectStatus "@baseboard_fab2_lib.baseboard_fab2(sch_1):page53_i43:vss(87)" )
			)
			( pin "J4A1.13"
				( objectStatus "@baseboard_fab2_lib.baseboard_fab2(sch_1):page53_i43:vss(88)" )
			)
			( pin "J4A1.11"
				( objectStatus "@baseboard_fab2_lib.baseboard_fab2(sch_1):page53_i43:vss(89)" )
			)
			( pin "J4A1.9"
				( objectStatus "@baseboard_fab2_lib.baseboard_fab2(sch_1):page53_i43:vss(90)" )
			)
			( pin "J4A1.6"
				( objectStatus "@baseboard_fab2_lib.baseboard_fab2(sch_1):page53_i43:vss(91)" )
			)
			( pin "J4A1.4"
				( objectStatus "@baseboard_fab2_lib.baseboard_fab2(sch_1):page53_i43:vss(92)" )
			)
			( pin "J4A1.2"
				( objectStatus "@baseboard_fab2_lib.baseboard_fab2(sch_1):page53_i43:vss(93)" )
			)
			( pin "J4A1.152"
				( objectStatus "@baseboard_fab2_lib.baseboard_fab2(sch_1):page53_i66:dqs0n" )
			)
			( pin "J4A1.153"
				( objectStatus "@baseboard_fab2_lib.baseboard_fab2(sch_1):page53_i66:dqs0p" )
			)
			( pin "J4A1.163"
				( objectStatus "@baseboard_fab2_lib.baseboard_fab2(sch_1):page53_i66:dqs1n" )
			)
			( pin "J4A1.164"
				( objectStatus "@baseboard_fab2_lib.baseboard_fab2(sch_1):page53_i66:dqs1p" )
			)
			( pin "J4A1.174"
				( objectStatus "@baseboard_fab2_lib.baseboard_fab2(sch_1):page53_i66:dqs2n" )
			)
			( pin "J4A1.175"
				( objectStatus "@baseboard_fab2_lib.baseboard_fab2(sch_1):page53_i66:dqs2p" )
			)
			( pin "J4A1.185"
				( objectStatus "@baseboard_fab2_lib.baseboard_fab2(sch_1):page53_i66:dqs3n" )
			)
			( pin "J4A1.186"
				( objectStatus "@baseboard_fab2_lib.baseboard_fab2(sch_1):page53_i66:dqs3p" )
			)
			( pin "J4A1.244"
				( objectStatus "@baseboard_fab2_lib.baseboard_fab2(sch_1):page53_i66:dqs4n" )
			)
			( pin "J4A1.245"
				( objectStatus "@baseboard_fab2_lib.baseboard_fab2(sch_1):page53_i66:dqs4p" )
			)
			( pin "J4A1.255"
				( objectStatus "@baseboard_fab2_lib.baseboard_fab2(sch_1):page53_i66:dqs5n" )
			)
			( pin "J4A1.256"
				( objectStatus "@baseboard_fab2_lib.baseboard_fab2(sch_1):page53_i66:dqs5p" )
			)
			( pin "J4A1.266"
				( objectStatus "@baseboard_fab2_lib.baseboard_fab2(sch_1):page53_i66:dqs6n" )
			)
			( pin "J4A1.267"
				( objectStatus "@baseboard_fab2_lib.baseboard_fab2(sch_1):page53_i66:dqs6p" )
			)
			( pin "J4A1.277"
				( objectStatus "@baseboard_fab2_lib.baseboard_fab2(sch_1):page53_i66:dqs7n" )
			)
			( pin "J4A1.278"
				( objectStatus "@baseboard_fab2_lib.baseboard_fab2(sch_1):page53_i66:dqs7p" )
			)
			( pin "J4A1.196"
				( objectStatus "@baseboard_fab2_lib.baseboard_fab2(sch_1):page53_i66:dqs8n" )
			)
			( pin "J4A1.197"
				( objectStatus "@baseboard_fab2_lib.baseboard_fab2(sch_1):page53_i66:dqs8p" )
			)
			( pin "J4A1.8"
				( objectStatus "@baseboard_fab2_lib.baseboard_fab2(sch_1):page53_i66:dqs9n" )
			)
			( pin "J4A1.7"
				( objectStatus "@baseboard_fab2_lib.baseboard_fab2(sch_1):page53_i66:dqs9p" )
			)
			( pin "J4A1.19"
				( objectStatus "@baseboard_fab2_lib.baseboard_fab2(sch_1):page53_i66:dqs10n" )
			)
			( pin "J4A1.18"
				( objectStatus "@baseboard_fab2_lib.baseboard_fab2(sch_1):page53_i66:dqs10p" )
			)
			( pin "J4A1.30"
				( objectStatus "@baseboard_fab2_lib.baseboard_fab2(sch_1):page53_i66:dqs11n" )
			)
			( pin "J4A1.29"
				( objectStatus "@baseboard_fab2_lib.baseboard_fab2(sch_1):page53_i66:dqs11p" )
			)
			( pin "J4A1.41"
				( objectStatus "@baseboard_fab2_lib.baseboard_fab2(sch_1):page53_i66:dqs12n" )
			)
			( pin "J4A1.40"
				( objectStatus "@baseboard_fab2_lib.baseboard_fab2(sch_1):page53_i66:dqs12p" )
			)
			( pin "J4A1.100"
				( objectStatus "@baseboard_fab2_lib.baseboard_fab2(sch_1):page53_i66:dqs13n" )
			)
			( pin "J4A1.99"
				( objectStatus "@baseboard_fab2_lib.baseboard_fab2(sch_1):page53_i66:dqs13p" )
			)
			( pin "J4A1.111"
				( objectStatus "@baseboard_fab2_lib.baseboard_fab2(sch_1):page53_i66:dqs14n" )
			)
			( pin "J4A1.110"
				( objectStatus "@baseboard_fab2_lib.baseboard_fab2(sch_1):page53_i66:dqs14p" )
			)
			( pin "J4A1.122"
				( objectStatus "@baseboard_fab2_lib.baseboard_fab2(sch_1):page53_i66:dqs15n" )
			)
			( pin "J4A1.121"
				( objectStatus "@baseboard_fab2_lib.baseboard_fab2(sch_1):page53_i66:dqs15p" )
			)
			( pin "J4A1.133"
				( objectStatus "@baseboard_fab2_lib.baseboard_fab2(sch_1):page53_i66:dqs16n" )
			)
			( pin "J4A1.132"
				( objectStatus "@baseboard_fab2_lib.baseboard_fab2(sch_1):page53_i66:dqs16p" )
			)
			( pin "J4A1.52"
				( objectStatus "@baseboard_fab2_lib.baseboard_fab2(sch_1):page53_i66:dqs17n" )
			)
			( pin "J4A1.51"
				( objectStatus "@baseboard_fab2_lib.baseboard_fab2(sch_1):page53_i66:dqs17p" )
			)
			( pin "J4A1.79"
				( objectStatus "@baseboard_fab2_lib.baseboard_fab2(sch_1):page53_i111:a0" )
			)
			( pin "J4A1.72"
				( objectStatus "@baseboard_fab2_lib.baseboard_fab2(sch_1):page53_i111:a1" )
			)
			( pin "J4A1.216"
				( objectStatus "@baseboard_fab2_lib.baseboard_fab2(sch_1):page53_i111:a2" )
			)
			( pin "J4A1.71"
				( objectStatus "@baseboard_fab2_lib.baseboard_fab2(sch_1):page53_i111:a3" )
			)
			( pin "J4A1.214"
				( objectStatus "@baseboard_fab2_lib.baseboard_fab2(sch_1):page53_i111:a4" )
			)
			( pin "J4A1.213"
				( objectStatus "@baseboard_fab2_lib.baseboard_fab2(sch_1):page53_i111:a5" )
			)
			( pin "J4A1.69"
				( objectStatus "@baseboard_fab2_lib.baseboard_fab2(sch_1):page53_i111:a6" )
			)
			( pin "J4A1.211"
				( objectStatus "@baseboard_fab2_lib.baseboard_fab2(sch_1):page53_i111:a7" )
			)
			( pin "J4A1.68"
				( objectStatus "@baseboard_fab2_lib.baseboard_fab2(sch_1):page53_i111:a8" )
			)
			( pin "J4A1.66"
				( objectStatus "@baseboard_fab2_lib.baseboard_fab2(sch_1):page53_i111:a9" )
			)
			( pin "J4A1.225"
				( objectStatus "@baseboard_fab2_lib.baseboard_fab2(sch_1):page53_i111:a10" )
			)
			( pin "J4A1.210"
				( objectStatus "@baseboard_fab2_lib.baseboard_fab2(sch_1):page53_i111:a11" )
			)
			( pin "J4A1.65"
				( objectStatus "@baseboard_fab2_lib.baseboard_fab2(sch_1):page53_i111:a12" )
			)
			( pin "J4A1.232"
				( objectStatus "@baseboard_fab2_lib.baseboard_fab2(sch_1):page53_i111:a13" )
			)
			( pin "J4A1.228"
				( objectStatus "@baseboard_fab2_lib.baseboard_fab2(sch_1):page53_i111:a14_we_n" )
			)
			( pin "J4A1.86"
				( objectStatus "@baseboard_fab2_lib.baseboard_fab2(sch_1):page53_i111:a15_cas_n" )
			)
			( pin "J4A1.82"
				( objectStatus "@baseboard_fab2_lib.baseboard_fab2(sch_1):page53_i111:a16_ras_n" )
			)
			( pin "J4A1.234"
				( objectStatus "@baseboard_fab2_lib.baseboard_fab2(sch_1):page53_i111:a17" )
			)
			( pin "J4A1.62"
				( objectStatus "@baseboard_fab2_lib.baseboard_fab2(sch_1):page53_i111:act_n" )
			)
			( pin "J4A1.208"
				( objectStatus "@baseboard_fab2_lib.baseboard_fab2(sch_1):page53_i111:alert_n" )
			)
			( pin "J4A1.81"
				( objectStatus "@baseboard_fab2_lib.baseboard_fab2(sch_1):page53_i111:ba(0)" )
			)
			( pin "J4A1.224"
				( objectStatus "@baseboard_fab2_lib.baseboard_fab2(sch_1):page53_i111:ba(1)" )
			)
			( pin "J4A1.63"
				( objectStatus "@baseboard_fab2_lib.baseboard_fab2(sch_1):page53_i111:bg(0)" )
			)
			( pin "J4A1.207"
				( objectStatus "@baseboard_fab2_lib.baseboard_fab2(sch_1):page53_i111:bg(1)" )
			)
			( pin "J4A1.235"
				( objectStatus "@baseboard_fab2_lib.baseboard_fab2(sch_1):page53_i111:c(2)" )
			)
			( pin "J4A1.49"
				( objectStatus "@baseboard_fab2_lib.baseboard_fab2(sch_1):page53_i111:cb(0)" )
			)
			( pin "J4A1.194"
				( objectStatus "@baseboard_fab2_lib.baseboard_fab2(sch_1):page53_i111:cb(1)" )
			)
			( pin "J4A1.56"
				( objectStatus "@baseboard_fab2_lib.baseboard_fab2(sch_1):page53_i111:cb(2)" )
			)
			( pin "J4A1.201"
				( objectStatus "@baseboard_fab2_lib.baseboard_fab2(sch_1):page53_i111:cb(3)" )
			)
			( pin "J4A1.47"
				( objectStatus "@baseboard_fab2_lib.baseboard_fab2(sch_1):page53_i111:cb(4)" )
			)
			( pin "J4A1.192"
				( objectStatus "@baseboard_fab2_lib.baseboard_fab2(sch_1):page53_i111:cb(5)" )
			)
			( pin "J4A1.54"
				( objectStatus "@baseboard_fab2_lib.baseboard_fab2(sch_1):page53_i111:cb(6)" )
			)
			( pin "J4A1.199"
				( objectStatus "@baseboard_fab2_lib.baseboard_fab2(sch_1):page53_i111:cb(7)" )
			)
			( pin "J4A1.75"
				( objectStatus "@baseboard_fab2_lib.baseboard_fab2(sch_1):page53_i111:ck0n" )
			)
			( pin "J4A1.74"
				( objectStatus "@baseboard_fab2_lib.baseboard_fab2(sch_1):page53_i111:ck0p" )
			)
			( pin "J4A1.219"
				( objectStatus "@baseboard_fab2_lib.baseboard_fab2(sch_1):page53_i111:ck1n" )
			)
			( pin "J4A1.218"
				( objectStatus "@baseboard_fab2_lib.baseboard_fab2(sch_1):page53_i111:ck1p" )
			)
			( pin "J4A1.60"
				( objectStatus "@baseboard_fab2_lib.baseboard_fab2(sch_1):page53_i111:cke(0)" )
			)
			( pin "J4A1.203"
				( objectStatus "@baseboard_fab2_lib.baseboard_fab2(sch_1):page53_i111:cke(1)" )
			)
			( pin "J4A1.5"
				( objectStatus "@baseboard_fab2_lib.baseboard_fab2(sch_1):page53_i111:dq(0)" )
			)
			( pin "J4A1.150"
				( objectStatus "@baseboard_fab2_lib.baseboard_fab2(sch_1):page53_i111:dq(1)" )
			)
			( pin "J4A1.12"
				( objectStatus "@baseboard_fab2_lib.baseboard_fab2(sch_1):page53_i111:dq(2)" )
			)
			( pin "J4A1.157"
				( objectStatus "@baseboard_fab2_lib.baseboard_fab2(sch_1):page53_i111:dq(3)" )
			)
			( pin "J4A1.3"
				( objectStatus "@baseboard_fab2_lib.baseboard_fab2(sch_1):page53_i111:dq(4)" )
			)
			( pin "J4A1.148"
				( objectStatus "@baseboard_fab2_lib.baseboard_fab2(sch_1):page53_i111:dq(5)" )
			)
			( pin "J4A1.10"
				( objectStatus "@baseboard_fab2_lib.baseboard_fab2(sch_1):page53_i111:dq(6)" )
			)
			( pin "J4A1.155"
				( objectStatus "@baseboard_fab2_lib.baseboard_fab2(sch_1):page53_i111:dq(7)" )
			)
			( pin "J4A1.16"
				( objectStatus "@baseboard_fab2_lib.baseboard_fab2(sch_1):page53_i111:dq(8)" )
			)
			( pin "J4A1.161"
				( objectStatus "@baseboard_fab2_lib.baseboard_fab2(sch_1):page53_i111:dq(9)" )
			)
			( pin "J4A1.23"
				( objectStatus "@baseboard_fab2_lib.baseboard_fab2(sch_1):page53_i111:dq(10)" )
			)
			( pin "J4A1.168"
				( objectStatus "@baseboard_fab2_lib.baseboard_fab2(sch_1):page53_i111:dq(11)" )
			)
			( pin "J4A1.14"
				( objectStatus "@baseboard_fab2_lib.baseboard_fab2(sch_1):page53_i111:dq(12)" )
			)
			( pin "J4A1.159"
				( objectStatus "@baseboard_fab2_lib.baseboard_fab2(sch_1):page53_i111:dq(13)" )
			)
			( pin "J4A1.21"
				( objectStatus "@baseboard_fab2_lib.baseboard_fab2(sch_1):page53_i111:dq(14)" )
			)
			( pin "J4A1.166"
				( objectStatus "@baseboard_fab2_lib.baseboard_fab2(sch_1):page53_i111:dq(15)" )
			)
			( pin "J4A1.27"
				( objectStatus "@baseboard_fab2_lib.baseboard_fab2(sch_1):page53_i111:dq(16)" )
			)
			( pin "J4A1.172"
				( objectStatus "@baseboard_fab2_lib.baseboard_fab2(sch_1):page53_i111:dq(17)" )
			)
			( pin "J4A1.34"
				( objectStatus "@baseboard_fab2_lib.baseboard_fab2(sch_1):page53_i111:dq(18)" )
			)
			( pin "J4A1.179"
				( objectStatus "@baseboard_fab2_lib.baseboard_fab2(sch_1):page53_i111:dq(19)" )
			)
			( pin "J4A1.25"
				( objectStatus "@baseboard_fab2_lib.baseboard_fab2(sch_1):page53_i111:dq(20)" )
			)
			( pin "J4A1.170"
				( objectStatus "@baseboard_fab2_lib.baseboard_fab2(sch_1):page53_i111:dq(21)" )
			)
			( pin "J4A1.32"
				( objectStatus "@baseboard_fab2_lib.baseboard_fab2(sch_1):page53_i111:dq(22)" )
			)
			( pin "J4A1.177"
				( objectStatus "@baseboard_fab2_lib.baseboard_fab2(sch_1):page53_i111:dq(23)" )
			)
			( pin "J4A1.38"
				( objectStatus "@baseboard_fab2_lib.baseboard_fab2(sch_1):page53_i111:dq(24)" )
			)
			( pin "J4A1.183"
				( objectStatus "@baseboard_fab2_lib.baseboard_fab2(sch_1):page53_i111:dq(25)" )
			)
			( pin "J4A1.45"
				( objectStatus "@baseboard_fab2_lib.baseboard_fab2(sch_1):page53_i111:dq(26)" )
			)
			( pin "J4A1.190"
				( objectStatus "@baseboard_fab2_lib.baseboard_fab2(sch_1):page53_i111:dq(27)" )
			)
			( pin "J4A1.36"
				( objectStatus "@baseboard_fab2_lib.baseboard_fab2(sch_1):page53_i111:dq(28)" )
			)
			( pin "J4A1.181"
				( objectStatus "@baseboard_fab2_lib.baseboard_fab2(sch_1):page53_i111:dq(29)" )
			)
			( pin "J4A1.43"
				( objectStatus "@baseboard_fab2_lib.baseboard_fab2(sch_1):page53_i111:dq(30)" )
			)
			( pin "J4A1.188"
				( objectStatus "@baseboard_fab2_lib.baseboard_fab2(sch_1):page53_i111:dq(31)" )
			)
			( pin "J4A1.97"
				( objectStatus "@baseboard_fab2_lib.baseboard_fab2(sch_1):page53_i111:dq(32)" )
			)
			( pin "J4A1.242"
				( objectStatus "@baseboard_fab2_lib.baseboard_fab2(sch_1):page53_i111:dq(33)" )
			)
			( pin "J4A1.104"
				( objectStatus "@baseboard_fab2_lib.baseboard_fab2(sch_1):page53_i111:dq(34)" )
			)
			( pin "J4A1.249"
				( objectStatus "@baseboard_fab2_lib.baseboard_fab2(sch_1):page53_i111:dq(35)" )
			)
			( pin "J4A1.95"
				( objectStatus "@baseboard_fab2_lib.baseboard_fab2(sch_1):page53_i111:dq(36)" )
			)
			( pin "J4A1.240"
				( objectStatus "@baseboard_fab2_lib.baseboard_fab2(sch_1):page53_i111:dq(37)" )
			)
			( pin "J4A1.102"
				( objectStatus "@baseboard_fab2_lib.baseboard_fab2(sch_1):page53_i111:dq(38)" )
			)
			( pin "J4A1.247"
				( objectStatus "@baseboard_fab2_lib.baseboard_fab2(sch_1):page53_i111:dq(39)" )
			)
			( pin "J4A1.108"
				( objectStatus "@baseboard_fab2_lib.baseboard_fab2(sch_1):page53_i111:dq(40)" )
			)
			( pin "J4A1.253"
				( objectStatus "@baseboard_fab2_lib.baseboard_fab2(sch_1):page53_i111:dq(41)" )
			)
			( pin "J4A1.115"
				( objectStatus "@baseboard_fab2_lib.baseboard_fab2(sch_1):page53_i111:dq(42)" )
			)
			( pin "J4A1.260"
				( objectStatus "@baseboard_fab2_lib.baseboard_fab2(sch_1):page53_i111:dq(43)" )
			)
			( pin "J4A1.106"
				( objectStatus "@baseboard_fab2_lib.baseboard_fab2(sch_1):page53_i111:dq(44)" )
			)
			( pin "J4A1.251"
				( objectStatus "@baseboard_fab2_lib.baseboard_fab2(sch_1):page53_i111:dq(45)" )
			)
			( pin "J4A1.113"
				( objectStatus "@baseboard_fab2_lib.baseboard_fab2(sch_1):page53_i111:dq(46)" )
			)
			( pin "J4A1.258"
				( objectStatus "@baseboard_fab2_lib.baseboard_fab2(sch_1):page53_i111:dq(47)" )
			)
			( pin "J4A1.119"
				( objectStatus "@baseboard_fab2_lib.baseboard_fab2(sch_1):page53_i111:dq(48)" )
			)
			( pin "J4A1.264"
				( objectStatus "@baseboard_fab2_lib.baseboard_fab2(sch_1):page53_i111:dq(49)" )
			)
			( pin "J4A1.126"
				( objectStatus "@baseboard_fab2_lib.baseboard_fab2(sch_1):page53_i111:dq(50)" )
			)
			( pin "J4A1.271"
				( objectStatus "@baseboard_fab2_lib.baseboard_fab2(sch_1):page53_i111:dq(51)" )
			)
			( pin "J4A1.117"
				( objectStatus "@baseboard_fab2_lib.baseboard_fab2(sch_1):page53_i111:dq(52)" )
			)
			( pin "J4A1.262"
				( objectStatus "@baseboard_fab2_lib.baseboard_fab2(sch_1):page53_i111:dq(53)" )
			)
			( pin "J4A1.124"
				( objectStatus "@baseboard_fab2_lib.baseboard_fab2(sch_1):page53_i111:dq(54)" )
			)
			( pin "J4A1.269"
				( objectStatus "@baseboard_fab2_lib.baseboard_fab2(sch_1):page53_i111:dq(55)" )
			)
			( pin "J4A1.130"
				( objectStatus "@baseboard_fab2_lib.baseboard_fab2(sch_1):page53_i111:dq(56)" )
			)
			( pin "J4A1.275"
				( objectStatus "@baseboard_fab2_lib.baseboard_fab2(sch_1):page53_i111:dq(57)" )
			)
			( pin "J4A1.137"
				( objectStatus "@baseboard_fab2_lib.baseboard_fab2(sch_1):page53_i111:dq(58)" )
			)
			( pin "J4A1.282"
				( objectStatus "@baseboard_fab2_lib.baseboard_fab2(sch_1):page53_i111:dq(59)" )
			)
			( pin "J4A1.128"
				( objectStatus "@baseboard_fab2_lib.baseboard_fab2(sch_1):page53_i111:dq(60)" )
			)
			( pin "J4A1.273"
				( objectStatus "@baseboard_fab2_lib.baseboard_fab2(sch_1):page53_i111:dq(61)" )
			)
			( pin "J4A1.135"
				( objectStatus "@baseboard_fab2_lib.baseboard_fab2(sch_1):page53_i111:dq(62)" )
			)
			( pin "J4A1.280"
				( objectStatus "@baseboard_fab2_lib.baseboard_fab2(sch_1):page53_i111:dq(63)" )
			)
			( pin "J4A1.78"
				( objectStatus "@baseboard_fab2_lib.baseboard_fab2(sch_1):page53_i111:event_n" )
			)
			( pin "J4A1.87"
				( objectStatus "@baseboard_fab2_lib.baseboard_fab2(sch_1):page53_i111:odt(0)" )
			)
			( pin "J4A1.91"
				( objectStatus "@baseboard_fab2_lib.baseboard_fab2(sch_1):page53_i111:odt(1)" )
			)
			( pin "J4A1.222"
				( objectStatus "@baseboard_fab2_lib.baseboard_fab2(sch_1):page53_i111:par" )
			)
			( pin "J4A1.58"
				( objectStatus "@baseboard_fab2_lib.baseboard_fab2(sch_1):page53_i111:reset_n" )
			)
			( pin "J4A1.205"
				( objectStatus "@baseboard_fab2_lib.baseboard_fab2(sch_1):page53_i111:rfu(0)" )
			)
			( pin "J4A1.227"
				( objectStatus "@baseboard_fab2_lib.baseboard_fab2(sch_1):page53_i111:rfu(1)" )
			)
			( pin "J4A1.144"
				( objectStatus "@baseboard_fab2_lib.baseboard_fab2(sch_1):page53_i111:rfu(2)" )
			)
			( pin "J4A1.84"
				( objectStatus "@baseboard_fab2_lib.baseboard_fab2(sch_1):page53_i111:s0_n" )
			)
			( pin "J4A1.89"
				( objectStatus "@baseboard_fab2_lib.baseboard_fab2(sch_1):page53_i111:s1_n" )
			)
			( pin "J4A1.93"
				( objectStatus "@baseboard_fab2_lib.baseboard_fab2(sch_1):page53_i111:s2_n_c(0)" )
			)
			( pin "J4A1.237"
				( objectStatus "@baseboard_fab2_lib.baseboard_fab2(sch_1):page53_i111:s3_n_c(1)" )
			)
			( pin "J4A1.139"
				( objectStatus "@baseboard_fab2_lib.baseboard_fab2(sch_1):page53_i111:sa(0)" )
			)
			( pin "J4A1.140"
				( objectStatus "@baseboard_fab2_lib.baseboard_fab2(sch_1):page53_i111:sa(1)" )
			)
			( pin "J4A1.238"
				( objectStatus "@baseboard_fab2_lib.baseboard_fab2(sch_1):page53_i111:sa(2)" )
			)
			( pin "J4A1.230"
				( objectStatus "@baseboard_fab2_lib.baseboard_fab2(sch_1):page53_i111:save_n_nc" )
			)
			( pin "J4A1.141"
				( objectStatus "@baseboard_fab2_lib.baseboard_fab2(sch_1):page53_i111:scl" )
			)
			( pin "J4A1.285"
				( objectStatus "@baseboard_fab2_lib.baseboard_fab2(sch_1):page53_i111:sda" )
			)
			( pin "J4A1.284"
				( objectStatus "@baseboard_fab2_lib.baseboard_fab2(sch_1):page53_i111:vddspd" )
			)
			( pin "J4A1.146"
				( objectStatus "@baseboard_fab2_lib.baseboard_fab2(sch_1):page53_i111:vrefca" )
			)
			( pin "J4A1.145"
				( objectStatus "@baseboard_fab2_lib.baseboard_fab2(sch_1):page53_i171:\12v\(0)" )
			)
			( pin "J4A1.1"
				( objectStatus "@baseboard_fab2_lib.baseboard_fab2(sch_1):page53_i171:\12v\(1)" )
			)
			( pin "J4A1.236"
				( objectStatus "@baseboard_fab2_lib.baseboard_fab2(sch_1):page53_i171:vdd(0)" )
			)
			( pin "J4A1.233"
				( objectStatus "@baseboard_fab2_lib.baseboard_fab2(sch_1):page53_i171:vdd(1)" )
			)
			( pin "J4A1.231"
				( objectStatus "@baseboard_fab2_lib.baseboard_fab2(sch_1):page53_i171:vdd(2)" )
			)
			( pin "J4A1.229"
				( objectStatus "@baseboard_fab2_lib.baseboard_fab2(sch_1):page53_i171:vdd(3)" )
			)
			( pin "J4A1.226"
				( objectStatus "@baseboard_fab2_lib.baseboard_fab2(sch_1):page53_i171:vdd(4)" )
			)
			( pin "J4A1.223"
				( objectStatus "@baseboard_fab2_lib.baseboard_fab2(sch_1):page53_i171:vdd(5)" )
			)
			( pin "J4A1.220"
				( objectStatus "@baseboard_fab2_lib.baseboard_fab2(sch_1):page53_i171:vdd(6)" )
			)
			( pin "J4A1.217"
				( objectStatus "@baseboard_fab2_lib.baseboard_fab2(sch_1):page53_i171:vdd(7)" )
			)
			( pin "J4A1.215"
				( objectStatus "@baseboard_fab2_lib.baseboard_fab2(sch_1):page53_i171:vdd(8)" )
			)
			( pin "J4A1.212"
				( objectStatus "@baseboard_fab2_lib.baseboard_fab2(sch_1):page53_i171:vdd(9)" )
			)
			( pin "J4A1.209"
				( objectStatus "@baseboard_fab2_lib.baseboard_fab2(sch_1):page53_i171:vdd(10)" )
			)
			( pin "J4A1.206"
				( objectStatus "@baseboard_fab2_lib.baseboard_fab2(sch_1):page53_i171:vdd(11)" )
			)
			( pin "J4A1.204"
				( objectStatus "@baseboard_fab2_lib.baseboard_fab2(sch_1):page53_i171:vdd(12)" )
			)
			( pin "J4A1.92"
				( objectStatus "@baseboard_fab2_lib.baseboard_fab2(sch_1):page53_i171:vdd(13)" )
			)
			( pin "J4A1.90"
				( objectStatus "@baseboard_fab2_lib.baseboard_fab2(sch_1):page53_i171:vdd(14)" )
			)
			( pin "J4A1.88"
				( objectStatus "@baseboard_fab2_lib.baseboard_fab2(sch_1):page53_i171:vdd(15)" )
			)
			( pin "J4A1.85"
				( objectStatus "@baseboard_fab2_lib.baseboard_fab2(sch_1):page53_i171:vdd(16)" )
			)
			( pin "J4A1.83"
				( objectStatus "@baseboard_fab2_lib.baseboard_fab2(sch_1):page53_i171:vdd(17)" )
			)
			( pin "J4A1.80"
				( objectStatus "@baseboard_fab2_lib.baseboard_fab2(sch_1):page53_i171:vdd(18)" )
			)
			( pin "J4A1.76"
				( objectStatus "@baseboard_fab2_lib.baseboard_fab2(sch_1):page53_i171:vdd(19)" )
			)
			( pin "J4A1.73"
				( objectStatus "@baseboard_fab2_lib.baseboard_fab2(sch_1):page53_i171:vdd(20)" )
			)
			( pin "J4A1.70"
				( objectStatus "@baseboard_fab2_lib.baseboard_fab2(sch_1):page53_i171:vdd(21)" )
			)
			( pin "J4A1.67"
				( objectStatus "@baseboard_fab2_lib.baseboard_fab2(sch_1):page53_i171:vdd(22)" )
			)
			( pin "J4A1.64"
				( objectStatus "@baseboard_fab2_lib.baseboard_fab2(sch_1):page53_i171:vdd(23)" )
			)
			( pin "J4A1.61"
				( objectStatus "@baseboard_fab2_lib.baseboard_fab2(sch_1):page53_i171:vdd(24)" )
			)
			( pin "J4A1.59"
				( objectStatus "@baseboard_fab2_lib.baseboard_fab2(sch_1):page53_i171:vdd(25)" )
			)
			( pin "J4A1.287"
				( objectStatus "@baseboard_fab2_lib.baseboard_fab2(sch_1):page53_i171:vpp(0)" )
			)
			( pin "J4A1.286"
				( objectStatus "@baseboard_fab2_lib.baseboard_fab2(sch_1):page53_i171:vpp(1)" )
			)
			( pin "J4A1.288"
				( objectStatus "@baseboard_fab2_lib.baseboard_fab2(sch_1):page53_i171:vpp(2)" )
			)
			( pin "J4A1.143"
				( objectStatus "@baseboard_fab2_lib.baseboard_fab2(sch_1):page53_i171:vpp(3)" )
			)
			( pin "J4A1.142"
				( objectStatus "@baseboard_fab2_lib.baseboard_fab2(sch_1):page53_i171:vpp(4)" )
			)
			( pin "J4A1.221"
				( objectStatus "@baseboard_fab2_lib.baseboard_fab2(sch_1):page53_i171:vtt(0)" )
			)
			( pin "J4A1.77"
				( objectStatus "@baseboard_fab2_lib.baseboard_fab2(sch_1):page53_i171:vtt(1)" )
			)
			( pin "C6L1.1"
				( objectStatus "@baseboard_fab2_lib.baseboard_fab2(sch_1):page53_i178:a" )
			)
			( pin "C6L1.2"
				( objectStatus "@baseboard_fab2_lib.baseboard_fab2(sch_1):page53_i178:b" )
			)
			( pin "J6L1.283"
				( objectStatus "@baseboard_fab2_lib.baseboard_fab2(sch_1):page54_i43:vss(0)" )
			)
			( pin "J6L1.281"
				( objectStatus "@baseboard_fab2_lib.baseboard_fab2(sch_1):page54_i43:vss(1)" )
			)
			( pin "J6L1.279"
				( objectStatus "@baseboard_fab2_lib.baseboard_fab2(sch_1):page54_i43:vss(2)" )
			)
			( pin "J6L1.276"
				( objectStatus "@baseboard_fab2_lib.baseboard_fab2(sch_1):page54_i43:vss(3)" )
			)
			( pin "J6L1.274"
				( objectStatus "@baseboard_fab2_lib.baseboard_fab2(sch_1):page54_i43:vss(4)" )
			)
			( pin "J6L1.272"
				( objectStatus "@baseboard_fab2_lib.baseboard_fab2(sch_1):page54_i43:vss(5)" )
			)
			( pin "J6L1.270"
				( objectStatus "@baseboard_fab2_lib.baseboard_fab2(sch_1):page54_i43:vss(6)" )
			)
			( pin "J6L1.268"
				( objectStatus "@baseboard_fab2_lib.baseboard_fab2(sch_1):page54_i43:vss(7)" )
			)
			( pin "J6L1.265"
				( objectStatus "@baseboard_fab2_lib.baseboard_fab2(sch_1):page54_i43:vss(8)" )
			)
			( pin "J6L1.263"
				( objectStatus "@baseboard_fab2_lib.baseboard_fab2(sch_1):page54_i43:vss(9)" )
			)
			( pin "J6L1.261"
				( objectStatus "@baseboard_fab2_lib.baseboard_fab2(sch_1):page54_i43:vss(10)" )
			)
			( pin "J6L1.259"
				( objectStatus "@baseboard_fab2_lib.baseboard_fab2(sch_1):page54_i43:vss(11)" )
			)
			( pin "J6L1.257"
				( objectStatus "@baseboard_fab2_lib.baseboard_fab2(sch_1):page54_i43:vss(12)" )
			)
			( pin "J6L1.254"
				( objectStatus "@baseboard_fab2_lib.baseboard_fab2(sch_1):page54_i43:vss(13)" )
			)
			( pin "J6L1.252"
				( objectStatus "@baseboard_fab2_lib.baseboard_fab2(sch_1):page54_i43:vss(14)" )
			)
			( pin "J6L1.250"
				( objectStatus "@baseboard_fab2_lib.baseboard_fab2(sch_1):page54_i43:vss(15)" )
			)
			( pin "J6L1.248"
				( objectStatus "@baseboard_fab2_lib.baseboard_fab2(sch_1):page54_i43:vss(16)" )
			)
			( pin "J6L1.246"
				( objectStatus "@baseboard_fab2_lib.baseboard_fab2(sch_1):page54_i43:vss(17)" )
			)
			( pin "J6L1.243"
				( objectStatus "@baseboard_fab2_lib.baseboard_fab2(sch_1):page54_i43:vss(18)" )
			)
			( pin "J6L1.241"
				( objectStatus "@baseboard_fab2_lib.baseboard_fab2(sch_1):page54_i43:vss(19)" )
			)
			( pin "J6L1.239"
				( objectStatus "@baseboard_fab2_lib.baseboard_fab2(sch_1):page54_i43:vss(20)" )
			)
			( pin "J6L1.202"
				( objectStatus "@baseboard_fab2_lib.baseboard_fab2(sch_1):page54_i43:vss(21)" )
			)
			( pin "J6L1.200"
				( objectStatus "@baseboard_fab2_lib.baseboard_fab2(sch_1):page54_i43:vss(22)" )
			)
			( pin "J6L1.198"
				( objectStatus "@baseboard_fab2_lib.baseboard_fab2(sch_1):page54_i43:vss(23)" )
			)
			( pin "J6L1.195"
				( objectStatus "@baseboard_fab2_lib.baseboard_fab2(sch_1):page54_i43:vss(24)" )
			)
			( pin "J6L1.193"
				( objectStatus "@baseboard_fab2_lib.baseboard_fab2(sch_1):page54_i43:vss(25)" )
			)
			( pin "J6L1.191"
				( objectStatus "@baseboard_fab2_lib.baseboard_fab2(sch_1):page54_i43:vss(26)" )
			)
			( pin "J6L1.189"
				( objectStatus "@baseboard_fab2_lib.baseboard_fab2(sch_1):page54_i43:vss(27)" )
			)
			( pin "J6L1.187"
				( objectStatus "@baseboard_fab2_lib.baseboard_fab2(sch_1):page54_i43:vss(28)" )
			)
			( pin "J6L1.184"
				( objectStatus "@baseboard_fab2_lib.baseboard_fab2(sch_1):page54_i43:vss(29)" )
			)
			( pin "J6L1.182"
				( objectStatus "@baseboard_fab2_lib.baseboard_fab2(sch_1):page54_i43:vss(30)" )
			)
			( pin "J6L1.180"
				( objectStatus "@baseboard_fab2_lib.baseboard_fab2(sch_1):page54_i43:vss(31)" )
			)
			( pin "J6L1.178"
				( objectStatus "@baseboard_fab2_lib.baseboard_fab2(sch_1):page54_i43:vss(32)" )
			)
			( pin "J6L1.176"
				( objectStatus "@baseboard_fab2_lib.baseboard_fab2(sch_1):page54_i43:vss(33)" )
			)
			( pin "J6L1.173"
				( objectStatus "@baseboard_fab2_lib.baseboard_fab2(sch_1):page54_i43:vss(34)" )
			)
			( pin "J6L1.171"
				( objectStatus "@baseboard_fab2_lib.baseboard_fab2(sch_1):page54_i43:vss(35)" )
			)
			( pin "J6L1.169"
				( objectStatus "@baseboard_fab2_lib.baseboard_fab2(sch_1):page54_i43:vss(36)" )
			)
			( pin "J6L1.167"
				( objectStatus "@baseboard_fab2_lib.baseboard_fab2(sch_1):page54_i43:vss(37)" )
			)
			( pin "J6L1.165"
				( objectStatus "@baseboard_fab2_lib.baseboard_fab2(sch_1):page54_i43:vss(38)" )
			)
			( pin "J6L1.162"
				( objectStatus "@baseboard_fab2_lib.baseboard_fab2(sch_1):page54_i43:vss(39)" )
			)
			( pin "J6L1.160"
				( objectStatus "@baseboard_fab2_lib.baseboard_fab2(sch_1):page54_i43:vss(40)" )
			)
			( pin "J6L1.158"
				( objectStatus "@baseboard_fab2_lib.baseboard_fab2(sch_1):page54_i43:vss(41)" )
			)
			( pin "J6L1.156"
				( objectStatus "@baseboard_fab2_lib.baseboard_fab2(sch_1):page54_i43:vss(42)" )
			)
			( pin "J6L1.154"
				( objectStatus "@baseboard_fab2_lib.baseboard_fab2(sch_1):page54_i43:vss(43)" )
			)
			( pin "J6L1.151"
				( objectStatus "@baseboard_fab2_lib.baseboard_fab2(sch_1):page54_i43:vss(44)" )
			)
			( pin "J6L1.149"
				( objectStatus "@baseboard_fab2_lib.baseboard_fab2(sch_1):page54_i43:vss(45)" )
			)
			( pin "J6L1.147"
				( objectStatus "@baseboard_fab2_lib.baseboard_fab2(sch_1):page54_i43:vss(46)" )
			)
			( pin "J6L1.138"
				( objectStatus "@baseboard_fab2_lib.baseboard_fab2(sch_1):page54_i43:vss(47)" )
			)
			( pin "J6L1.136"
				( objectStatus "@baseboard_fab2_lib.baseboard_fab2(sch_1):page54_i43:vss(48)" )
			)
			( pin "J6L1.134"
				( objectStatus "@baseboard_fab2_lib.baseboard_fab2(sch_1):page54_i43:vss(49)" )
			)
			( pin "J6L1.131"
				( objectStatus "@baseboard_fab2_lib.baseboard_fab2(sch_1):page54_i43:vss(50)" )
			)
			( pin "J6L1.129"
				( objectStatus "@baseboard_fab2_lib.baseboard_fab2(sch_1):page54_i43:vss(51)" )
			)
			( pin "J6L1.127"
				( objectStatus "@baseboard_fab2_lib.baseboard_fab2(sch_1):page54_i43:vss(52)" )
			)
			( pin "J6L1.125"
				( objectStatus "@baseboard_fab2_lib.baseboard_fab2(sch_1):page54_i43:vss(53)" )
			)
			( pin "J6L1.123"
				( objectStatus "@baseboard_fab2_lib.baseboard_fab2(sch_1):page54_i43:vss(54)" )
			)
			( pin "J6L1.120"
				( objectStatus "@baseboard_fab2_lib.baseboard_fab2(sch_1):page54_i43:vss(55)" )
			)
			( pin "J6L1.118"
				( objectStatus "@baseboard_fab2_lib.baseboard_fab2(sch_1):page54_i43:vss(56)" )
			)
			( pin "J6L1.116"
				( objectStatus "@baseboard_fab2_lib.baseboard_fab2(sch_1):page54_i43:vss(57)" )
			)
			( pin "J6L1.114"
				( objectStatus "@baseboard_fab2_lib.baseboard_fab2(sch_1):page54_i43:vss(58)" )
			)
			( pin "J6L1.112"
				( objectStatus "@baseboard_fab2_lib.baseboard_fab2(sch_1):page54_i43:vss(59)" )
			)
			( pin "J6L1.109"
				( objectStatus "@baseboard_fab2_lib.baseboard_fab2(sch_1):page54_i43:vss(60)" )
			)
			( pin "J6L1.107"
				( objectStatus "@baseboard_fab2_lib.baseboard_fab2(sch_1):page54_i43:vss(61)" )
			)
			( pin "J6L1.105"
				( objectStatus "@baseboard_fab2_lib.baseboard_fab2(sch_1):page54_i43:vss(62)" )
			)
			( pin "J6L1.103"
				( objectStatus "@baseboard_fab2_lib.baseboard_fab2(sch_1):page54_i43:vss(63)" )
			)
			( pin "J6L1.101"
				( objectStatus "@baseboard_fab2_lib.baseboard_fab2(sch_1):page54_i43:vss(64)" )
			)
			( pin "J6L1.98"
				( objectStatus "@baseboard_fab2_lib.baseboard_fab2(sch_1):page54_i43:vss(65)" )
			)
			( pin "J6L1.96"
				( objectStatus "@baseboard_fab2_lib.baseboard_fab2(sch_1):page54_i43:vss(66)" )
			)
			( pin "J6L1.94"
				( objectStatus "@baseboard_fab2_lib.baseboard_fab2(sch_1):page54_i43:vss(67)" )
			)
			( pin "J6L1.57"
				( objectStatus "@baseboard_fab2_lib.baseboard_fab2(sch_1):page54_i43:vss(68)" )
			)
			( pin "J6L1.55"
				( objectStatus "@baseboard_fab2_lib.baseboard_fab2(sch_1):page54_i43:vss(69)" )
			)
			( pin "J6L1.53"
				( objectStatus "@baseboard_fab2_lib.baseboard_fab2(sch_1):page54_i43:vss(70)" )
			)
			( pin "J6L1.50"
				( objectStatus "@baseboard_fab2_lib.baseboard_fab2(sch_1):page54_i43:vss(71)" )
			)
			( pin "J6L1.48"
				( objectStatus "@baseboard_fab2_lib.baseboard_fab2(sch_1):page54_i43:vss(72)" )
			)
			( pin "J6L1.46"
				( objectStatus "@baseboard_fab2_lib.baseboard_fab2(sch_1):page54_i43:vss(73)" )
			)
			( pin "J6L1.44"
				( objectStatus "@baseboard_fab2_lib.baseboard_fab2(sch_1):page54_i43:vss(74)" )
			)
			( pin "J6L1.42"
				( objectStatus "@baseboard_fab2_lib.baseboard_fab2(sch_1):page54_i43:vss(75)" )
			)
			( pin "J6L1.39"
				( objectStatus "@baseboard_fab2_lib.baseboard_fab2(sch_1):page54_i43:vss(76)" )
			)
			( pin "J6L1.37"
				( objectStatus "@baseboard_fab2_lib.baseboard_fab2(sch_1):page54_i43:vss(77)" )
			)
			( pin "J6L1.35"
				( objectStatus "@baseboard_fab2_lib.baseboard_fab2(sch_1):page54_i43:vss(78)" )
			)
			( pin "J6L1.33"
				( objectStatus "@baseboard_fab2_lib.baseboard_fab2(sch_1):page54_i43:vss(79)" )
			)
			( pin "J6L1.31"
				( objectStatus "@baseboard_fab2_lib.baseboard_fab2(sch_1):page54_i43:vss(80)" )
			)
			( pin "J6L1.28"
				( objectStatus "@baseboard_fab2_lib.baseboard_fab2(sch_1):page54_i43:vss(81)" )
			)
			( pin "J6L1.26"
				( objectStatus "@baseboard_fab2_lib.baseboard_fab2(sch_1):page54_i43:vss(82)" )
			)
			( pin "J6L1.24"
				( objectStatus "@baseboard_fab2_lib.baseboard_fab2(sch_1):page54_i43:vss(83)" )
			)
			( pin "J6L1.22"
				( objectStatus "@baseboard_fab2_lib.baseboard_fab2(sch_1):page54_i43:vss(84)" )
			)
			( pin "J6L1.20"
				( objectStatus "@baseboard_fab2_lib.baseboard_fab2(sch_1):page54_i43:vss(85)" )
			)
			( pin "J6L1.17"
				( objectStatus "@baseboard_fab2_lib.baseboard_fab2(sch_1):page54_i43:vss(86)" )
			)
			( pin "J6L1.15"
				( objectStatus "@baseboard_fab2_lib.baseboard_fab2(sch_1):page54_i43:vss(87)" )
			)
			( pin "J6L1.13"
				( objectStatus "@baseboard_fab2_lib.baseboard_fab2(sch_1):page54_i43:vss(88)" )
			)
			( pin "J6L1.11"
				( objectStatus "@baseboard_fab2_lib.baseboard_fab2(sch_1):page54_i43:vss(89)" )
			)
			( pin "J6L1.9"
				( objectStatus "@baseboard_fab2_lib.baseboard_fab2(sch_1):page54_i43:vss(90)" )
			)
			( pin "J6L1.6"
				( objectStatus "@baseboard_fab2_lib.baseboard_fab2(sch_1):page54_i43:vss(91)" )
			)
			( pin "J6L1.4"
				( objectStatus "@baseboard_fab2_lib.baseboard_fab2(sch_1):page54_i43:vss(92)" )
			)
			( pin "J6L1.2"
				( objectStatus "@baseboard_fab2_lib.baseboard_fab2(sch_1):page54_i43:vss(93)" )
			)
			( pin "J6L1.152"
				( objectStatus "@baseboard_fab2_lib.baseboard_fab2(sch_1):page54_i66:dqs0n" )
			)
			( pin "J6L1.153"
				( objectStatus "@baseboard_fab2_lib.baseboard_fab2(sch_1):page54_i66:dqs0p" )
			)
			( pin "J6L1.163"
				( objectStatus "@baseboard_fab2_lib.baseboard_fab2(sch_1):page54_i66:dqs1n" )
			)
			( pin "J6L1.164"
				( objectStatus "@baseboard_fab2_lib.baseboard_fab2(sch_1):page54_i66:dqs1p" )
			)
			( pin "J6L1.174"
				( objectStatus "@baseboard_fab2_lib.baseboard_fab2(sch_1):page54_i66:dqs2n" )
			)
			( pin "J6L1.175"
				( objectStatus "@baseboard_fab2_lib.baseboard_fab2(sch_1):page54_i66:dqs2p" )
			)
			( pin "J6L1.185"
				( objectStatus "@baseboard_fab2_lib.baseboard_fab2(sch_1):page54_i66:dqs3n" )
			)
			( pin "J6L1.186"
				( objectStatus "@baseboard_fab2_lib.baseboard_fab2(sch_1):page54_i66:dqs3p" )
			)
			( pin "J6L1.244"
				( objectStatus "@baseboard_fab2_lib.baseboard_fab2(sch_1):page54_i66:dqs4n" )
			)
			( pin "J6L1.245"
				( objectStatus "@baseboard_fab2_lib.baseboard_fab2(sch_1):page54_i66:dqs4p" )
			)
			( pin "J6L1.255"
				( objectStatus "@baseboard_fab2_lib.baseboard_fab2(sch_1):page54_i66:dqs5n" )
			)
			( pin "J6L1.256"
				( objectStatus "@baseboard_fab2_lib.baseboard_fab2(sch_1):page54_i66:dqs5p" )
			)
			( pin "J6L1.266"
				( objectStatus "@baseboard_fab2_lib.baseboard_fab2(sch_1):page54_i66:dqs6n" )
			)
			( pin "J6L1.267"
				( objectStatus "@baseboard_fab2_lib.baseboard_fab2(sch_1):page54_i66:dqs6p" )
			)
			( pin "J6L1.277"
				( objectStatus "@baseboard_fab2_lib.baseboard_fab2(sch_1):page54_i66:dqs7n" )
			)
			( pin "J6L1.278"
				( objectStatus "@baseboard_fab2_lib.baseboard_fab2(sch_1):page54_i66:dqs7p" )
			)
			( pin "J6L1.196"
				( objectStatus "@baseboard_fab2_lib.baseboard_fab2(sch_1):page54_i66:dqs8n" )
			)
			( pin "J6L1.197"
				( objectStatus "@baseboard_fab2_lib.baseboard_fab2(sch_1):page54_i66:dqs8p" )
			)
			( pin "J6L1.8"
				( objectStatus "@baseboard_fab2_lib.baseboard_fab2(sch_1):page54_i66:dqs9n" )
			)
			( pin "J6L1.7"
				( objectStatus "@baseboard_fab2_lib.baseboard_fab2(sch_1):page54_i66:dqs9p" )
			)
			( pin "J6L1.19"
				( objectStatus "@baseboard_fab2_lib.baseboard_fab2(sch_1):page54_i66:dqs10n" )
			)
			( pin "J6L1.18"
				( objectStatus "@baseboard_fab2_lib.baseboard_fab2(sch_1):page54_i66:dqs10p" )
			)
			( pin "J6L1.30"
				( objectStatus "@baseboard_fab2_lib.baseboard_fab2(sch_1):page54_i66:dqs11n" )
			)
			( pin "J6L1.29"
				( objectStatus "@baseboard_fab2_lib.baseboard_fab2(sch_1):page54_i66:dqs11p" )
			)
			( pin "J6L1.41"
				( objectStatus "@baseboard_fab2_lib.baseboard_fab2(sch_1):page54_i66:dqs12n" )
			)
			( pin "J6L1.40"
				( objectStatus "@baseboard_fab2_lib.baseboard_fab2(sch_1):page54_i66:dqs12p" )
			)
			( pin "J6L1.100"
				( objectStatus "@baseboard_fab2_lib.baseboard_fab2(sch_1):page54_i66:dqs13n" )
			)
			( pin "J6L1.99"
				( objectStatus "@baseboard_fab2_lib.baseboard_fab2(sch_1):page54_i66:dqs13p" )
			)
			( pin "J6L1.111"
				( objectStatus "@baseboard_fab2_lib.baseboard_fab2(sch_1):page54_i66:dqs14n" )
			)
			( pin "J6L1.110"
				( objectStatus "@baseboard_fab2_lib.baseboard_fab2(sch_1):page54_i66:dqs14p" )
			)
			( pin "J6L1.122"
				( objectStatus "@baseboard_fab2_lib.baseboard_fab2(sch_1):page54_i66:dqs15n" )
			)
			( pin "J6L1.121"
				( objectStatus "@baseboard_fab2_lib.baseboard_fab2(sch_1):page54_i66:dqs15p" )
			)
			( pin "J6L1.133"
				( objectStatus "@baseboard_fab2_lib.baseboard_fab2(sch_1):page54_i66:dqs16n" )
			)
			( pin "J6L1.132"
				( objectStatus "@baseboard_fab2_lib.baseboard_fab2(sch_1):page54_i66:dqs16p" )
			)
			( pin "J6L1.52"
				( objectStatus "@baseboard_fab2_lib.baseboard_fab2(sch_1):page54_i66:dqs17n" )
			)
			( pin "J6L1.51"
				( objectStatus "@baseboard_fab2_lib.baseboard_fab2(sch_1):page54_i66:dqs17p" )
			)
			( pin "J6L1.79"
				( objectStatus "@baseboard_fab2_lib.baseboard_fab2(sch_1):page54_i111:a0" )
			)
			( pin "J6L1.72"
				( objectStatus "@baseboard_fab2_lib.baseboard_fab2(sch_1):page54_i111:a1" )
			)
			( pin "J6L1.216"
				( objectStatus "@baseboard_fab2_lib.baseboard_fab2(sch_1):page54_i111:a2" )
			)
			( pin "J6L1.71"
				( objectStatus "@baseboard_fab2_lib.baseboard_fab2(sch_1):page54_i111:a3" )
			)
			( pin "J6L1.214"
				( objectStatus "@baseboard_fab2_lib.baseboard_fab2(sch_1):page54_i111:a4" )
			)
			( pin "J6L1.213"
				( objectStatus "@baseboard_fab2_lib.baseboard_fab2(sch_1):page54_i111:a5" )
			)
			( pin "J6L1.69"
				( objectStatus "@baseboard_fab2_lib.baseboard_fab2(sch_1):page54_i111:a6" )
			)
			( pin "J6L1.211"
				( objectStatus "@baseboard_fab2_lib.baseboard_fab2(sch_1):page54_i111:a7" )
			)
			( pin "J6L1.68"
				( objectStatus "@baseboard_fab2_lib.baseboard_fab2(sch_1):page54_i111:a8" )
			)
			( pin "J6L1.66"
				( objectStatus "@baseboard_fab2_lib.baseboard_fab2(sch_1):page54_i111:a9" )
			)
			( pin "J6L1.225"
				( objectStatus "@baseboard_fab2_lib.baseboard_fab2(sch_1):page54_i111:a10" )
			)
			( pin "J6L1.210"
				( objectStatus "@baseboard_fab2_lib.baseboard_fab2(sch_1):page54_i111:a11" )
			)
			( pin "J6L1.65"
				( objectStatus "@baseboard_fab2_lib.baseboard_fab2(sch_1):page54_i111:a12" )
			)
			( pin "J6L1.232"
				( objectStatus "@baseboard_fab2_lib.baseboard_fab2(sch_1):page54_i111:a13" )
			)
			( pin "J6L1.228"
				( objectStatus "@baseboard_fab2_lib.baseboard_fab2(sch_1):page54_i111:a14_we_n" )
			)
			( pin "J6L1.86"
				( objectStatus "@baseboard_fab2_lib.baseboard_fab2(sch_1):page54_i111:a15_cas_n" )
			)
			( pin "J6L1.82"
				( objectStatus "@baseboard_fab2_lib.baseboard_fab2(sch_1):page54_i111:a16_ras_n" )
			)
			( pin "J6L1.234"
				( objectStatus "@baseboard_fab2_lib.baseboard_fab2(sch_1):page54_i111:a17" )
			)
			( pin "J6L1.62"
				( objectStatus "@baseboard_fab2_lib.baseboard_fab2(sch_1):page54_i111:act_n" )
			)
			( pin "J6L1.208"
				( objectStatus "@baseboard_fab2_lib.baseboard_fab2(sch_1):page54_i111:alert_n" )
			)
			( pin "J6L1.81"
				( objectStatus "@baseboard_fab2_lib.baseboard_fab2(sch_1):page54_i111:ba(0)" )
			)
			( pin "J6L1.224"
				( objectStatus "@baseboard_fab2_lib.baseboard_fab2(sch_1):page54_i111:ba(1)" )
			)
			( pin "J6L1.63"
				( objectStatus "@baseboard_fab2_lib.baseboard_fab2(sch_1):page54_i111:bg(0)" )
			)
			( pin "J6L1.207"
				( objectStatus "@baseboard_fab2_lib.baseboard_fab2(sch_1):page54_i111:bg(1)" )
			)
			( pin "J6L1.235"
				( objectStatus "@baseboard_fab2_lib.baseboard_fab2(sch_1):page54_i111:c(2)" )
			)
			( pin "J6L1.49"
				( objectStatus "@baseboard_fab2_lib.baseboard_fab2(sch_1):page54_i111:cb(0)" )
			)
			( pin "J6L1.194"
				( objectStatus "@baseboard_fab2_lib.baseboard_fab2(sch_1):page54_i111:cb(1)" )
			)
			( pin "J6L1.56"
				( objectStatus "@baseboard_fab2_lib.baseboard_fab2(sch_1):page54_i111:cb(2)" )
			)
			( pin "J6L1.201"
				( objectStatus "@baseboard_fab2_lib.baseboard_fab2(sch_1):page54_i111:cb(3)" )
			)
			( pin "J6L1.47"
				( objectStatus "@baseboard_fab2_lib.baseboard_fab2(sch_1):page54_i111:cb(4)" )
			)
			( pin "J6L1.192"
				( objectStatus "@baseboard_fab2_lib.baseboard_fab2(sch_1):page54_i111:cb(5)" )
			)
			( pin "J6L1.54"
				( objectStatus "@baseboard_fab2_lib.baseboard_fab2(sch_1):page54_i111:cb(6)" )
			)
			( pin "J6L1.199"
				( objectStatus "@baseboard_fab2_lib.baseboard_fab2(sch_1):page54_i111:cb(7)" )
			)
			( pin "J6L1.75"
				( objectStatus "@baseboard_fab2_lib.baseboard_fab2(sch_1):page54_i111:ck0n" )
			)
			( pin "J6L1.74"
				( objectStatus "@baseboard_fab2_lib.baseboard_fab2(sch_1):page54_i111:ck0p" )
			)
			( pin "J6L1.219"
				( objectStatus "@baseboard_fab2_lib.baseboard_fab2(sch_1):page54_i111:ck1n" )
			)
			( pin "J6L1.218"
				( objectStatus "@baseboard_fab2_lib.baseboard_fab2(sch_1):page54_i111:ck1p" )
			)
			( pin "J6L1.60"
				( objectStatus "@baseboard_fab2_lib.baseboard_fab2(sch_1):page54_i111:cke(0)" )
			)
			( pin "J6L1.203"
				( objectStatus "@baseboard_fab2_lib.baseboard_fab2(sch_1):page54_i111:cke(1)" )
			)
			( pin "J6L1.5"
				( objectStatus "@baseboard_fab2_lib.baseboard_fab2(sch_1):page54_i111:dq(0)" )
			)
			( pin "J6L1.150"
				( objectStatus "@baseboard_fab2_lib.baseboard_fab2(sch_1):page54_i111:dq(1)" )
			)
			( pin "J6L1.12"
				( objectStatus "@baseboard_fab2_lib.baseboard_fab2(sch_1):page54_i111:dq(2)" )
			)
			( pin "J6L1.157"
				( objectStatus "@baseboard_fab2_lib.baseboard_fab2(sch_1):page54_i111:dq(3)" )
			)
			( pin "J6L1.3"
				( objectStatus "@baseboard_fab2_lib.baseboard_fab2(sch_1):page54_i111:dq(4)" )
			)
			( pin "J6L1.148"
				( objectStatus "@baseboard_fab2_lib.baseboard_fab2(sch_1):page54_i111:dq(5)" )
			)
			( pin "J6L1.10"
				( objectStatus "@baseboard_fab2_lib.baseboard_fab2(sch_1):page54_i111:dq(6)" )
			)
			( pin "J6L1.155"
				( objectStatus "@baseboard_fab2_lib.baseboard_fab2(sch_1):page54_i111:dq(7)" )
			)
			( pin "J6L1.16"
				( objectStatus "@baseboard_fab2_lib.baseboard_fab2(sch_1):page54_i111:dq(8)" )
			)
			( pin "J6L1.161"
				( objectStatus "@baseboard_fab2_lib.baseboard_fab2(sch_1):page54_i111:dq(9)" )
			)
			( pin "J6L1.23"
				( objectStatus "@baseboard_fab2_lib.baseboard_fab2(sch_1):page54_i111:dq(10)" )
			)
			( pin "J6L1.168"
				( objectStatus "@baseboard_fab2_lib.baseboard_fab2(sch_1):page54_i111:dq(11)" )
			)
			( pin "J6L1.14"
				( objectStatus "@baseboard_fab2_lib.baseboard_fab2(sch_1):page54_i111:dq(12)" )
			)
			( pin "J6L1.159"
				( objectStatus "@baseboard_fab2_lib.baseboard_fab2(sch_1):page54_i111:dq(13)" )
			)
			( pin "J6L1.21"
				( objectStatus "@baseboard_fab2_lib.baseboard_fab2(sch_1):page54_i111:dq(14)" )
			)
			( pin "J6L1.166"
				( objectStatus "@baseboard_fab2_lib.baseboard_fab2(sch_1):page54_i111:dq(15)" )
			)
			( pin "J6L1.27"
				( objectStatus "@baseboard_fab2_lib.baseboard_fab2(sch_1):page54_i111:dq(16)" )
			)
			( pin "J6L1.172"
				( objectStatus "@baseboard_fab2_lib.baseboard_fab2(sch_1):page54_i111:dq(17)" )
			)
			( pin "J6L1.34"
				( objectStatus "@baseboard_fab2_lib.baseboard_fab2(sch_1):page54_i111:dq(18)" )
			)
			( pin "J6L1.179"
				( objectStatus "@baseboard_fab2_lib.baseboard_fab2(sch_1):page54_i111:dq(19)" )
			)
			( pin "J6L1.25"
				( objectStatus "@baseboard_fab2_lib.baseboard_fab2(sch_1):page54_i111:dq(20)" )
			)
			( pin "J6L1.170"
				( objectStatus "@baseboard_fab2_lib.baseboard_fab2(sch_1):page54_i111:dq(21)" )
			)
			( pin "J6L1.32"
				( objectStatus "@baseboard_fab2_lib.baseboard_fab2(sch_1):page54_i111:dq(22)" )
			)
			( pin "J6L1.177"
				( objectStatus "@baseboard_fab2_lib.baseboard_fab2(sch_1):page54_i111:dq(23)" )
			)
			( pin "J6L1.38"
				( objectStatus "@baseboard_fab2_lib.baseboard_fab2(sch_1):page54_i111:dq(24)" )
			)
			( pin "J6L1.183"
				( objectStatus "@baseboard_fab2_lib.baseboard_fab2(sch_1):page54_i111:dq(25)" )
			)
			( pin "J6L1.45"
				( objectStatus "@baseboard_fab2_lib.baseboard_fab2(sch_1):page54_i111:dq(26)" )
			)
			( pin "J6L1.190"
				( objectStatus "@baseboard_fab2_lib.baseboard_fab2(sch_1):page54_i111:dq(27)" )
			)
			( pin "J6L1.36"
				( objectStatus "@baseboard_fab2_lib.baseboard_fab2(sch_1):page54_i111:dq(28)" )
			)
			( pin "J6L1.181"
				( objectStatus "@baseboard_fab2_lib.baseboard_fab2(sch_1):page54_i111:dq(29)" )
			)
			( pin "J6L1.43"
				( objectStatus "@baseboard_fab2_lib.baseboard_fab2(sch_1):page54_i111:dq(30)" )
			)
			( pin "J6L1.188"
				( objectStatus "@baseboard_fab2_lib.baseboard_fab2(sch_1):page54_i111:dq(31)" )
			)
			( pin "J6L1.97"
				( objectStatus "@baseboard_fab2_lib.baseboard_fab2(sch_1):page54_i111:dq(32)" )
			)
			( pin "J6L1.242"
				( objectStatus "@baseboard_fab2_lib.baseboard_fab2(sch_1):page54_i111:dq(33)" )
			)
			( pin "J6L1.104"
				( objectStatus "@baseboard_fab2_lib.baseboard_fab2(sch_1):page54_i111:dq(34)" )
			)
			( pin "J6L1.249"
				( objectStatus "@baseboard_fab2_lib.baseboard_fab2(sch_1):page54_i111:dq(35)" )
			)
			( pin "J6L1.95"
				( objectStatus "@baseboard_fab2_lib.baseboard_fab2(sch_1):page54_i111:dq(36)" )
			)
			( pin "J6L1.240"
				( objectStatus "@baseboard_fab2_lib.baseboard_fab2(sch_1):page54_i111:dq(37)" )
			)
			( pin "J6L1.102"
				( objectStatus "@baseboard_fab2_lib.baseboard_fab2(sch_1):page54_i111:dq(38)" )
			)
			( pin "J6L1.247"
				( objectStatus "@baseboard_fab2_lib.baseboard_fab2(sch_1):page54_i111:dq(39)" )
			)
			( pin "J6L1.108"
				( objectStatus "@baseboard_fab2_lib.baseboard_fab2(sch_1):page54_i111:dq(40)" )
			)
			( pin "J6L1.253"
				( objectStatus "@baseboard_fab2_lib.baseboard_fab2(sch_1):page54_i111:dq(41)" )
			)
			( pin "J6L1.115"
				( objectStatus "@baseboard_fab2_lib.baseboard_fab2(sch_1):page54_i111:dq(42)" )
			)
			( pin "J6L1.260"
				( objectStatus "@baseboard_fab2_lib.baseboard_fab2(sch_1):page54_i111:dq(43)" )
			)
			( pin "J6L1.106"
				( objectStatus "@baseboard_fab2_lib.baseboard_fab2(sch_1):page54_i111:dq(44)" )
			)
			( pin "J6L1.251"
				( objectStatus "@baseboard_fab2_lib.baseboard_fab2(sch_1):page54_i111:dq(45)" )
			)
			( pin "J6L1.113"
				( objectStatus "@baseboard_fab2_lib.baseboard_fab2(sch_1):page54_i111:dq(46)" )
			)
			( pin "J6L1.258"
				( objectStatus "@baseboard_fab2_lib.baseboard_fab2(sch_1):page54_i111:dq(47)" )
			)
			( pin "J6L1.119"
				( objectStatus "@baseboard_fab2_lib.baseboard_fab2(sch_1):page54_i111:dq(48)" )
			)
			( pin "J6L1.264"
				( objectStatus "@baseboard_fab2_lib.baseboard_fab2(sch_1):page54_i111:dq(49)" )
			)
			( pin "J6L1.126"
				( objectStatus "@baseboard_fab2_lib.baseboard_fab2(sch_1):page54_i111:dq(50)" )
			)
			( pin "J6L1.271"
				( objectStatus "@baseboard_fab2_lib.baseboard_fab2(sch_1):page54_i111:dq(51)" )
			)
			( pin "J6L1.117"
				( objectStatus "@baseboard_fab2_lib.baseboard_fab2(sch_1):page54_i111:dq(52)" )
			)
			( pin "J6L1.262"
				( objectStatus "@baseboard_fab2_lib.baseboard_fab2(sch_1):page54_i111:dq(53)" )
			)
			( pin "J6L1.124"
				( objectStatus "@baseboard_fab2_lib.baseboard_fab2(sch_1):page54_i111:dq(54)" )
			)
			( pin "J6L1.269"
				( objectStatus "@baseboard_fab2_lib.baseboard_fab2(sch_1):page54_i111:dq(55)" )
			)
			( pin "J6L1.130"
				( objectStatus "@baseboard_fab2_lib.baseboard_fab2(sch_1):page54_i111:dq(56)" )
			)
			( pin "J6L1.275"
				( objectStatus "@baseboard_fab2_lib.baseboard_fab2(sch_1):page54_i111:dq(57)" )
			)
			( pin "J6L1.137"
				( objectStatus "@baseboard_fab2_lib.baseboard_fab2(sch_1):page54_i111:dq(58)" )
			)
			( pin "J6L1.282"
				( objectStatus "@baseboard_fab2_lib.baseboard_fab2(sch_1):page54_i111:dq(59)" )
			)
			( pin "J6L1.128"
				( objectStatus "@baseboard_fab2_lib.baseboard_fab2(sch_1):page54_i111:dq(60)" )
			)
			( pin "J6L1.273"
				( objectStatus "@baseboard_fab2_lib.baseboard_fab2(sch_1):page54_i111:dq(61)" )
			)
			( pin "J6L1.135"
				( objectStatus "@baseboard_fab2_lib.baseboard_fab2(sch_1):page54_i111:dq(62)" )
			)
			( pin "J6L1.280"
				( objectStatus "@baseboard_fab2_lib.baseboard_fab2(sch_1):page54_i111:dq(63)" )
			)
			( pin "J6L1.78"
				( objectStatus "@baseboard_fab2_lib.baseboard_fab2(sch_1):page54_i111:event_n" )
			)
			( pin "J6L1.87"
				( objectStatus "@baseboard_fab2_lib.baseboard_fab2(sch_1):page54_i111:odt(0)" )
			)
			( pin "J6L1.91"
				( objectStatus "@baseboard_fab2_lib.baseboard_fab2(sch_1):page54_i111:odt(1)" )
			)
			( pin "J6L1.222"
				( objectStatus "@baseboard_fab2_lib.baseboard_fab2(sch_1):page54_i111:par" )
			)
			( pin "J6L1.58"
				( objectStatus "@baseboard_fab2_lib.baseboard_fab2(sch_1):page54_i111:reset_n" )
			)
			( pin "J6L1.205"
				( objectStatus "@baseboard_fab2_lib.baseboard_fab2(sch_1):page54_i111:rfu(0)" )
			)
			( pin "J6L1.227"
				( objectStatus "@baseboard_fab2_lib.baseboard_fab2(sch_1):page54_i111:rfu(1)" )
			)
			( pin "J6L1.144"
				( objectStatus "@baseboard_fab2_lib.baseboard_fab2(sch_1):page54_i111:rfu(2)" )
			)
			( pin "J6L1.84"
				( objectStatus "@baseboard_fab2_lib.baseboard_fab2(sch_1):page54_i111:s0_n" )
			)
			( pin "J6L1.89"
				( objectStatus "@baseboard_fab2_lib.baseboard_fab2(sch_1):page54_i111:s1_n" )
			)
			( pin "J6L1.93"
				( objectStatus "@baseboard_fab2_lib.baseboard_fab2(sch_1):page54_i111:s2_n_c(0)" )
			)
			( pin "J6L1.237"
				( objectStatus "@baseboard_fab2_lib.baseboard_fab2(sch_1):page54_i111:s3_n_c(1)" )
			)
			( pin "J6L1.139"
				( objectStatus "@baseboard_fab2_lib.baseboard_fab2(sch_1):page54_i111:sa(0)" )
			)
			( pin "J6L1.140"
				( objectStatus "@baseboard_fab2_lib.baseboard_fab2(sch_1):page54_i111:sa(1)" )
			)
			( pin "J6L1.238"
				( objectStatus "@baseboard_fab2_lib.baseboard_fab2(sch_1):page54_i111:sa(2)" )
			)
			( pin "J6L1.230"
				( objectStatus "@baseboard_fab2_lib.baseboard_fab2(sch_1):page54_i111:save_n_nc" )
			)
			( pin "J6L1.141"
				( objectStatus "@baseboard_fab2_lib.baseboard_fab2(sch_1):page54_i111:scl" )
			)
			( pin "J6L1.285"
				( objectStatus "@baseboard_fab2_lib.baseboard_fab2(sch_1):page54_i111:sda" )
			)
			( pin "J6L1.284"
				( objectStatus "@baseboard_fab2_lib.baseboard_fab2(sch_1):page54_i111:vddspd" )
			)
			( pin "J6L1.146"
				( objectStatus "@baseboard_fab2_lib.baseboard_fab2(sch_1):page54_i111:vrefca" )
			)
			( pin "J6L1.145"
				( objectStatus "@baseboard_fab2_lib.baseboard_fab2(sch_1):page54_i170:\12v\(0)" )
			)
			( pin "J6L1.1"
				( objectStatus "@baseboard_fab2_lib.baseboard_fab2(sch_1):page54_i170:\12v\(1)" )
			)
			( pin "J6L1.236"
				( objectStatus "@baseboard_fab2_lib.baseboard_fab2(sch_1):page54_i170:vdd(0)" )
			)
			( pin "J6L1.233"
				( objectStatus "@baseboard_fab2_lib.baseboard_fab2(sch_1):page54_i170:vdd(1)" )
			)
			( pin "J6L1.231"
				( objectStatus "@baseboard_fab2_lib.baseboard_fab2(sch_1):page54_i170:vdd(2)" )
			)
			( pin "J6L1.229"
				( objectStatus "@baseboard_fab2_lib.baseboard_fab2(sch_1):page54_i170:vdd(3)" )
			)
			( pin "J6L1.226"
				( objectStatus "@baseboard_fab2_lib.baseboard_fab2(sch_1):page54_i170:vdd(4)" )
			)
			( pin "J6L1.223"
				( objectStatus "@baseboard_fab2_lib.baseboard_fab2(sch_1):page54_i170:vdd(5)" )
			)
			( pin "J6L1.220"
				( objectStatus "@baseboard_fab2_lib.baseboard_fab2(sch_1):page54_i170:vdd(6)" )
			)
			( pin "J6L1.217"
				( objectStatus "@baseboard_fab2_lib.baseboard_fab2(sch_1):page54_i170:vdd(7)" )
			)
			( pin "J6L1.215"
				( objectStatus "@baseboard_fab2_lib.baseboard_fab2(sch_1):page54_i170:vdd(8)" )
			)
			( pin "J6L1.212"
				( objectStatus "@baseboard_fab2_lib.baseboard_fab2(sch_1):page54_i170:vdd(9)" )
			)
			( pin "J6L1.209"
				( objectStatus "@baseboard_fab2_lib.baseboard_fab2(sch_1):page54_i170:vdd(10)" )
			)
			( pin "J6L1.206"
				( objectStatus "@baseboard_fab2_lib.baseboard_fab2(sch_1):page54_i170:vdd(11)" )
			)
			( pin "J6L1.204"
				( objectStatus "@baseboard_fab2_lib.baseboard_fab2(sch_1):page54_i170:vdd(12)" )
			)
			( pin "J6L1.92"
				( objectStatus "@baseboard_fab2_lib.baseboard_fab2(sch_1):page54_i170:vdd(13)" )
			)
			( pin "J6L1.90"
				( objectStatus "@baseboard_fab2_lib.baseboard_fab2(sch_1):page54_i170:vdd(14)" )
			)
			( pin "J6L1.88"
				( objectStatus "@baseboard_fab2_lib.baseboard_fab2(sch_1):page54_i170:vdd(15)" )
			)
			( pin "J6L1.85"
				( objectStatus "@baseboard_fab2_lib.baseboard_fab2(sch_1):page54_i170:vdd(16)" )
			)
			( pin "J6L1.83"
				( objectStatus "@baseboard_fab2_lib.baseboard_fab2(sch_1):page54_i170:vdd(17)" )
			)
			( pin "J6L1.80"
				( objectStatus "@baseboard_fab2_lib.baseboard_fab2(sch_1):page54_i170:vdd(18)" )
			)
			( pin "J6L1.76"
				( objectStatus "@baseboard_fab2_lib.baseboard_fab2(sch_1):page54_i170:vdd(19)" )
			)
			( pin "J6L1.73"
				( objectStatus "@baseboard_fab2_lib.baseboard_fab2(sch_1):page54_i170:vdd(20)" )
			)
			( pin "J6L1.70"
				( objectStatus "@baseboard_fab2_lib.baseboard_fab2(sch_1):page54_i170:vdd(21)" )
			)
			( pin "J6L1.67"
				( objectStatus "@baseboard_fab2_lib.baseboard_fab2(sch_1):page54_i170:vdd(22)" )
			)
			( pin "J6L1.64"
				( objectStatus "@baseboard_fab2_lib.baseboard_fab2(sch_1):page54_i170:vdd(23)" )
			)
			( pin "J6L1.61"
				( objectStatus "@baseboard_fab2_lib.baseboard_fab2(sch_1):page54_i170:vdd(24)" )
			)
			( pin "J6L1.59"
				( objectStatus "@baseboard_fab2_lib.baseboard_fab2(sch_1):page54_i170:vdd(25)" )
			)
			( pin "J6L1.287"
				( objectStatus "@baseboard_fab2_lib.baseboard_fab2(sch_1):page54_i170:vpp(0)" )
			)
			( pin "J6L1.286"
				( objectStatus "@baseboard_fab2_lib.baseboard_fab2(sch_1):page54_i170:vpp(1)" )
			)
			( pin "J6L1.288"
				( objectStatus "@baseboard_fab2_lib.baseboard_fab2(sch_1):page54_i170:vpp(2)" )
			)
			( pin "J6L1.143"
				( objectStatus "@baseboard_fab2_lib.baseboard_fab2(sch_1):page54_i170:vpp(3)" )
			)
			( pin "J6L1.142"
				( objectStatus "@baseboard_fab2_lib.baseboard_fab2(sch_1):page54_i170:vpp(4)" )
			)
			( pin "J6L1.221"
				( objectStatus "@baseboard_fab2_lib.baseboard_fab2(sch_1):page54_i170:vtt(0)" )
			)
			( pin "J6L1.77"
				( objectStatus "@baseboard_fab2_lib.baseboard_fab2(sch_1):page54_i170:vtt(1)" )
			)
			( pin "C4A5.1"
				( objectStatus "@baseboard_fab2_lib.baseboard_fab2(sch_1):page54_i179:a" )
			)
			( pin "C4A5.2"
				( objectStatus "@baseboard_fab2_lib.baseboard_fab2(sch_1):page54_i179:b" )
			)
			( pin "R9N1.1"
				( objectStatus "@baseboard_fab2_lib.baseboard_fab2(sch_1):page55_i4:a" )
			)
			( pin "R9N1.2"
				( objectStatus "@baseboard_fab2_lib.baseboard_fab2(sch_1):page55_i4:b" )
			)
			( pin "R9N2.1"
				( objectStatus "@baseboard_fab2_lib.baseboard_fab2(sch_1):page55_i7:a" )
			)
			( pin "R9N2.2"
				( objectStatus "@baseboard_fab2_lib.baseboard_fab2(sch_1):page55_i7:b" )
			)
			( pin "R3B2.1"
				( objectStatus "@baseboard_fab2_lib.baseboard_fab2(sch_1):page55_i19:a" )
			)
			( pin "R3B2.2"
				( objectStatus "@baseboard_fab2_lib.baseboard_fab2(sch_1):page55_i19:b" )
			)
			( pin "R3B4.1"
				( objectStatus "@baseboard_fab2_lib.baseboard_fab2(sch_1):page55_i21:a" )
			)
			( pin "R3B4.2"
				( objectStatus "@baseboard_fab2_lib.baseboard_fab2(sch_1):page55_i21:b" )
			)
			( pin "R1C2.1"
				( objectStatus "@baseboard_fab2_lib.baseboard_fab2(sch_1):page55_i24:a" )
			)
			( pin "R1C2.2"
				( objectStatus "@baseboard_fab2_lib.baseboard_fab2(sch_1):page55_i24:b" )
			)
			( pin "R1C3.1"
				( objectStatus "@baseboard_fab2_lib.baseboard_fab2(sch_1):page55_i25:a" )
			)
			( pin "R1C3.2"
				( objectStatus "@baseboard_fab2_lib.baseboard_fab2(sch_1):page55_i25:b" )
			)
			( pin "R1C1.1"
				( objectStatus "@baseboard_fab2_lib.baseboard_fab2(sch_1):page55_i26:a" )
			)
			( pin "R1C1.2"
				( objectStatus "@baseboard_fab2_lib.baseboard_fab2(sch_1):page55_i26:b" )
			)
			( pin "R3B1.1"
				( objectStatus "@baseboard_fab2_lib.baseboard_fab2(sch_1):page55_i27:a" )
			)
			( pin "R3B1.2"
				( objectStatus "@baseboard_fab2_lib.baseboard_fab2(sch_1):page55_i27:b" )
			)
			( pin "R3B5.1"
				( objectStatus "@baseboard_fab2_lib.baseboard_fab2(sch_1):page55_i28:a" )
			)
			( pin "R3B5.2"
				( objectStatus "@baseboard_fab2_lib.baseboard_fab2(sch_1):page55_i28:b" )
			)
			( pin "R3B3.1"
				( objectStatus "@baseboard_fab2_lib.baseboard_fab2(sch_1):page55_i29:a" )
			)
			( pin "R3B3.2"
				( objectStatus "@baseboard_fab2_lib.baseboard_fab2(sch_1):page55_i29:b" )
			)
			( pin "R7P19.1"
				( objectStatus "@baseboard_fab2_lib.baseboard_fab2(sch_1):page55_i115:a" )
			)
			( pin "R7P19.2"
				( objectStatus "@baseboard_fab2_lib.baseboard_fab2(sch_1):page55_i115:b" )
			)
			( pin "R3D1.1"
				( objectStatus "@baseboard_fab2_lib.baseboard_fab2(sch_1):page55_i116:a" )
			)
			( pin "R3D1.2"
				( objectStatus "@baseboard_fab2_lib.baseboard_fab2(sch_1):page55_i116:b" )
			)
			( pin "R3D2.1"
				( objectStatus "@baseboard_fab2_lib.baseboard_fab2(sch_1):page55_i117:a" )
			)
			( pin "R3D2.2"
				( objectStatus "@baseboard_fab2_lib.baseboard_fab2(sch_1):page55_i117:b" )
			)
			( pin "R3D3.1"
				( objectStatus "@baseboard_fab2_lib.baseboard_fab2(sch_1):page55_i118:a" )
			)
			( pin "R3D3.2"
				( objectStatus "@baseboard_fab2_lib.baseboard_fab2(sch_1):page55_i118:b" )
			)
			( pin "R7P16.1"
				( objectStatus "@baseboard_fab2_lib.baseboard_fab2(sch_1):page55_i119:a" )
			)
			( pin "R7P16.2"
				( objectStatus "@baseboard_fab2_lib.baseboard_fab2(sch_1):page55_i119:b" )
			)
			( pin "R7P8.1"
				( objectStatus "@baseboard_fab2_lib.baseboard_fab2(sch_1):page55_i123:a" )
			)
			( pin "R7P8.2"
				( objectStatus "@baseboard_fab2_lib.baseboard_fab2(sch_1):page55_i123:b" )
			)
			( pin "R7P10.1"
				( objectStatus "@baseboard_fab2_lib.baseboard_fab2(sch_1):page55_i124:a" )
			)
			( pin "R7P10.2"
				( objectStatus "@baseboard_fab2_lib.baseboard_fab2(sch_1):page55_i124:b" )
			)
			( pin "R3D19.1"
				( objectStatus "@baseboard_fab2_lib.baseboard_fab2(sch_1):page55_i125:a" )
			)
			( pin "R3D19.2"
				( objectStatus "@baseboard_fab2_lib.baseboard_fab2(sch_1):page55_i125:b" )
			)
			( pin "R7P11.1"
				( objectStatus "@baseboard_fab2_lib.baseboard_fab2(sch_1):page55_i126:a" )
			)
			( pin "R7P11.2"
				( objectStatus "@baseboard_fab2_lib.baseboard_fab2(sch_1):page55_i126:b" )
			)
			( pin "R7P17.1"
				( objectStatus "@baseboard_fab2_lib.baseboard_fab2(sch_1):page55_i140:a" )
			)
			( pin "R7P17.2"
				( objectStatus "@baseboard_fab2_lib.baseboard_fab2(sch_1):page55_i140:b" )
			)
			( pin "R3D4.1"
				( objectStatus "@baseboard_fab2_lib.baseboard_fab2(sch_1):page55_i155:a" )
			)
			( pin "R3D4.2"
				( objectStatus "@baseboard_fab2_lib.baseboard_fab2(sch_1):page55_i155:b" )
			)
			( pin "R7P26.1"
				( objectStatus "@baseboard_fab2_lib.baseboard_fab2(sch_1):page55_i156:a" )
			)
			( pin "R7P26.2"
				( objectStatus "@baseboard_fab2_lib.baseboard_fab2(sch_1):page55_i156:b" )
			)
			( pin "R8N1.1"
				( objectStatus "@baseboard_fab2_lib.baseboard_fab2(sch_1):page55_i157:a" )
			)
			( pin "R8N1.2"
				( objectStatus "@baseboard_fab2_lib.baseboard_fab2(sch_1):page55_i157:b" )
			)
			( pin "R8N4.1"
				( objectStatus "@baseboard_fab2_lib.baseboard_fab2(sch_1):page55_i158:a" )
			)
			( pin "R8N4.2"
				( objectStatus "@baseboard_fab2_lib.baseboard_fab2(sch_1):page55_i158:b" )
			)
			( pin "R8N3.1"
				( objectStatus "@baseboard_fab2_lib.baseboard_fab2(sch_1):page55_i159:a" )
			)
			( pin "R8N3.2"
				( objectStatus "@baseboard_fab2_lib.baseboard_fab2(sch_1):page55_i159:b" )
			)
			( pin "R8N5.1"
				( objectStatus "@baseboard_fab2_lib.baseboard_fab2(sch_1):page55_i160:a" )
			)
			( pin "R8N5.2"
				( objectStatus "@baseboard_fab2_lib.baseboard_fab2(sch_1):page55_i160:b" )
			)
			( pin "R8N2.1"
				( objectStatus "@baseboard_fab2_lib.baseboard_fab2(sch_1):page55_i161:a" )
			)
			( pin "R8N2.2"
				( objectStatus "@baseboard_fab2_lib.baseboard_fab2(sch_1):page55_i161:b" )
			)
			( pin "R7P25.1"
				( objectStatus "@baseboard_fab2_lib.baseboard_fab2(sch_1):page55_i170:a" )
			)
			( pin "R7P25.2"
				( objectStatus "@baseboard_fab2_lib.baseboard_fab2(sch_1):page55_i170:b" )
			)
			( pin "U2D1.AU24"
				( objectStatus "@baseboard_fab2_lib.baseboard_fab2(sch_1):page55_i172:bclk0_dn" )
			)
			( pin "U2D1.AW24"
				( objectStatus "@baseboard_fab2_lib.baseboard_fab2(sch_1):page55_i172:bclk0_dp" )
			)
			( pin "U2D1.CR26"
				( objectStatus "@baseboard_fab2_lib.baseboard_fab2(sch_1):page55_i172:bclk1_dn" )
			)
			( pin "U2D1.CP27"
				( objectStatus "@baseboard_fab2_lib.baseboard_fab2(sch_1):page55_i172:bclk1_dp" )
			)
			( pin "U2D1.CT25"
				( objectStatus "@baseboard_fab2_lib.baseboard_fab2(sch_1):page55_i172:bclk2_dn" )
			)
			( pin "U2D1.CU26"
				( objectStatus "@baseboard_fab2_lib.baseboard_fab2(sch_1):page55_i172:bclk2_dp" )
			)
			( pin "U2D1.BA20"
				( objectStatus "@baseboard_fab2_lib.baseboard_fab2(sch_1):page55_i172:bist_enable" )
			)
			( pin "U2D1.BD23"
				( objectStatus "@baseboard_fab2_lib.baseboard_fab2(sch_1):page55_i172:bmcinit" )
			)
			( pin "U2D1.AJ10"
				( objectStatus "@baseboard_fab2_lib.baseboard_fab2(sch_1):page55_i172:bpm_n(0)" )
			)
			( pin "U2D1.AH11"
				( objectStatus "@baseboard_fab2_lib.baseboard_fab2(sch_1):page55_i172:bpm_n(1)" )
			)
			( pin "U2D1.AG10"
				( objectStatus "@baseboard_fab2_lib.baseboard_fab2(sch_1):page55_i172:bpm_n(2)" )
			)
			( pin "U2D1.AF11"
				( objectStatus "@baseboard_fab2_lib.baseboard_fab2(sch_1):page55_i172:bpm_n(3)" )
			)
			( pin "U2D1.AA12"
				( objectStatus "@baseboard_fab2_lib.baseboard_fab2(sch_1):page55_i172:bpm_n(4)" )
			)
			( pin "U2D1.Y11"
				( objectStatus "@baseboard_fab2_lib.baseboard_fab2(sch_1):page55_i172:bpm_n(5)" )
			)
			( pin "U2D1.AE12"
				( objectStatus "@baseboard_fab2_lib.baseboard_fab2(sch_1):page55_i172:bpm_n(6)" )
			)
			( pin "U2D1.AC12"
				( objectStatus "@baseboard_fab2_lib.baseboard_fab2(sch_1):page55_i172:bpm_n(7)" )
			)
			( pin "U2D1.AL14"
				( objectStatus "@baseboard_fab2_lib.baseboard_fab2(sch_1):page55_i172:caterr_n" )
			)
			( pin "U2D1.AJ64"
				( objectStatus "@baseboard_fab2_lib.baseboard_fab2(sch_1):page55_i172:ddr0_cavref" )
			)
			( pin "U2D1.AK63"
				( objectStatus "@baseboard_fab2_lib.baseboard_fab2(sch_1):page55_i172:ddr1_cavref" )
			)
			( pin "U2D1.AH63"
				( objectStatus "@baseboard_fab2_lib.baseboard_fab2(sch_1):page55_i172:ddr2_cavref" )
			)
			( pin "U2D1.CP61"
				( objectStatus "@baseboard_fab2_lib.baseboard_fab2(sch_1):page55_i172:ddr3_cavref" )
			)
			( pin "U2D1.CT61"
				( objectStatus "@baseboard_fab2_lib.baseboard_fab2(sch_1):page55_i172:ddr4_cavref" )
			)
			( pin "U2D1.CV61"
				( objectStatus "@baseboard_fab2_lib.baseboard_fab2(sch_1):page55_i172:ddr5_cavref" )
			)
			( pin "U2D1.AN30"
				( objectStatus "@baseboard_fab2_lib.baseboard_fab2(sch_1):page55_i172:ddr012_dram_pwr_ok" )
			)
			( pin "U2D1.Y43"
				( objectStatus "@baseboard_fab2_lib.baseboard_fab2(sch_1):page55_i172:ddr012_rcomp(0)" )
			)
			( pin "U2D1.AB43"
				( objectStatus "@baseboard_fab2_lib.baseboard_fab2(sch_1):page55_i172:ddr012_rcomp(1)" )
			)
			( pin "U2D1.AC42"
				( objectStatus "@baseboard_fab2_lib.baseboard_fab2(sch_1):page55_i172:ddr012_rcomp(2)" )
			)
			( pin "U2D1.U64"
				( objectStatus "@baseboard_fab2_lib.baseboard_fab2(sch_1):page55_i172:ddr012_reset_n" )
			)
			( pin "U2D1.AJ18"
				( objectStatus "@baseboard_fab2_lib.baseboard_fab2(sch_1):page55_i172:ddr012_spdscl" )
			)
			( pin "U2D1.AF17"
				( objectStatus "@baseboard_fab2_lib.baseboard_fab2(sch_1):page55_i172:ddr012_spdsda" )
			)
			( pin "U2D1.CR28"
				( objectStatus "@baseboard_fab2_lib.baseboard_fab2(sch_1):page55_i172:ddr345_dram_pwr_ok" )
			)
			( pin "U2D1.DC48"
				( objectStatus "@baseboard_fab2_lib.baseboard_fab2(sch_1):page55_i172:ddr345_rcomp(0)" )
			)
			( pin "U2D1.DD47"
				( objectStatus "@baseboard_fab2_lib.baseboard_fab2(sch_1):page55_i172:ddr345_rcomp(1)" )
			)
			( pin "U2D1.DD49"
				( objectStatus "@baseboard_fab2_lib.baseboard_fab2(sch_1):page55_i172:ddr345_rcomp(2)" )
			)
			( pin "U2D1.DV63"
				( objectStatus "@baseboard_fab2_lib.baseboard_fab2(sch_1):page55_i172:ddr345_reset_n" )
			)
			( pin "U2D1.AE18"
				( objectStatus "@baseboard_fab2_lib.baseboard_fab2(sch_1):page55_i172:ddr345_spdscl" )
			)
			( pin "U2D1.AD17"
				( objectStatus "@baseboard_fab2_lib.baseboard_fab2(sch_1):page55_i172:ddr345_spdsda" )
			)
			( pin "U2D1.AJ14"
				( objectStatus "@baseboard_fab2_lib.baseboard_fab2(sch_1):page55_i172:ear_n" )
			)
			( pin "U2D1.AJ12"
				( objectStatus "@baseboard_fab2_lib.baseboard_fab2(sch_1):page55_i172:error_n(0)" )
			)
			( pin "U2D1.AK11"
				( objectStatus "@baseboard_fab2_lib.baseboard_fab2(sch_1):page55_i172:error_n(1)" )
			)
			( pin "U2D1.AL12"
				( objectStatus "@baseboard_fab2_lib.baseboard_fab2(sch_1):page55_i172:error_n(2)" )
			)
			( pin "U2D1.AV17"
				( objectStatus "@baseboard_fab2_lib.baseboard_fab2(sch_1):page55_i172:frmagent" )
			)
			( pin "U2D1.AE20"
				( objectStatus "@baseboard_fab2_lib.baseboard_fab2(sch_1):page55_i172:legacy_skt" )
			)
			( pin "U2D1.CU32"
				( objectStatus "@baseboard_fab2_lib.baseboard_fab2(sch_1):page55_i172:mcp01_rbias(0)" )
			)
			( pin "U2D1.CT31"
				( objectStatus "@baseboard_fab2_lib.baseboard_fab2(sch_1):page55_i172:mcp01_rbias(1)" )
			)
			( pin "U2D1.AH13"
				( objectStatus "@baseboard_fab2_lib.baseboard_fab2(sch_1):page55_i172:mem_hot_c012_n" )
			)
			( pin "U2D1.AF13"
				( objectStatus "@baseboard_fab2_lib.baseboard_fab2(sch_1):page55_i172:mem_hot_c345_n" )
			)
			( pin "U2D1.AN20"
				( objectStatus "@baseboard_fab2_lib.baseboard_fab2(sch_1):page55_i172:msmi_n" )
			)
			( pin "U2D1.AP11"
				( objectStatus "@baseboard_fab2_lib.baseboard_fab2(sch_1):page55_i172:nmi" )
			)
			( pin "U2D1.CP29"
				( objectStatus "@baseboard_fab2_lib.baseboard_fab2(sch_1):page55_i172:pe3_rbias(0)" )
			)
			( pin "U2D1.CR30"
				( objectStatus "@baseboard_fab2_lib.baseboard_fab2(sch_1):page55_i172:pe3_rbias(1)" )
			)
			( pin "U2D1.CN30"
				( objectStatus "@baseboard_fab2_lib.baseboard_fab2(sch_1):page55_i172:pe012_rbias(0)" )
			)
			( pin "U2D1.CL30"
				( objectStatus "@baseboard_fab2_lib.baseboard_fab2(sch_1):page55_i172:pe012_rbias(1)" )
			)
			( pin "U2D1.AM19"
				( objectStatus "@baseboard_fab2_lib.baseboard_fab2(sch_1):page55_i172:pe_hp_scl" )
			)
			( pin "U2D1.AL18"
				( objectStatus "@baseboard_fab2_lib.baseboard_fab2(sch_1):page55_i172:pe_hp_sda" )
			)
			( pin "U2D1.AU12"
				( objectStatus "@baseboard_fab2_lib.baseboard_fab2(sch_1):page55_i172:peci" )
			)
			( pin "U2D1.CU58"
				( objectStatus "@baseboard_fab2_lib.baseboard_fab2(sch_1):page55_i172:pirom_addr(0)" )
			)
			( pin "U2D1.CV57"
				( objectStatus "@baseboard_fab2_lib.baseboard_fab2(sch_1):page55_i172:pirom_addr(1)" )
			)
			( pin "U2D1.CW56"
				( objectStatus "@baseboard_fab2_lib.baseboard_fab2(sch_1):page55_i172:pirom_addr(2)" )
			)
			( pin "U2D1.DC72"
				( objectStatus "@baseboard_fab2_lib.baseboard_fab2(sch_1):page55_i172:pkgid(0)" )
			)
			( pin "U2D1.CW72"
				( objectStatus "@baseboard_fab2_lib.baseboard_fab2(sch_1):page55_i172:pkgid(1)" )
			)
			( pin "U2D1.DA72"
				( objectStatus "@baseboard_fab2_lib.baseboard_fab2(sch_1):page55_i172:pkgid(2)" )
			)
			( pin "U2D1.AF15"
				( objectStatus "@baseboard_fab2_lib.baseboard_fab2(sch_1):page55_i172:pm_fast_wake_n" )
			)
			( pin "U2D1.AR14"
				( objectStatus "@baseboard_fab2_lib.baseboard_fab2(sch_1):page55_i172:pmsync" )
			)
			( pin "U2D1.AT19"
				( objectStatus "@baseboard_fab2_lib.baseboard_fab2(sch_1):page55_i172:pmsync_clk" )
			)
			( pin "U2D1.AG16"
				( objectStatus "@baseboard_fab2_lib.baseboard_fab2(sch_1):page55_i172:prdy_n" )
			)
			( pin "U2D1.AR12"
				( objectStatus "@baseboard_fab2_lib.baseboard_fab2(sch_1):page55_i172:preq_n" )
			)
			( pin "U2D1.CY71"
				( objectStatus "@baseboard_fab2_lib.baseboard_fab2(sch_1):page55_i172:proc_id(0)" )
			)
			( pin "U2D1.DB71"
				( objectStatus "@baseboard_fab2_lib.baseboard_fab2(sch_1):page55_i172:proc_id(1)" )
			)
			( pin "U2D1.AB17"
				( objectStatus "@baseboard_fab2_lib.baseboard_fab2(sch_1):page55_i172:procdis_n" )
			)
			( pin "U2D1.AC16"
				( objectStatus "@baseboard_fab2_lib.baseboard_fab2(sch_1):page55_i172:prochot_n" )
			)
			( pin "U2D1.BC24"
				( objectStatus "@baseboard_fab2_lib.baseboard_fab2(sch_1):page55_i172:pwrgood" )
			)
			( pin "U2D1.AP21"
				( objectStatus "@baseboard_fab2_lib.baseboard_fab2(sch_1):page55_i172:reset_n" )
			)
			( pin "U2D1.AR18"
				( objectStatus "@baseboard_fab2_lib.baseboard_fab2(sch_1):page55_i172:safe_mode_boot" )
			)
			( pin "U2D1.AB13"
				( objectStatus "@baseboard_fab2_lib.baseboard_fab2(sch_1):page55_i172:sktocc_n" )
			)
			( pin "U2D1.CV59"
				( objectStatus "@baseboard_fab2_lib.baseboard_fab2(sch_1):page55_i172:sm_wp" )
			)
			( pin "U2D1.CT59"
				( objectStatus "@baseboard_fab2_lib.baseboard_fab2(sch_1):page55_i172:smbclk" )
			)
			( pin "U2D1.CW58"
				( objectStatus "@baseboard_fab2_lib.baseboard_fab2(sch_1):page55_i172:smbdat" )
			)
			( pin "U2D1.AU22"
				( objectStatus "@baseboard_fab2_lib.baseboard_fab2(sch_1):page55_i172:socket_id(0)" )
			)
			( pin "U2D1.AU16"
				( objectStatus "@baseboard_fab2_lib.baseboard_fab2(sch_1):page55_i172:socket_id(1)" )
			)
			( pin "U2D1.AU20"
				( objectStatus "@baseboard_fab2_lib.baseboard_fab2(sch_1):page55_i172:socket_id(2)" )
			)
			( pin "U2D1.DE44"
				( objectStatus "@baseboard_fab2_lib.baseboard_fab2(sch_1):page55_i172:svidalert_n(0)" )
			)
			( pin "U2D1.DL44"
				( objectStatus "@baseboard_fab2_lib.baseboard_fab2(sch_1):page55_i172:svidalert_n(1)" )
			)
			( pin "U2D1.DC44"
				( objectStatus "@baseboard_fab2_lib.baseboard_fab2(sch_1):page55_i172:svidclk(0)" )
			)
			( pin "U2D1.DG44"
				( objectStatus "@baseboard_fab2_lib.baseboard_fab2(sch_1):page55_i172:svidclk(1)" )
			)
			( pin "U2D1.DB45"
				( objectStatus "@baseboard_fab2_lib.baseboard_fab2(sch_1):page55_i172:sviddata(0)" )
			)
			( pin "U2D1.DJ44"
				( objectStatus "@baseboard_fab2_lib.baseboard_fab2(sch_1):page55_i172:sviddata(1)" )
			)
			( pin "U2D1.AA14"
				( objectStatus "@baseboard_fab2_lib.baseboard_fab2(sch_1):page55_i172:tck" )
			)
			( pin "U2D1.AC14"
				( objectStatus "@baseboard_fab2_lib.baseboard_fab2(sch_1):page55_i172:tdi" )
			)
			( pin "U2D1.AE14"
				( objectStatus "@baseboard_fab2_lib.baseboard_fab2(sch_1):page55_i172:tdo" )
			)
			( pin "U2D1.AY19"
				( objectStatus "@baseboard_fab2_lib.baseboard_fab2(sch_1):page55_i172:test_12" )
			)
			( pin "U2D1.DB51"
				( objectStatus "@baseboard_fab2_lib.baseboard_fab2(sch_1):page55_i172:test_13" )
			)
			( pin "U2D1.DC50"
				( objectStatus "@baseboard_fab2_lib.baseboard_fab2(sch_1):page55_i172:test_14" )
			)
			( pin "U2D1.AW14"
				( objectStatus "@baseboard_fab2_lib.baseboard_fab2(sch_1):page55_i172:test_15" )
			)
			( pin "U2D1.AB15"
				( objectStatus "@baseboard_fab2_lib.baseboard_fab2(sch_1):page55_i172:thermtrip_n" )
			)
			( pin "U2D1.W14"
				( objectStatus "@baseboard_fab2_lib.baseboard_fab2(sch_1):page55_i172:tms" )
			)
			( pin "U2D1.Y13"
				( objectStatus "@baseboard_fab2_lib.baseboard_fab2(sch_1):page55_i172:trst_n" )
			)
			( pin "U2D1.AM11"
				( objectStatus "@baseboard_fab2_lib.baseboard_fab2(sch_1):page55_i172:tsc_sync" )
			)
			( pin "U2D1.AW18"
				( objectStatus "@baseboard_fab2_lib.baseboard_fab2(sch_1):page55_i172:txt_agent" )
			)
			( pin "U2D1.AV15"
				( objectStatus "@baseboard_fab2_lib.baseboard_fab2(sch_1):page55_i172:txt_plten" )
			)
			( pin "U2D1.AT29"
				( objectStatus "@baseboard_fab2_lib.baseboard_fab2(sch_1):page55_i172:upi01_rbias(0)" )
			)
			( pin "U2D1.AP29"
				( objectStatus "@baseboard_fab2_lib.baseboard_fab2(sch_1):page55_i172:upi01_rbias(1)" )
			)
			( pin "U2D1.CL28"
				( objectStatus "@baseboard_fab2_lib.baseboard_fab2(sch_1):page55_i172:upi2_rbias(0)" )
			)
			( pin "U2D1.CK29"
				( objectStatus "@baseboard_fab2_lib.baseboard_fab2(sch_1):page55_i172:upi2_rbias(1)" )
			)
			( pin "R6P39.1"
				( objectStatus "@baseboard_fab2_lib.baseboard_fab2(sch_1):page55_i181:a" )
			)
			( pin "R6P39.2"
				( objectStatus "@baseboard_fab2_lib.baseboard_fab2(sch_1):page55_i181:b" )
			)
			( pin "U2D1.AV21"
				( objectStatus "@baseboard_fab2_lib.baseboard_fab2(sch_1):page56_i169:debug_en_n" )
			)
			( pin "U2D1.AW12"
				( objectStatus "@baseboard_fab2_lib.baseboard_fab2(sch_1):page56_i169:dmimode_override" )
			)
			( pin "U2D1.AU14"
				( objectStatus "@baseboard_fab2_lib.baseboard_fab2(sch_1):page56_i169:fivr_fault" )
			)
			( pin "U2D1.AP17"
				( objectStatus "@baseboard_fab2_lib.baseboard_fab2(sch_1):page56_i169:pwr_debug_n" )
			)
			( pin "U2D1.AP61"
				( objectStatus "@baseboard_fab2_lib.baseboard_fab2(sch_1):page56_i169:rsvd(194)" )
			)
			( pin "U2D1.AP27"
				( objectStatus "@baseboard_fab2_lib.baseboard_fab2(sch_1):page56_i169:rsvd(195)" )
			)
			( pin "U2D1.AP25"
				( objectStatus "@baseboard_fab2_lib.baseboard_fab2(sch_1):page56_i169:rsvd(196)" )
			)
			( pin "U2D1.AP23"
				( objectStatus "@baseboard_fab2_lib.baseboard_fab2(sch_1):page56_i169:rsvd(197)" )
			)
			( pin "U2D1.AN62"
				( objectStatus "@baseboard_fab2_lib.baseboard_fab2(sch_1):page56_i169:rsvd(198)" )
			)
			( pin "U2D1.AN60"
				( objectStatus "@baseboard_fab2_lib.baseboard_fab2(sch_1):page56_i169:rsvd(199)" )
			)
			( pin "U2D1.AN26"
				( objectStatus "@baseboard_fab2_lib.baseboard_fab2(sch_1):page56_i169:rsvd(200)" )
			)
			( pin "U2D1.AN24"
				( objectStatus "@baseboard_fab2_lib.baseboard_fab2(sch_1):page56_i169:rsvd(201)" )
			)
			( pin "U2D1.AN22"
				( objectStatus "@baseboard_fab2_lib.baseboard_fab2(sch_1):page56_i169:rsvd(202)" )
			)
			( pin "U2D1.AN18"
				( objectStatus "@baseboard_fab2_lib.baseboard_fab2(sch_1):page56_i169:rsvd(203)" )
			)
			( pin "U2D1.AM61"
				( objectStatus "@baseboard_fab2_lib.baseboard_fab2(sch_1):page56_i169:rsvd(204)" )
			)
			( pin "U2D1.AM59"
				( objectStatus "@baseboard_fab2_lib.baseboard_fab2(sch_1):page56_i169:rsvd(205)" )
			)
			( pin "U2D1.AM27"
				( objectStatus "@baseboard_fab2_lib.baseboard_fab2(sch_1):page56_i169:rsvd(206)" )
			)
			( pin "U2D1.AM25"
				( objectStatus "@baseboard_fab2_lib.baseboard_fab2(sch_1):page56_i169:rsvd(207)" )
			)
			( pin "U2D1.AM23"
				( objectStatus "@baseboard_fab2_lib.baseboard_fab2(sch_1):page56_i169:rsvd(208)" )
			)
			( pin "U2D1.AM21"
				( objectStatus "@baseboard_fab2_lib.baseboard_fab2(sch_1):page56_i169:rsvd(209)" )
			)
			( pin "U2D1.AL62"
				( objectStatus "@baseboard_fab2_lib.baseboard_fab2(sch_1):page56_i169:rsvd(210)" )
			)
			( pin "U2D1.AL60"
				( objectStatus "@baseboard_fab2_lib.baseboard_fab2(sch_1):page56_i169:rsvd(211)" )
			)
			( pin "U2D1.AL58"
				( objectStatus "@baseboard_fab2_lib.baseboard_fab2(sch_1):page56_i169:rsvd(212)" )
			)
			( pin "U2D1.AL26"
				( objectStatus "@baseboard_fab2_lib.baseboard_fab2(sch_1):page56_i169:rsvd(213)" )
			)
			( pin "U2D1.AL22"
				( objectStatus "@baseboard_fab2_lib.baseboard_fab2(sch_1):page56_i169:rsvd(214)" )
			)
			( pin "U2D1.AL20"
				( objectStatus "@baseboard_fab2_lib.baseboard_fab2(sch_1):page56_i169:rsvd(215)" )
			)
			( pin "U2D1.AK69"
				( objectStatus "@baseboard_fab2_lib.baseboard_fab2(sch_1):page56_i169:rsvd(216)" )
			)
			( pin "U2D1.AK61"
				( objectStatus "@baseboard_fab2_lib.baseboard_fab2(sch_1):page56_i169:rsvd(217)" )
			)
			( pin "U2D1.AK59"
				( objectStatus "@baseboard_fab2_lib.baseboard_fab2(sch_1):page56_i169:rsvd(218)" )
			)
			( pin "U2D1.AK57"
				( objectStatus "@baseboard_fab2_lib.baseboard_fab2(sch_1):page56_i169:rsvd(219)" )
			)
			( pin "U2D1.AK27"
				( objectStatus "@baseboard_fab2_lib.baseboard_fab2(sch_1):page56_i169:rsvd(220)" )
			)
			( pin "U2D1.AK21"
				( objectStatus "@baseboard_fab2_lib.baseboard_fab2(sch_1):page56_i169:rsvd(221)" )
			)
			( pin "U2D1.AJ70"
				( objectStatus "@baseboard_fab2_lib.baseboard_fab2(sch_1):page56_i169:rsvd(222)" )
			)
			( pin "U2D1.AJ62"
				( objectStatus "@baseboard_fab2_lib.baseboard_fab2(sch_1):page56_i169:rsvd(223)" )
			)
			( pin "U2D1.AJ60"
				( objectStatus "@baseboard_fab2_lib.baseboard_fab2(sch_1):page56_i169:rsvd(224)" )
			)
			( pin "U2D1.AJ58"
				( objectStatus "@baseboard_fab2_lib.baseboard_fab2(sch_1):page56_i169:rsvd(225)" )
			)
			( pin "U2D1.AJ56"
				( objectStatus "@baseboard_fab2_lib.baseboard_fab2(sch_1):page56_i169:rsvd(226)" )
			)
			( pin "U2D1.AJ20"
				( objectStatus "@baseboard_fab2_lib.baseboard_fab2(sch_1):page56_i169:rsvd(227)" )
			)
			( pin "U2D1.AH73"
				( objectStatus "@baseboard_fab2_lib.baseboard_fab2(sch_1):page56_i169:rsvd(228)" )
			)
			( pin "U2D1.AH71"
				( objectStatus "@baseboard_fab2_lib.baseboard_fab2(sch_1):page56_i169:rsvd(229)" )
			)
			( pin "U2D1.AH57"
				( objectStatus "@baseboard_fab2_lib.baseboard_fab2(sch_1):page56_i169:rsvd(230)" )
			)
			( pin "U2D1.AH55"
				( objectStatus "@baseboard_fab2_lib.baseboard_fab2(sch_1):page56_i169:rsvd(231)" )
			)
			( pin "U2D1.AH19"
				( objectStatus "@baseboard_fab2_lib.baseboard_fab2(sch_1):page56_i169:rsvd(232)" )
			)
			( pin "U2D1.AH15"
				( objectStatus "@baseboard_fab2_lib.baseboard_fab2(sch_1):page56_i169:rsvd(233)" )
			)
			( pin "U2D1.AG72"
				( objectStatus "@baseboard_fab2_lib.baseboard_fab2(sch_1):page56_i169:rsvd(234)" )
			)
			( pin "U2D1.AG56"
				( objectStatus "@baseboard_fab2_lib.baseboard_fab2(sch_1):page56_i169:rsvd(235)" )
			)
			( pin "U2D1.AG54"
				( objectStatus "@baseboard_fab2_lib.baseboard_fab2(sch_1):page56_i169:rsvd(236)" )
			)
			( pin "U2D1.AG52"
				( objectStatus "@baseboard_fab2_lib.baseboard_fab2(sch_1):page56_i169:rsvd(237)" )
			)
			( pin "U2D1.AG50"
				( objectStatus "@baseboard_fab2_lib.baseboard_fab2(sch_1):page56_i169:rsvd(238)" )
			)
			( pin "U2D1.AG48"
				( objectStatus "@baseboard_fab2_lib.baseboard_fab2(sch_1):page56_i169:rsvd(239)" )
			)
			( pin "U2D1.AG20"
				( objectStatus "@baseboard_fab2_lib.baseboard_fab2(sch_1):page56_i169:rsvd(240)" )
			)
			( pin "U2D1.AF71"
				( objectStatus "@baseboard_fab2_lib.baseboard_fab2(sch_1):page56_i169:rsvd(241)" )
			)
			( pin "U2D1.AF53"
				( objectStatus "@baseboard_fab2_lib.baseboard_fab2(sch_1):page56_i169:rsvd(242)" )
			)
			( pin "U2D1.AF51"
				( objectStatus "@baseboard_fab2_lib.baseboard_fab2(sch_1):page56_i169:rsvd(243)" )
			)
			( pin "U2D1.AF49"
				( objectStatus "@baseboard_fab2_lib.baseboard_fab2(sch_1):page56_i169:rsvd(244)" )
			)
			( pin "U2D1.AF47"
				( objectStatus "@baseboard_fab2_lib.baseboard_fab2(sch_1):page56_i169:rsvd(245)" )
			)
			( pin "U2D1.AF19"
				( objectStatus "@baseboard_fab2_lib.baseboard_fab2(sch_1):page56_i169:rsvd(246)" )
			)
			( pin "U2D1.AE72"
				( objectStatus "@baseboard_fab2_lib.baseboard_fab2(sch_1):page56_i169:rsvd(247)" )
			)
			( pin "U2D1.AE52"
				( objectStatus "@baseboard_fab2_lib.baseboard_fab2(sch_1):page56_i169:rsvd(248)" )
			)
			( pin "U2D1.AE50"
				( objectStatus "@baseboard_fab2_lib.baseboard_fab2(sch_1):page56_i169:rsvd(249)" )
			)
			( pin "U2D1.AE48"
				( objectStatus "@baseboard_fab2_lib.baseboard_fab2(sch_1):page56_i169:rsvd(250)" )
			)
			( pin "U2D1.AE46"
				( objectStatus "@baseboard_fab2_lib.baseboard_fab2(sch_1):page56_i169:rsvd(251)" )
			)
			( pin "U2D1.AD51"
				( objectStatus "@baseboard_fab2_lib.baseboard_fab2(sch_1):page56_i169:rsvd(252)" )
			)
			( pin "U2D1.AD49"
				( objectStatus "@baseboard_fab2_lib.baseboard_fab2(sch_1):page56_i169:rsvd(253)" )
			)
			( pin "U2D1.AD47"
				( objectStatus "@baseboard_fab2_lib.baseboard_fab2(sch_1):page56_i169:rsvd(254)" )
			)
			( pin "U2D1.Y65"
				( objectStatus "@baseboard_fab2_lib.baseboard_fab2(sch_1):page56_i169:rsvd(256)" )
			)
			( pin "U2D1.Y23"
				( objectStatus "@baseboard_fab2_lib.baseboard_fab2(sch_1):page56_i169:rsvd(257)" )
			)
			( pin "U2D1.W66"
				( objectStatus "@baseboard_fab2_lib.baseboard_fab2(sch_1):page56_i169:rsvd(258)" )
			)
			( pin "U2D1.V67"
				( objectStatus "@baseboard_fab2_lib.baseboard_fab2(sch_1):page56_i169:rsvd(259)" )
			)
			( pin "U2D1.V65"
				( objectStatus "@baseboard_fab2_lib.baseboard_fab2(sch_1):page56_i169:rsvd(260)" )
			)
			( pin "U2D1.U66"
				( objectStatus "@baseboard_fab2_lib.baseboard_fab2(sch_1):page56_i169:rsvd(261)" )
			)
			( pin "U2D1.T67"
				( objectStatus "@baseboard_fab2_lib.baseboard_fab2(sch_1):page56_i169:rsvd(262)" )
			)
			( pin "U2D1.R66"
				( objectStatus "@baseboard_fab2_lib.baseboard_fab2(sch_1):page56_i169:rsvd(263)" )
			)
			( pin "U2D1.R62"
				( objectStatus "@baseboard_fab2_lib.baseboard_fab2(sch_1):page56_i169:rsvd(264)" )
			)
			( pin "U2D1.P65"
				( objectStatus "@baseboard_fab2_lib.baseboard_fab2(sch_1):page56_i169:rsvd(265)" )
			)
			( pin "U2D1.M63"
				( objectStatus "@baseboard_fab2_lib.baseboard_fab2(sch_1):page56_i169:rsvd(266)" )
			)
			( pin "U2D1.K61"
				( objectStatus "@baseboard_fab2_lib.baseboard_fab2(sch_1):page56_i169:rsvd(267)" )
			)
			( pin "U2D1.J62"
				( objectStatus "@baseboard_fab2_lib.baseboard_fab2(sch_1):page56_i169:rsvd(268)" )
			)
			( pin "U2D1.J46"
				( objectStatus "@baseboard_fab2_lib.baseboard_fab2(sch_1):page56_i169:rsvd(269)" )
			)
			( pin "U2D1.H85"
				( objectStatus "@baseboard_fab2_lib.baseboard_fab2(sch_1):page56_i169:rsvd(270)" )
			)
			( pin "U2D1.H83"
				( objectStatus "@baseboard_fab2_lib.baseboard_fab2(sch_1):page56_i169:rsvd(271)" )
			)
			( pin "U2D1.H1"
				( objectStatus "@baseboard_fab2_lib.baseboard_fab2(sch_1):page56_i169:rsvd(272)" )
			)
			( pin "U2D1.G84"
				( objectStatus "@baseboard_fab2_lib.baseboard_fab2(sch_1):page56_i169:rsvd(273)" )
			)
			( pin "U2D1.G64"
				( objectStatus "@baseboard_fab2_lib.baseboard_fab2(sch_1):page56_i169:rsvd(274)" )
			)
			( pin "U2D1.G2"
				( objectStatus "@baseboard_fab2_lib.baseboard_fab2(sch_1):page56_i169:rsvd(275)" )
			)
			( pin "U2D1.F83"
				( objectStatus "@baseboard_fab2_lib.baseboard_fab2(sch_1):page56_i169:rsvd(276)" )
			)
			( pin "U2D1.F65"
				( objectStatus "@baseboard_fab2_lib.baseboard_fab2(sch_1):page56_i169:rsvd(277)" )
			)
			( pin "U2D1.F23"
				( objectStatus "@baseboard_fab2_lib.baseboard_fab2(sch_1):page56_i169:rsvd(278)" )
			)
			( pin "U2D1.F3"
				( objectStatus "@baseboard_fab2_lib.baseboard_fab2(sch_1):page56_i169:rsvd(279)" )
			)
			( pin "U2D1.E84"
				( objectStatus "@baseboard_fab2_lib.baseboard_fab2(sch_1):page56_i169:rsvd(280)" )
			)
			( pin "U2D1.E24"
				( objectStatus "@baseboard_fab2_lib.baseboard_fab2(sch_1):page56_i169:rsvd(281)" )
			)
			( pin "U2D1.E4"
				( objectStatus "@baseboard_fab2_lib.baseboard_fab2(sch_1):page56_i169:rsvd(282)" )
			)
			( pin "U2D1.E2"
				( objectStatus "@baseboard_fab2_lib.baseboard_fab2(sch_1):page56_i169:rsvd(283)" )
			)
			( pin "U2D1.D83"
				( objectStatus "@baseboard_fab2_lib.baseboard_fab2(sch_1):page56_i169:rsvd(284)" )
			)
			( pin "U2D1.D65"
				( objectStatus "@baseboard_fab2_lib.baseboard_fab2(sch_1):page56_i169:rsvd(285)" )
			)
			( pin "U2D1.D17"
				( objectStatus "@baseboard_fab2_lib.baseboard_fab2(sch_1):page56_i169:rsvd(286)" )
			)
			( pin "U2D1.D5"
				( objectStatus "@baseboard_fab2_lib.baseboard_fab2(sch_1):page56_i169:rsvd(287)" )
			)
			( pin "U2D1.C82"
				( objectStatus "@baseboard_fab2_lib.baseboard_fab2(sch_1):page56_i169:rsvd(288)" )
			)
			( pin "U2D1.C24"
				( objectStatus "@baseboard_fab2_lib.baseboard_fab2(sch_1):page56_i169:rsvd(289)" )
			)
			( pin "U2D1.C18"
				( objectStatus "@baseboard_fab2_lib.baseboard_fab2(sch_1):page56_i169:rsvd(290)" )
			)
			( pin "U2D1.C6"
				( objectStatus "@baseboard_fab2_lib.baseboard_fab2(sch_1):page56_i169:rsvd(291)" )
			)
			( pin "U2D1.B81"
				( objectStatus "@baseboard_fab2_lib.baseboard_fab2(sch_1):page56_i169:rsvd(292)" )
			)
			( pin "U2D1.B77"
				( objectStatus "@baseboard_fab2_lib.baseboard_fab2(sch_1):page56_i169:rsvd(293)" )
			)
			( pin "U2D1.B17"
				( objectStatus "@baseboard_fab2_lib.baseboard_fab2(sch_1):page56_i169:rsvd(294)" )
			)
			( pin "U2D1.B15"
				( objectStatus "@baseboard_fab2_lib.baseboard_fab2(sch_1):page56_i169:rsvd(295)" )
			)
			( pin "U2D1.B13"
				( objectStatus "@baseboard_fab2_lib.baseboard_fab2(sch_1):page56_i169:rsvd(296)" )
			)
			( pin "U2D1.B7"
				( objectStatus "@baseboard_fab2_lib.baseboard_fab2(sch_1):page56_i169:rsvd(298)" )
			)
			( pin "U2D1.B3"
				( objectStatus "@baseboard_fab2_lib.baseboard_fab2(sch_1):page56_i169:rsvd(299)" )
			)
			( pin "U2D1.A24"
				( objectStatus "@baseboard_fab2_lib.baseboard_fab2(sch_1):page56_i169:rsvd(300)" )
			)
			( pin "U2D1.A16"
				( objectStatus "@baseboard_fab2_lib.baseboard_fab2(sch_1):page56_i169:rsvd(301)" )
			)
			( pin "U2D1.A14"
				( objectStatus "@baseboard_fab2_lib.baseboard_fab2(sch_1):page56_i169:rsvd(302)" )
			)
			( pin "U2D1.A6"
				( objectStatus "@baseboard_fab2_lib.baseboard_fab2(sch_1):page56_i169:rsvd(303)" )
			)
			( pin "U2D1.A4"
				( objectStatus "@baseboard_fab2_lib.baseboard_fab2(sch_1):page56_i169:rsvd(304)" )
			)
			( pin "U2D1.AF45"
				( objectStatus "@baseboard_fab2_lib.baseboard_fab2(sch_1):page56_i169:test_1" )
			)
			( pin "U2D1.AG46"
				( objectStatus "@baseboard_fab2_lib.baseboard_fab2(sch_1):page56_i169:test_2" )
			)
			( pin "U2D1.AM13"
				( objectStatus "@baseboard_fab2_lib.baseboard_fab2(sch_1):page56_i169:test_3" )
			)
			( pin "U2D1.AN12"
				( objectStatus "@baseboard_fab2_lib.baseboard_fab2(sch_1):page56_i169:test_4" )
			)
			( pin "U2D1.AN14"
				( objectStatus "@baseboard_fab2_lib.baseboard_fab2(sch_1):page56_i169:test_5" )
			)
			( pin "U2D1.AY13"
				( objectStatus "@baseboard_fab2_lib.baseboard_fab2(sch_1):page56_i169:test_11" )
			)
			( pin "R8P3.1"
				( objectStatus "@baseboard_fab2_lib.baseboard_fab2(sch_1):page56_i173:a" )
			)
			( pin "R8P3.2"
				( objectStatus "@baseboard_fab2_lib.baseboard_fab2(sch_1):page56_i173:b" )
			)
			( pin "R8R1.1"
				( objectStatus "@baseboard_fab2_lib.baseboard_fab2(sch_1):page56_i174:a" )
			)
			( pin "R8R1.2"
				( objectStatus "@baseboard_fab2_lib.baseboard_fab2(sch_1):page56_i174:b" )
			)
			( pin "U2D1.J60"
				( objectStatus "@baseboard_fab2_lib.baseboard_fab2(sch_1):page57_i172:ddr0_act_n" )
			)
			( pin "U2D1.B61"
				( objectStatus "@baseboard_fab2_lib.baseboard_fab2(sch_1):page57_i172:ddr0_alert_n" )
			)
			( pin "U2D1.C52"
				( objectStatus "@baseboard_fab2_lib.baseboard_fab2(sch_1):page57_i172:ddr0_ba(0)" )
			)
			( pin "U2D1.G54"
				( objectStatus "@baseboard_fab2_lib.baseboard_fab2(sch_1):page57_i172:ddr0_ba(1)" )
			)
			( pin "U2D1.D61"
				( objectStatus "@baseboard_fab2_lib.baseboard_fab2(sch_1):page57_i172:ddr0_bg(0)" )
			)
			( pin "U2D1.F63"
				( objectStatus "@baseboard_fab2_lib.baseboard_fab2(sch_1):page57_i172:ddr0_bg(1)" )
			)
			( pin "U2D1.G46"
				( objectStatus "@baseboard_fab2_lib.baseboard_fab2(sch_1):page57_i172:ddr0_cid(2)" )
			)
			( pin "U2D1.C62"
				( objectStatus "@baseboard_fab2_lib.baseboard_fab2(sch_1):page57_i172:ddr0_cke(0)" )
			)
			( pin "U2D1.C64"
				( objectStatus "@baseboard_fab2_lib.baseboard_fab2(sch_1):page57_i172:ddr0_cke(1)" )
			)
			( pin "U2D1.B63"
				( objectStatus "@baseboard_fab2_lib.baseboard_fab2(sch_1):page57_i172:ddr0_cke(2)" )
			)
			( pin "U2D1.D63"
				( objectStatus "@baseboard_fab2_lib.baseboard_fab2(sch_1):page57_i172:ddr0_cke(3)" )
			)
			( pin "U2D1.F55"
				( objectStatus "@baseboard_fab2_lib.baseboard_fab2(sch_1):page57_i172:ddr0_clk_dn(0)" )
			)
			( pin "U2D1.C54"
				( objectStatus "@baseboard_fab2_lib.baseboard_fab2(sch_1):page57_i172:ddr0_clk_dn(1)" )
			)
			( pin "U2D1.J56"
				( objectStatus "@baseboard_fab2_lib.baseboard_fab2(sch_1):page57_i172:ddr0_clk_dn(2)" )
			)
			( pin "U2D1.C56"
				( objectStatus "@baseboard_fab2_lib.baseboard_fab2(sch_1):page57_i172:ddr0_clk_dn(3)" )
			)
			( pin "U2D1.D55"
				( objectStatus "@baseboard_fab2_lib.baseboard_fab2(sch_1):page57_i172:ddr0_clk_dp(0)" )
			)
			( pin "U2D1.B55"
				( objectStatus "@baseboard_fab2_lib.baseboard_fab2(sch_1):page57_i172:ddr0_clk_dp(1)" )
			)
			( pin "U2D1.G56"
				( objectStatus "@baseboard_fab2_lib.baseboard_fab2(sch_1):page57_i172:ddr0_clk_dp(2)" )
			)
			( pin "U2D1.B57"
				( objectStatus "@baseboard_fab2_lib.baseboard_fab2(sch_1):page57_i172:ddr0_clk_dp(3)" )
			)
			( pin "U2D1.G52"
				( objectStatus "@baseboard_fab2_lib.baseboard_fab2(sch_1):page57_i172:ddr0_cs_n(0)" )
			)
			( pin "U2D1.F49"
				( objectStatus "@baseboard_fab2_lib.baseboard_fab2(sch_1):page57_i172:ddr0_cs_n(1)" )
			)
			( pin "U2D1.D47"
				( objectStatus "@baseboard_fab2_lib.baseboard_fab2(sch_1):page57_i172:ddr0_cs_n(2)" )
			)
			( pin "U2D1.F47"
				( objectStatus "@baseboard_fab2_lib.baseboard_fab2(sch_1):page57_i172:ddr0_cs_n(3)" )
			)
			( pin "U2D1.B51"
				( objectStatus "@baseboard_fab2_lib.baseboard_fab2(sch_1):page57_i172:ddr0_cs_n(4)" )
			)
			( pin "U2D1.D49"
				( objectStatus "@baseboard_fab2_lib.baseboard_fab2(sch_1):page57_i172:ddr0_cs_n(5)" )
			)
			( pin "U2D1.F45"
				( objectStatus "@baseboard_fab2_lib.baseboard_fab2(sch_1):page57_i172:ddr0_cs_n(6)" )
			)
			( pin "U2D1.K45"
				( objectStatus "@baseboard_fab2_lib.baseboard_fab2(sch_1):page57_i172:ddr0_cs_n(7)" )
			)
			( pin "U2D1.AN86"
				( objectStatus "@baseboard_fab2_lib.baseboard_fab2(sch_1):page57_i172:ddr0_dq(0)" )
			)
			( pin "U2D1.AN84"
				( objectStatus "@baseboard_fab2_lib.baseboard_fab2(sch_1):page57_i172:ddr0_dq(1)" )
			)
			( pin "U2D1.AE86"
				( objectStatus "@baseboard_fab2_lib.baseboard_fab2(sch_1):page57_i172:ddr0_dq(2)" )
			)
			( pin "U2D1.AE84"
				( objectStatus "@baseboard_fab2_lib.baseboard_fab2(sch_1):page57_i172:ddr0_dq(3)" )
			)
			( pin "U2D1.AR86"
				( objectStatus "@baseboard_fab2_lib.baseboard_fab2(sch_1):page57_i172:ddr0_dq(4)" )
			)
			( pin "U2D1.AR84"
				( objectStatus "@baseboard_fab2_lib.baseboard_fab2(sch_1):page57_i172:ddr0_dq(5)" )
			)
			( pin "U2D1.AG86"
				( objectStatus "@baseboard_fab2_lib.baseboard_fab2(sch_1):page57_i172:ddr0_dq(6)" )
			)
			( pin "U2D1.AG84"
				( objectStatus "@baseboard_fab2_lib.baseboard_fab2(sch_1):page57_i172:ddr0_dq(7)" )
			)
			( pin "U2D1.W86"
				( objectStatus "@baseboard_fab2_lib.baseboard_fab2(sch_1):page57_i172:ddr0_dq(8)" )
			)
			( pin "U2D1.W84"
				( objectStatus "@baseboard_fab2_lib.baseboard_fab2(sch_1):page57_i172:ddr0_dq(9)" )
			)
			( pin "U2D1.L86"
				( objectStatus "@baseboard_fab2_lib.baseboard_fab2(sch_1):page57_i172:ddr0_dq(10)" )
			)
			( pin "U2D1.L84"
				( objectStatus "@baseboard_fab2_lib.baseboard_fab2(sch_1):page57_i172:ddr0_dq(11)" )
			)
			( pin "U2D1.AA86"
				( objectStatus "@baseboard_fab2_lib.baseboard_fab2(sch_1):page57_i172:ddr0_dq(12)" )
			)
			( pin "U2D1.AA84"
				( objectStatus "@baseboard_fab2_lib.baseboard_fab2(sch_1):page57_i172:ddr0_dq(13)" )
			)
			( pin "U2D1.N86"
				( objectStatus "@baseboard_fab2_lib.baseboard_fab2(sch_1):page57_i172:ddr0_dq(14)" )
			)
			( pin "U2D1.N84"
				( objectStatus "@baseboard_fab2_lib.baseboard_fab2(sch_1):page57_i172:ddr0_dq(15)" )
			)
			( pin "U2D1.V81"
				( objectStatus "@baseboard_fab2_lib.baseboard_fab2(sch_1):page57_i172:ddr0_dq(16)" )
			)
			( pin "U2D1.T79"
				( objectStatus "@baseboard_fab2_lib.baseboard_fab2(sch_1):page57_i172:ddr0_dq(17)" )
			)
			( pin "U2D1.N82"
				( objectStatus "@baseboard_fab2_lib.baseboard_fab2(sch_1):page57_i172:ddr0_dq(18)" )
			)
			( pin "U2D1.M81"
				( objectStatus "@baseboard_fab2_lib.baseboard_fab2(sch_1):page57_i172:ddr0_dq(19)" )
			)
			( pin "U2D1.W80"
				( objectStatus "@baseboard_fab2_lib.baseboard_fab2(sch_1):page57_i172:ddr0_dq(20)" )
			)
			( pin "U2D1.V79"
				( objectStatus "@baseboard_fab2_lib.baseboard_fab2(sch_1):page57_i172:ddr0_dq(21)" )
			)
			( pin "U2D1.R82"
				( objectStatus "@baseboard_fab2_lib.baseboard_fab2(sch_1):page57_i172:ddr0_dq(22)" )
			)
			( pin "U2D1.N80"
				( objectStatus "@baseboard_fab2_lib.baseboard_fab2(sch_1):page57_i172:ddr0_dq(23)" )
			)
			( pin "U2D1.L76"
				( objectStatus "@baseboard_fab2_lib.baseboard_fab2(sch_1):page57_i172:ddr0_dq(24)" )
			)
			( pin "U2D1.R76"
				( objectStatus "@baseboard_fab2_lib.baseboard_fab2(sch_1):page57_i172:ddr0_dq(25)" )
			)
			( pin "U2D1.M73"
				( objectStatus "@baseboard_fab2_lib.baseboard_fab2(sch_1):page57_i172:ddr0_dq(26)" )
			)
			( pin "U2D1.P73"
				( objectStatus "@baseboard_fab2_lib.baseboard_fab2(sch_1):page57_i172:ddr0_dq(27)" )
			)
			( pin "U2D1.M77"
				( objectStatus "@baseboard_fab2_lib.baseboard_fab2(sch_1):page57_i172:ddr0_dq(28)" )
			)
			( pin "U2D1.P77"
				( objectStatus "@baseboard_fab2_lib.baseboard_fab2(sch_1):page57_i172:ddr0_dq(29)" )
			)
			( pin "U2D1.L74"
				( objectStatus "@baseboard_fab2_lib.baseboard_fab2(sch_1):page57_i172:ddr0_dq(30)" )
			)
			( pin "U2D1.R74"
				( objectStatus "@baseboard_fab2_lib.baseboard_fab2(sch_1):page57_i172:ddr0_dq(31)" )
			)
			( pin "U2D1.C42"
				( objectStatus "@baseboard_fab2_lib.baseboard_fab2(sch_1):page57_i172:ddr0_dq(32)" )
			)
			( pin "U2D1.B41"
				( objectStatus "@baseboard_fab2_lib.baseboard_fab2(sch_1):page57_i172:ddr0_dq(33)" )
			)
			( pin "U2D1.C38"
				( objectStatus "@baseboard_fab2_lib.baseboard_fab2(sch_1):page57_i172:ddr0_dq(34)" )
			)
			( pin "U2D1.E38"
				( objectStatus "@baseboard_fab2_lib.baseboard_fab2(sch_1):page57_i172:ddr0_dq(35)" )
			)
			( pin "U2D1.E42"
				( objectStatus "@baseboard_fab2_lib.baseboard_fab2(sch_1):page57_i172:ddr0_dq(36)" )
			)
			( pin "U2D1.F41"
				( objectStatus "@baseboard_fab2_lib.baseboard_fab2(sch_1):page57_i172:ddr0_dq(37)" )
			)
			( pin "U2D1.B39"
				( objectStatus "@baseboard_fab2_lib.baseboard_fab2(sch_1):page57_i172:ddr0_dq(38)" )
			)
			( pin "U2D1.F39"
				( objectStatus "@baseboard_fab2_lib.baseboard_fab2(sch_1):page57_i172:ddr0_dq(39)" )
			)
			( pin "U2D1.K37"
				( objectStatus "@baseboard_fab2_lib.baseboard_fab2(sch_1):page57_i172:ddr0_dq(40)" )
			)
			( pin "U2D1.P37"
				( objectStatus "@baseboard_fab2_lib.baseboard_fab2(sch_1):page57_i172:ddr0_dq(41)" )
			)
			( pin "U2D1.L34"
				( objectStatus "@baseboard_fab2_lib.baseboard_fab2(sch_1):page57_i172:ddr0_dq(42)" )
			)
			( pin "U2D1.N34"
				( objectStatus "@baseboard_fab2_lib.baseboard_fab2(sch_1):page57_i172:ddr0_dq(43)" )
			)
			( pin "U2D1.L38"
				( objectStatus "@baseboard_fab2_lib.baseboard_fab2(sch_1):page57_i172:ddr0_dq(44)" )
			)
			( pin "U2D1.N38"
				( objectStatus "@baseboard_fab2_lib.baseboard_fab2(sch_1):page57_i172:ddr0_dq(45)" )
			)
			( pin "U2D1.K35"
				( objectStatus "@baseboard_fab2_lib.baseboard_fab2(sch_1):page57_i172:ddr0_dq(46)" )
			)
			( pin "U2D1.P35"
				( objectStatus "@baseboard_fab2_lib.baseboard_fab2(sch_1):page57_i172:ddr0_dq(47)" )
			)
			( pin "U2D1.K31"
				( objectStatus "@baseboard_fab2_lib.baseboard_fab2(sch_1):page57_i172:ddr0_dq(48)" )
			)
			( pin "U2D1.P31"
				( objectStatus "@baseboard_fab2_lib.baseboard_fab2(sch_1):page57_i172:ddr0_dq(49)" )
			)
			( pin "U2D1.L28"
				( objectStatus "@baseboard_fab2_lib.baseboard_fab2(sch_1):page57_i172:ddr0_dq(50)" )
			)
			( pin "U2D1.N28"
				( objectStatus "@baseboard_fab2_lib.baseboard_fab2(sch_1):page57_i172:ddr0_dq(51)" )
			)
			( pin "U2D1.L32"
				( objectStatus "@baseboard_fab2_lib.baseboard_fab2(sch_1):page57_i172:ddr0_dq(52)" )
			)
			( pin "U2D1.N32"
				( objectStatus "@baseboard_fab2_lib.baseboard_fab2(sch_1):page57_i172:ddr0_dq(53)" )
			)
			( pin "U2D1.K29"
				( objectStatus "@baseboard_fab2_lib.baseboard_fab2(sch_1):page57_i172:ddr0_dq(54)" )
			)
			( pin "U2D1.P29"
				( objectStatus "@baseboard_fab2_lib.baseboard_fab2(sch_1):page57_i172:ddr0_dq(55)" )
			)
			( pin "U2D1.K25"
				( objectStatus "@baseboard_fab2_lib.baseboard_fab2(sch_1):page57_i172:ddr0_dq(56)" )
			)
			( pin "U2D1.P25"
				( objectStatus "@baseboard_fab2_lib.baseboard_fab2(sch_1):page57_i172:ddr0_dq(57)" )
			)
			( pin "U2D1.P23"
				( objectStatus "@baseboard_fab2_lib.baseboard_fab2(sch_1):page57_i172:ddr0_dq(58)" )
			)
			( pin "U2D1.T23"
				( objectStatus "@baseboard_fab2_lib.baseboard_fab2(sch_1):page57_i172:ddr0_dq(59)" )
			)
			( pin "U2D1.L26"
				( objectStatus "@baseboard_fab2_lib.baseboard_fab2(sch_1):page57_i172:ddr0_dq(60)" )
			)
			( pin "U2D1.N26"
				( objectStatus "@baseboard_fab2_lib.baseboard_fab2(sch_1):page57_i172:ddr0_dq(61)" )
			)
			( pin "U2D1.H23"
				( objectStatus "@baseboard_fab2_lib.baseboard_fab2(sch_1):page57_i172:ddr0_dq(62)" )
			)
			( pin "U2D1.K23"
				( objectStatus "@baseboard_fab2_lib.baseboard_fab2(sch_1):page57_i172:ddr0_dq(63)" )
			)
			( pin "U2D1.AJ84"
				( objectStatus "@baseboard_fab2_lib.baseboard_fab2(sch_1):page57_i172:ddr0_dqs_dn(0)" )
			)
			( pin "U2D1.R84"
				( objectStatus "@baseboard_fab2_lib.baseboard_fab2(sch_1):page57_i172:ddr0_dqs_dn(1)" )
			)
			( pin "U2D1.P79"
				( objectStatus "@baseboard_fab2_lib.baseboard_fab2(sch_1):page57_i172:ddr0_dqs_dn(2)" )
			)
			( pin "U2D1.T75"
				( objectStatus "@baseboard_fab2_lib.baseboard_fab2(sch_1):page57_i172:ddr0_dqs_dn(3)" )
			)
			( pin "U2D1.G40"
				( objectStatus "@baseboard_fab2_lib.baseboard_fab2(sch_1):page57_i172:ddr0_dqs_dn(4)" )
			)
			( pin "U2D1.R36"
				( objectStatus "@baseboard_fab2_lib.baseboard_fab2(sch_1):page57_i172:ddr0_dqs_dn(5)" )
			)
			( pin "U2D1.R30"
				( objectStatus "@baseboard_fab2_lib.baseboard_fab2(sch_1):page57_i172:ddr0_dqs_dn(6)" )
			)
			( pin "U2D1.N24"
				( objectStatus "@baseboard_fab2_lib.baseboard_fab2(sch_1):page57_i172:ddr0_dqs_dn(7)" )
			)
			( pin "U2D1.AH67"
				( objectStatus "@baseboard_fab2_lib.baseboard_fab2(sch_1):page57_i172:ddr0_dqs_dn(8)" )
			)
			( pin "U2D1.AL84"
				( objectStatus "@baseboard_fab2_lib.baseboard_fab2(sch_1):page57_i172:ddr0_dqs_dn(9)" )
			)
			( pin "U2D1.U84"
				( objectStatus "@baseboard_fab2_lib.baseboard_fab2(sch_1):page57_i172:ddr0_dqs_dn(10)" )
			)
			( pin "U2D1.U82"
				( objectStatus "@baseboard_fab2_lib.baseboard_fab2(sch_1):page57_i172:ddr0_dqs_dn(11)" )
			)
			( pin "U2D1.K75"
				( objectStatus "@baseboard_fab2_lib.baseboard_fab2(sch_1):page57_i172:ddr0_dqs_dn(12)" )
			)
			( pin "U2D1.A40"
				( objectStatus "@baseboard_fab2_lib.baseboard_fab2(sch_1):page57_i172:ddr0_dqs_dn(13)" )
			)
			( pin "U2D1.J36"
				( objectStatus "@baseboard_fab2_lib.baseboard_fab2(sch_1):page57_i172:ddr0_dqs_dn(14)" )
			)
			( pin "U2D1.J30"
				( objectStatus "@baseboard_fab2_lib.baseboard_fab2(sch_1):page57_i172:ddr0_dqs_dn(15)" )
			)
			( pin "U2D1.J24"
				( objectStatus "@baseboard_fab2_lib.baseboard_fab2(sch_1):page57_i172:ddr0_dqs_dn(16)" )
			)
			( pin "U2D1.AB67"
				( objectStatus "@baseboard_fab2_lib.baseboard_fab2(sch_1):page57_i172:ddr0_dqs_dn(17)" )
			)
			( pin "U2D1.AH85"
				( objectStatus "@baseboard_fab2_lib.baseboard_fab2(sch_1):page57_i172:ddr0_dqs_dp(0)" )
			)
			( pin "U2D1.P85"
				( objectStatus "@baseboard_fab2_lib.baseboard_fab2(sch_1):page57_i172:ddr0_dqs_dp(1)" )
			)
			( pin "U2D1.R80"
				( objectStatus "@baseboard_fab2_lib.baseboard_fab2(sch_1):page57_i172:ddr0_dqs_dp(2)" )
			)
			( pin "U2D1.P75"
				( objectStatus "@baseboard_fab2_lib.baseboard_fab2(sch_1):page57_i172:ddr0_dqs_dp(3)" )
			)
			( pin "U2D1.E40"
				( objectStatus "@baseboard_fab2_lib.baseboard_fab2(sch_1):page57_i172:ddr0_dqs_dp(4)" )
			)
			( pin "U2D1.N36"
				( objectStatus "@baseboard_fab2_lib.baseboard_fab2(sch_1):page57_i172:ddr0_dqs_dp(5)" )
			)
			( pin "U2D1.N30"
				( objectStatus "@baseboard_fab2_lib.baseboard_fab2(sch_1):page57_i172:ddr0_dqs_dp(6)" )
			)
			( pin "U2D1.R24"
				( objectStatus "@baseboard_fab2_lib.baseboard_fab2(sch_1):page57_i172:ddr0_dqs_dp(7)" )
			)
			( pin "U2D1.AF67"
				( objectStatus "@baseboard_fab2_lib.baseboard_fab2(sch_1):page57_i172:ddr0_dqs_dp(8)" )
			)
			( pin "U2D1.AM85"
				( objectStatus "@baseboard_fab2_lib.baseboard_fab2(sch_1):page57_i172:ddr0_dqs_dp(9)" )
			)
			( pin "U2D1.V85"
				( objectStatus "@baseboard_fab2_lib.baseboard_fab2(sch_1):page57_i172:ddr0_dqs_dp(10)" )
			)
			( pin "U2D1.T81"
				( objectStatus "@baseboard_fab2_lib.baseboard_fab2(sch_1):page57_i172:ddr0_dqs_dp(11)" )
			)
			( pin "U2D1.M75"
				( objectStatus "@baseboard_fab2_lib.baseboard_fab2(sch_1):page57_i172:ddr0_dqs_dp(12)" )
			)
			( pin "U2D1.C40"
				( objectStatus "@baseboard_fab2_lib.baseboard_fab2(sch_1):page57_i172:ddr0_dqs_dp(13)" )
			)
			( pin "U2D1.L36"
				( objectStatus "@baseboard_fab2_lib.baseboard_fab2(sch_1):page57_i172:ddr0_dqs_dp(14)" )
			)
			( pin "U2D1.L30"
				( objectStatus "@baseboard_fab2_lib.baseboard_fab2(sch_1):page57_i172:ddr0_dqs_dp(15)" )
			)
			( pin "U2D1.L24"
				( objectStatus "@baseboard_fab2_lib.baseboard_fab2(sch_1):page57_i172:ddr0_dqs_dp(16)" )
			)
			( pin "U2D1.AD67"
				( objectStatus "@baseboard_fab2_lib.baseboard_fab2(sch_1):page57_i172:ddr0_dqs_dp(17)" )
			)
			( pin "U2D1.AC68"
				( objectStatus "@baseboard_fab2_lib.baseboard_fab2(sch_1):page57_i172:ddr0_ecc(0)" )
			)
			( pin "U2D1.AG68"
				( objectStatus "@baseboard_fab2_lib.baseboard_fab2(sch_1):page57_i172:ddr0_ecc(1)" )
			)
			( pin "U2D1.AD65"
				( objectStatus "@baseboard_fab2_lib.baseboard_fab2(sch_1):page57_i172:ddr0_ecc(2)" )
			)
			( pin "U2D1.AF65"
				( objectStatus "@baseboard_fab2_lib.baseboard_fab2(sch_1):page57_i172:ddr0_ecc(3)" )
			)
			( pin "U2D1.AD69"
				( objectStatus "@baseboard_fab2_lib.baseboard_fab2(sch_1):page57_i172:ddr0_ecc(4)" )
			)
			( pin "U2D1.AF69"
				( objectStatus "@baseboard_fab2_lib.baseboard_fab2(sch_1):page57_i172:ddr0_ecc(5)" )
			)
			( pin "U2D1.AC66"
				( objectStatus "@baseboard_fab2_lib.baseboard_fab2(sch_1):page57_i172:ddr0_ecc(6)" )
			)
			( pin "U2D1.AG66"
				( objectStatus "@baseboard_fab2_lib.baseboard_fab2(sch_1):page57_i172:ddr0_ecc(7)" )
			)
			( pin "U2D1.F53"
				( objectStatus "@baseboard_fab2_lib.baseboard_fab2(sch_1):page57_i172:ddr0_ma(0)" )
			)
			( pin "U2D1.F57"
				( objectStatus "@baseboard_fab2_lib.baseboard_fab2(sch_1):page57_i172:ddr0_ma(1)" )
			)
			( pin "U2D1.D57"
				( objectStatus "@baseboard_fab2_lib.baseboard_fab2(sch_1):page57_i172:ddr0_ma(2)" )
			)
			( pin "U2D1.C58"
				( objectStatus "@baseboard_fab2_lib.baseboard_fab2(sch_1):page57_i172:ddr0_ma(3)" )
			)
			( pin "U2D1.G58"
				( objectStatus "@baseboard_fab2_lib.baseboard_fab2(sch_1):page57_i172:ddr0_ma(4)" )
			)
			( pin "U2D1.F59"
				( objectStatus "@baseboard_fab2_lib.baseboard_fab2(sch_1):page57_i172:ddr0_ma(5)" )
			)
			( pin "U2D1.D59"
				( objectStatus "@baseboard_fab2_lib.baseboard_fab2(sch_1):page57_i172:ddr0_ma(6)" )
			)
			( pin "U2D1.G60"
				( objectStatus "@baseboard_fab2_lib.baseboard_fab2(sch_1):page57_i172:ddr0_ma(7)" )
			)
			( pin "U2D1.C60"
				( objectStatus "@baseboard_fab2_lib.baseboard_fab2(sch_1):page57_i172:ddr0_ma(8)" )
			)
			( pin "U2D1.F61"
				( objectStatus "@baseboard_fab2_lib.baseboard_fab2(sch_1):page57_i172:ddr0_ma(9)" )
			)
			( pin "U2D1.J54"
				( objectStatus "@baseboard_fab2_lib.baseboard_fab2(sch_1):page57_i172:ddr0_ma(10)" )
			)
			( pin "U2D1.G62"
				( objectStatus "@baseboard_fab2_lib.baseboard_fab2(sch_1):page57_i172:ddr0_ma(11)" )
			)
			( pin "U2D1.J64"
				( objectStatus "@baseboard_fab2_lib.baseboard_fab2(sch_1):page57_i172:ddr0_ma(12)" )
			)
			( pin "U2D1.J48"
				( objectStatus "@baseboard_fab2_lib.baseboard_fab2(sch_1):page57_i172:ddr0_ma(13)" )
			)
			( pin "U2D1.F51"
				( objectStatus "@baseboard_fab2_lib.baseboard_fab2(sch_1):page57_i172:ddr0_ma(14)" )
			)
			( pin "U2D1.K49"
				( objectStatus "@baseboard_fab2_lib.baseboard_fab2(sch_1):page57_i172:ddr0_ma(15)" )
			)
			( pin "U2D1.D51"
				( objectStatus "@baseboard_fab2_lib.baseboard_fab2(sch_1):page57_i172:ddr0_ma(16)" )
			)
			( pin "U2D1.K47"
				( objectStatus "@baseboard_fab2_lib.baseboard_fab2(sch_1):page57_i172:ddr0_ma(17)" )
			)
			( pin "U2D1.C50"
				( objectStatus "@baseboard_fab2_lib.baseboard_fab2(sch_1):page57_i172:ddr0_odt(0)" )
			)
			( pin "U2D1.C48"
				( objectStatus "@baseboard_fab2_lib.baseboard_fab2(sch_1):page57_i172:ddr0_odt(1)" )
			)
			( pin "U2D1.G50"
				( objectStatus "@baseboard_fab2_lib.baseboard_fab2(sch_1):page57_i172:ddr0_odt(2)" )
			)
			( pin "U2D1.G48"
				( objectStatus "@baseboard_fab2_lib.baseboard_fab2(sch_1):page57_i172:ddr0_odt(3)" )
			)
			( pin "U2D1.D53"
				( objectStatus "@baseboard_fab2_lib.baseboard_fab2(sch_1):page57_i172:ddr0_par" )
			)
			( pin "U2D1.T63"
				( objectStatus "@baseboard_fab2_lib.baseboard_fab2(sch_1):page58_i172:ddr1_act_n" )
			)
			( pin "U2D1.W62"
				( objectStatus "@baseboard_fab2_lib.baseboard_fab2(sch_1):page58_i172:ddr1_alert_n" )
			)
			( pin "U2D1.T53"
				( objectStatus "@baseboard_fab2_lib.baseboard_fab2(sch_1):page58_i172:ddr1_ba(0)" )
			)
			( pin "U2D1.K55"
				( objectStatus "@baseboard_fab2_lib.baseboard_fab2(sch_1):page58_i172:ddr1_ba(1)" )
			)
			( pin "U2D1.M61"
				( objectStatus "@baseboard_fab2_lib.baseboard_fab2(sch_1):page58_i172:ddr1_bg(0)" )
			)
			( pin "U2D1.N60"
				( objectStatus "@baseboard_fab2_lib.baseboard_fab2(sch_1):page58_i172:ddr1_bg(1)" )
			)
			( pin "U2D1.M47"
				( objectStatus "@baseboard_fab2_lib.baseboard_fab2(sch_1):page58_i172:ddr1_cid(2)" )
			)
			( pin "U2D1.N62"
				( objectStatus "@baseboard_fab2_lib.baseboard_fab2(sch_1):page58_i172:ddr1_cke(0)" )
			)
			( pin "U2D1.R64"
				( objectStatus "@baseboard_fab2_lib.baseboard_fab2(sch_1):page58_i172:ddr1_cke(1)" )
			)
			( pin "U2D1.K63"
				( objectStatus "@baseboard_fab2_lib.baseboard_fab2(sch_1):page58_i172:ddr1_cke(2)" )
			)
			( pin "U2D1.L64"
				( objectStatus "@baseboard_fab2_lib.baseboard_fab2(sch_1):page58_i172:ddr1_cke(3)" )
			)
			( pin "U2D1.M53"
				( objectStatus "@baseboard_fab2_lib.baseboard_fab2(sch_1):page58_i172:ddr1_clk_dn(0)" )
			)
			( pin "U2D1.R54"
				( objectStatus "@baseboard_fab2_lib.baseboard_fab2(sch_1):page58_i172:ddr1_clk_dn(1)" )
			)
			( pin "U2D1.N56"
				( objectStatus "@baseboard_fab2_lib.baseboard_fab2(sch_1):page58_i172:ddr1_clk_dn(2)" )
			)
			( pin "U2D1.R56"
				( objectStatus "@baseboard_fab2_lib.baseboard_fab2(sch_1):page58_i172:ddr1_clk_dn(3)" )
			)
			( pin "U2D1.N54"
				( objectStatus "@baseboard_fab2_lib.baseboard_fab2(sch_1):page58_i172:ddr1_clk_dp(0)" )
			)
			( pin "U2D1.T55"
				( objectStatus "@baseboard_fab2_lib.baseboard_fab2(sch_1):page58_i172:ddr1_clk_dp(1)" )
			)
			( pin "U2D1.M57"
				( objectStatus "@baseboard_fab2_lib.baseboard_fab2(sch_1):page58_i172:ddr1_clk_dp(2)" )
			)
			( pin "U2D1.T57"
				( objectStatus "@baseboard_fab2_lib.baseboard_fab2(sch_1):page58_i172:ddr1_clk_dp(3)" )
			)
			( pin "U2D1.K51"
				( objectStatus "@baseboard_fab2_lib.baseboard_fab2(sch_1):page58_i172:ddr1_cs_n(0)" )
			)
			( pin "U2D1.R50"
				( objectStatus "@baseboard_fab2_lib.baseboard_fab2(sch_1):page58_i172:ddr1_cs_n(1)" )
			)
			( pin "U2D1.N46"
				( objectStatus "@baseboard_fab2_lib.baseboard_fab2(sch_1):page58_i172:ddr1_cs_n(2)" )
			)
			( pin "U2D1.V47"
				( objectStatus "@baseboard_fab2_lib.baseboard_fab2(sch_1):page58_i172:ddr1_cs_n(3)" )
			)
			( pin "U2D1.J50"
				( objectStatus "@baseboard_fab2_lib.baseboard_fab2(sch_1):page58_i172:ddr1_cs_n(4)" )
			)
			( pin "U2D1.T49"
				( objectStatus "@baseboard_fab2_lib.baseboard_fab2(sch_1):page58_i172:ddr1_cs_n(5)" )
			)
			( pin "U2D1.M45"
				( objectStatus "@baseboard_fab2_lib.baseboard_fab2(sch_1):page58_i172:ddr1_cs_n(6)" )
			)
			( pin "U2D1.R46"
				( objectStatus "@baseboard_fab2_lib.baseboard_fab2(sch_1):page58_i172:ddr1_cs_n(7)" )
			)
			( pin "U2D1.AV81"
				( objectStatus "@baseboard_fab2_lib.baseboard_fab2(sch_1):page58_i172:ddr1_dq(0)" )
			)
			( pin "U2D1.AT79"
				( objectStatus "@baseboard_fab2_lib.baseboard_fab2(sch_1):page58_i172:ddr1_dq(1)" )
			)
			( pin "U2D1.AN82"
				( objectStatus "@baseboard_fab2_lib.baseboard_fab2(sch_1):page58_i172:ddr1_dq(2)" )
			)
			( pin "U2D1.AM81"
				( objectStatus "@baseboard_fab2_lib.baseboard_fab2(sch_1):page58_i172:ddr1_dq(3)" )
			)
			( pin "U2D1.AW80"
				( objectStatus "@baseboard_fab2_lib.baseboard_fab2(sch_1):page58_i172:ddr1_dq(4)" )
			)
			( pin "U2D1.AV79"
				( objectStatus "@baseboard_fab2_lib.baseboard_fab2(sch_1):page58_i172:ddr1_dq(5)" )
			)
			( pin "U2D1.AR82"
				( objectStatus "@baseboard_fab2_lib.baseboard_fab2(sch_1):page58_i172:ddr1_dq(6)" )
			)
			( pin "U2D1.AN80"
				( objectStatus "@baseboard_fab2_lib.baseboard_fab2(sch_1):page58_i172:ddr1_dq(7)" )
			)
			( pin "U2D1.AH81"
				( objectStatus "@baseboard_fab2_lib.baseboard_fab2(sch_1):page58_i172:ddr1_dq(8)" )
			)
			( pin "U2D1.AF79"
				( objectStatus "@baseboard_fab2_lib.baseboard_fab2(sch_1):page58_i172:ddr1_dq(9)" )
			)
			( pin "U2D1.AC82"
				( objectStatus "@baseboard_fab2_lib.baseboard_fab2(sch_1):page58_i172:ddr1_dq(10)" )
			)
			( pin "U2D1.AB81"
				( objectStatus "@baseboard_fab2_lib.baseboard_fab2(sch_1):page58_i172:ddr1_dq(11)" )
			)
			( pin "U2D1.AJ80"
				( objectStatus "@baseboard_fab2_lib.baseboard_fab2(sch_1):page58_i172:ddr1_dq(12)" )
			)
			( pin "U2D1.AH79"
				( objectStatus "@baseboard_fab2_lib.baseboard_fab2(sch_1):page58_i172:ddr1_dq(13)" )
			)
			( pin "U2D1.AE82"
				( objectStatus "@baseboard_fab2_lib.baseboard_fab2(sch_1):page58_i172:ddr1_dq(14)" )
			)
			( pin "U2D1.AC80"
				( objectStatus "@baseboard_fab2_lib.baseboard_fab2(sch_1):page58_i172:ddr1_dq(15)" )
			)
			( pin "U2D1.E80"
				( objectStatus "@baseboard_fab2_lib.baseboard_fab2(sch_1):page58_i172:ddr1_dq(16)" )
			)
			( pin "U2D1.J80"
				( objectStatus "@baseboard_fab2_lib.baseboard_fab2(sch_1):page58_i172:ddr1_dq(17)" )
			)
			( pin "U2D1.F77"
				( objectStatus "@baseboard_fab2_lib.baseboard_fab2(sch_1):page58_i172:ddr1_dq(18)" )
			)
			( pin "U2D1.H77"
				( objectStatus "@baseboard_fab2_lib.baseboard_fab2(sch_1):page58_i172:ddr1_dq(19)" )
			)
			( pin "U2D1.F81"
				( objectStatus "@baseboard_fab2_lib.baseboard_fab2(sch_1):page58_i172:ddr1_dq(20)" )
			)
			( pin "U2D1.H81"
				( objectStatus "@baseboard_fab2_lib.baseboard_fab2(sch_1):page58_i172:ddr1_dq(21)" )
			)
			( pin "U2D1.E78"
				( objectStatus "@baseboard_fab2_lib.baseboard_fab2(sch_1):page58_i172:ddr1_dq(22)" )
			)
			( pin "U2D1.J78"
				( objectStatus "@baseboard_fab2_lib.baseboard_fab2(sch_1):page58_i172:ddr1_dq(23)" )
			)
			( pin "U2D1.D75"
				( objectStatus "@baseboard_fab2_lib.baseboard_fab2(sch_1):page58_i172:ddr1_dq(24)" )
			)
			( pin "U2D1.C74"
				( objectStatus "@baseboard_fab2_lib.baseboard_fab2(sch_1):page58_i172:ddr1_dq(25)" )
			)
			( pin "U2D1.D71"
				( objectStatus "@baseboard_fab2_lib.baseboard_fab2(sch_1):page58_i172:ddr1_dq(26)" )
			)
			( pin "U2D1.F71"
				( objectStatus "@baseboard_fab2_lib.baseboard_fab2(sch_1):page58_i172:ddr1_dq(27)" )
			)
			( pin "U2D1.F75"
				( objectStatus "@baseboard_fab2_lib.baseboard_fab2(sch_1):page58_i172:ddr1_dq(28)" )
			)
			( pin "U2D1.G74"
				( objectStatus "@baseboard_fab2_lib.baseboard_fab2(sch_1):page58_i172:ddr1_dq(29)" )
			)
			( pin "U2D1.C72"
				( objectStatus "@baseboard_fab2_lib.baseboard_fab2(sch_1):page58_i172:ddr1_dq(30)" )
			)
			( pin "U2D1.G72"
				( objectStatus "@baseboard_fab2_lib.baseboard_fab2(sch_1):page58_i172:ddr1_dq(31)" )
			)
			( pin "U2D1.K43"
				( objectStatus "@baseboard_fab2_lib.baseboard_fab2(sch_1):page58_i172:ddr1_dq(32)" )
			)
			( pin "U2D1.H43"
				( objectStatus "@baseboard_fab2_lib.baseboard_fab2(sch_1):page58_i172:ddr1_dq(33)" )
			)
			( pin "U2D1.L40"
				( objectStatus "@baseboard_fab2_lib.baseboard_fab2(sch_1):page58_i172:ddr1_dq(34)" )
			)
			( pin "U2D1.N40"
				( objectStatus "@baseboard_fab2_lib.baseboard_fab2(sch_1):page58_i172:ddr1_dq(35)" )
			)
			( pin "U2D1.P43"
				( objectStatus "@baseboard_fab2_lib.baseboard_fab2(sch_1):page58_i172:ddr1_dq(36)" )
			)
			( pin "U2D1.T43"
				( objectStatus "@baseboard_fab2_lib.baseboard_fab2(sch_1):page58_i172:ddr1_dq(37)" )
			)
			( pin "U2D1.K41"
				( objectStatus "@baseboard_fab2_lib.baseboard_fab2(sch_1):page58_i172:ddr1_dq(38)" )
			)
			( pin "U2D1.P41"
				( objectStatus "@baseboard_fab2_lib.baseboard_fab2(sch_1):page58_i172:ddr1_dq(39)" )
			)
			( pin "U2D1.C36"
				( objectStatus "@baseboard_fab2_lib.baseboard_fab2(sch_1):page58_i172:ddr1_dq(40)" )
			)
			( pin "U2D1.B35"
				( objectStatus "@baseboard_fab2_lib.baseboard_fab2(sch_1):page58_i172:ddr1_dq(41)" )
			)
			( pin "U2D1.C32"
				( objectStatus "@baseboard_fab2_lib.baseboard_fab2(sch_1):page58_i172:ddr1_dq(42)" )
			)
			( pin "U2D1.E32"
				( objectStatus "@baseboard_fab2_lib.baseboard_fab2(sch_1):page58_i172:ddr1_dq(43)" )
			)
			( pin "U2D1.E36"
				( objectStatus "@baseboard_fab2_lib.baseboard_fab2(sch_1):page58_i172:ddr1_dq(44)" )
			)
			( pin "U2D1.F35"
				( objectStatus "@baseboard_fab2_lib.baseboard_fab2(sch_1):page58_i172:ddr1_dq(45)" )
			)
			( pin "U2D1.B33"
				( objectStatus "@baseboard_fab2_lib.baseboard_fab2(sch_1):page58_i172:ddr1_dq(46)" )
			)
			( pin "U2D1.F33"
				( objectStatus "@baseboard_fab2_lib.baseboard_fab2(sch_1):page58_i172:ddr1_dq(47)" )
			)
			( pin "U2D1.C30"
				( objectStatus "@baseboard_fab2_lib.baseboard_fab2(sch_1):page58_i172:ddr1_dq(48)" )
			)
			( pin "U2D1.B29"
				( objectStatus "@baseboard_fab2_lib.baseboard_fab2(sch_1):page58_i172:ddr1_dq(49)" )
			)
			( pin "U2D1.C26"
				( objectStatus "@baseboard_fab2_lib.baseboard_fab2(sch_1):page58_i172:ddr1_dq(50)" )
			)
			( pin "U2D1.E26"
				( objectStatus "@baseboard_fab2_lib.baseboard_fab2(sch_1):page58_i172:ddr1_dq(51)" )
			)
			( pin "U2D1.E30"
				( objectStatus "@baseboard_fab2_lib.baseboard_fab2(sch_1):page58_i172:ddr1_dq(52)" )
			)
			( pin "U2D1.F29"
				( objectStatus "@baseboard_fab2_lib.baseboard_fab2(sch_1):page58_i172:ddr1_dq(53)" )
			)
			( pin "U2D1.B27"
				( objectStatus "@baseboard_fab2_lib.baseboard_fab2(sch_1):page58_i172:ddr1_dq(54)" )
			)
			( pin "U2D1.F27"
				( objectStatus "@baseboard_fab2_lib.baseboard_fab2(sch_1):page58_i172:ddr1_dq(55)" )
			)
			( pin "U2D1.U28"
				( objectStatus "@baseboard_fab2_lib.baseboard_fab2(sch_1):page58_i172:ddr1_dq(56)" )
			)
			( pin "U2D1.AA28"
				( objectStatus "@baseboard_fab2_lib.baseboard_fab2(sch_1):page58_i172:ddr1_dq(57)" )
			)
			( pin "U2D1.V25"
				( objectStatus "@baseboard_fab2_lib.baseboard_fab2(sch_1):page58_i172:ddr1_dq(58)" )
			)
			( pin "U2D1.Y25"
				( objectStatus "@baseboard_fab2_lib.baseboard_fab2(sch_1):page58_i172:ddr1_dq(59)" )
			)
			( pin "U2D1.V29"
				( objectStatus "@baseboard_fab2_lib.baseboard_fab2(sch_1):page58_i172:ddr1_dq(60)" )
			)
			( pin "U2D1.Y29"
				( objectStatus "@baseboard_fab2_lib.baseboard_fab2(sch_1):page58_i172:ddr1_dq(61)" )
			)
			( pin "U2D1.U26"
				( objectStatus "@baseboard_fab2_lib.baseboard_fab2(sch_1):page58_i172:ddr1_dq(62)" )
			)
			( pin "U2D1.AA26"
				( objectStatus "@baseboard_fab2_lib.baseboard_fab2(sch_1):page58_i172:ddr1_dq(63)" )
			)
			( pin "U2D1.AP79"
				( objectStatus "@baseboard_fab2_lib.baseboard_fab2(sch_1):page58_i172:ddr1_dqs_dn(0)" )
			)
			( pin "U2D1.AD79"
				( objectStatus "@baseboard_fab2_lib.baseboard_fab2(sch_1):page58_i172:ddr1_dqs_dn(1)" )
			)
			( pin "U2D1.K79"
				( objectStatus "@baseboard_fab2_lib.baseboard_fab2(sch_1):page58_i172:ddr1_dqs_dn(2)" )
			)
			( pin "U2D1.H73"
				( objectStatus "@baseboard_fab2_lib.baseboard_fab2(sch_1):page58_i172:ddr1_dqs_dn(3)" )
			)
			( pin "U2D1.N42"
				( objectStatus "@baseboard_fab2_lib.baseboard_fab2(sch_1):page58_i172:ddr1_dqs_dn(4)" )
			)
			( pin "U2D1.G34"
				( objectStatus "@baseboard_fab2_lib.baseboard_fab2(sch_1):page58_i172:ddr1_dqs_dn(5)" )
			)
			( pin "U2D1.G28"
				( objectStatus "@baseboard_fab2_lib.baseboard_fab2(sch_1):page58_i172:ddr1_dqs_dn(6)" )
			)
			( pin "U2D1.AB27"
				( objectStatus "@baseboard_fab2_lib.baseboard_fab2(sch_1):page58_i172:ddr1_dqs_dn(7)" )
			)
			( pin "U2D1.N68"
				( objectStatus "@baseboard_fab2_lib.baseboard_fab2(sch_1):page58_i172:ddr1_dqs_dn(8)" )
			)
			( pin "U2D1.AU82"
				( objectStatus "@baseboard_fab2_lib.baseboard_fab2(sch_1):page58_i172:ddr1_dqs_dn(9)" )
			)
			( pin "U2D1.AG82"
				( objectStatus "@baseboard_fab2_lib.baseboard_fab2(sch_1):page58_i172:ddr1_dqs_dn(10)" )
			)
			( pin "U2D1.D79"
				( objectStatus "@baseboard_fab2_lib.baseboard_fab2(sch_1):page58_i172:ddr1_dqs_dn(11)" )
			)
			( pin "U2D1.B73"
				( objectStatus "@baseboard_fab2_lib.baseboard_fab2(sch_1):page58_i172:ddr1_dqs_dn(12)" )
			)
			( pin "U2D1.J42"
				( objectStatus "@baseboard_fab2_lib.baseboard_fab2(sch_1):page58_i172:ddr1_dqs_dn(13)" )
			)
			( pin "U2D1.A34"
				( objectStatus "@baseboard_fab2_lib.baseboard_fab2(sch_1):page58_i172:ddr1_dqs_dn(14)" )
			)
			( pin "U2D1.A28"
				( objectStatus "@baseboard_fab2_lib.baseboard_fab2(sch_1):page58_i172:ddr1_dqs_dn(15)" )
			)
			( pin "U2D1.T27"
				( objectStatus "@baseboard_fab2_lib.baseboard_fab2(sch_1):page58_i172:ddr1_dqs_dn(16)" )
			)
			( pin "U2D1.G68"
				( objectStatus "@baseboard_fab2_lib.baseboard_fab2(sch_1):page58_i172:ddr1_dqs_dn(17)" )
			)
			( pin "U2D1.AR80"
				( objectStatus "@baseboard_fab2_lib.baseboard_fab2(sch_1):page58_i172:ddr1_dqs_dp(0)" )
			)
			( pin "U2D1.AE80"
				( objectStatus "@baseboard_fab2_lib.baseboard_fab2(sch_1):page58_i172:ddr1_dqs_dp(1)" )
			)
			( pin "U2D1.H79"
				( objectStatus "@baseboard_fab2_lib.baseboard_fab2(sch_1):page58_i172:ddr1_dqs_dp(2)" )
			)
			( pin "U2D1.F73"
				( objectStatus "@baseboard_fab2_lib.baseboard_fab2(sch_1):page58_i172:ddr1_dqs_dp(3)" )
			)
			( pin "U2D1.R42"
				( objectStatus "@baseboard_fab2_lib.baseboard_fab2(sch_1):page58_i172:ddr1_dqs_dp(4)" )
			)
			( pin "U2D1.E34"
				( objectStatus "@baseboard_fab2_lib.baseboard_fab2(sch_1):page58_i172:ddr1_dqs_dp(5)" )
			)
			( pin "U2D1.E28"
				( objectStatus "@baseboard_fab2_lib.baseboard_fab2(sch_1):page58_i172:ddr1_dqs_dp(6)" )
			)
			( pin "U2D1.Y27"
				( objectStatus "@baseboard_fab2_lib.baseboard_fab2(sch_1):page58_i172:ddr1_dqs_dp(7)" )
			)
			( pin "U2D1.L68"
				( objectStatus "@baseboard_fab2_lib.baseboard_fab2(sch_1):page58_i172:ddr1_dqs_dp(8)" )
			)
			( pin "U2D1.AT81"
				( objectStatus "@baseboard_fab2_lib.baseboard_fab2(sch_1):page58_i172:ddr1_dqs_dp(9)" )
			)
			( pin "U2D1.AF81"
				( objectStatus "@baseboard_fab2_lib.baseboard_fab2(sch_1):page58_i172:ddr1_dqs_dp(10)" )
			)
			( pin "U2D1.F79"
				( objectStatus "@baseboard_fab2_lib.baseboard_fab2(sch_1):page58_i172:ddr1_dqs_dp(11)" )
			)
			( pin "U2D1.D73"
				( objectStatus "@baseboard_fab2_lib.baseboard_fab2(sch_1):page58_i172:ddr1_dqs_dp(12)" )
			)
			( pin "U2D1.L42"
				( objectStatus "@baseboard_fab2_lib.baseboard_fab2(sch_1):page58_i172:ddr1_dqs_dp(13)" )
			)
			( pin "U2D1.C34"
				( objectStatus "@baseboard_fab2_lib.baseboard_fab2(sch_1):page58_i172:ddr1_dqs_dp(14)" )
			)
			( pin "U2D1.C28"
				( objectStatus "@baseboard_fab2_lib.baseboard_fab2(sch_1):page58_i172:ddr1_dqs_dp(15)" )
			)
			( pin "U2D1.V27"
				( objectStatus "@baseboard_fab2_lib.baseboard_fab2(sch_1):page58_i172:ddr1_dqs_dp(16)" )
			)
			( pin "U2D1.J68"
				( objectStatus "@baseboard_fab2_lib.baseboard_fab2(sch_1):page58_i172:ddr1_dqs_dp(17)" )
			)
			( pin "U2D1.J70"
				( objectStatus "@baseboard_fab2_lib.baseboard_fab2(sch_1):page58_i172:ddr1_ecc(0)" )
			)
			( pin "U2D1.H69"
				( objectStatus "@baseboard_fab2_lib.baseboard_fab2(sch_1):page58_i172:ddr1_ecc(1)" )
			)
			( pin "U2D1.J66"
				( objectStatus "@baseboard_fab2_lib.baseboard_fab2(sch_1):page58_i172:ddr1_ecc(2)" )
			)
			( pin "U2D1.L66"
				( objectStatus "@baseboard_fab2_lib.baseboard_fab2(sch_1):page58_i172:ddr1_ecc(3)" )
			)
			( pin "U2D1.L70"
				( objectStatus "@baseboard_fab2_lib.baseboard_fab2(sch_1):page58_i172:ddr1_ecc(4)" )
			)
			( pin "U2D1.M69"
				( objectStatus "@baseboard_fab2_lib.baseboard_fab2(sch_1):page58_i172:ddr1_ecc(5)" )
			)
			( pin "U2D1.H67"
				( objectStatus "@baseboard_fab2_lib.baseboard_fab2(sch_1):page58_i172:ddr1_ecc(6)" )
			)
			( pin "U2D1.M67"
				( objectStatus "@baseboard_fab2_lib.baseboard_fab2(sch_1):page58_i172:ddr1_ecc(7)" )
			)
			( pin "U2D1.J52"
				( objectStatus "@baseboard_fab2_lib.baseboard_fab2(sch_1):page58_i172:ddr1_ma(0)" )
			)
			( pin "U2D1.J58"
				( objectStatus "@baseboard_fab2_lib.baseboard_fab2(sch_1):page58_i172:ddr1_ma(1)" )
			)
			( pin "U2D1.K57"
				( objectStatus "@baseboard_fab2_lib.baseboard_fab2(sch_1):page58_i172:ddr1_ma(2)" )
			)
			( pin "U2D1.N58"
				( objectStatus "@baseboard_fab2_lib.baseboard_fab2(sch_1):page58_i172:ddr1_ma(3)" )
			)
			( pin "U2D1.M59"
				( objectStatus "@baseboard_fab2_lib.baseboard_fab2(sch_1):page58_i172:ddr1_ma(4)" )
			)
			( pin "U2D1.R58"
				( objectStatus "@baseboard_fab2_lib.baseboard_fab2(sch_1):page58_i172:ddr1_ma(5)" )
			)
			( pin "U2D1.T59"
				( objectStatus "@baseboard_fab2_lib.baseboard_fab2(sch_1):page58_i172:ddr1_ma(6)" )
			)
			( pin "U2D1.V61"
				( objectStatus "@baseboard_fab2_lib.baseboard_fab2(sch_1):page58_i172:ddr1_ma(7)" )
			)
			( pin "U2D1.W60"
				( objectStatus "@baseboard_fab2_lib.baseboard_fab2(sch_1):page58_i172:ddr1_ma(8)" )
			)
			( pin "U2D1.K59"
				( objectStatus "@baseboard_fab2_lib.baseboard_fab2(sch_1):page58_i172:ddr1_ma(9)" )
			)
			( pin "U2D1.M55"
				( objectStatus "@baseboard_fab2_lib.baseboard_fab2(sch_1):page58_i172:ddr1_ma(10)" )
			)
			( pin "U2D1.R60"
				( objectStatus "@baseboard_fab2_lib.baseboard_fab2(sch_1):page58_i172:ddr1_ma(11)" )
			)
			( pin "U2D1.T61"
				( objectStatus "@baseboard_fab2_lib.baseboard_fab2(sch_1):page58_i172:ddr1_ma(12)" )
			)
			( pin "U2D1.M51"
				( objectStatus "@baseboard_fab2_lib.baseboard_fab2(sch_1):page58_i172:ddr1_ma(13)" )
			)
			( pin "U2D1.T51"
				( objectStatus "@baseboard_fab2_lib.baseboard_fab2(sch_1):page58_i172:ddr1_ma(14)" )
			)
			( pin "U2D1.N52"
				( objectStatus "@baseboard_fab2_lib.baseboard_fab2(sch_1):page58_i172:ddr1_ma(15)" )
			)
			( pin "U2D1.R52"
				( objectStatus "@baseboard_fab2_lib.baseboard_fab2(sch_1):page58_i172:ddr1_ma(16)" )
			)
			( pin "U2D1.N48"
				( objectStatus "@baseboard_fab2_lib.baseboard_fab2(sch_1):page58_i172:ddr1_ma(17)" )
			)
			( pin "U2D1.N50"
				( objectStatus "@baseboard_fab2_lib.baseboard_fab2(sch_1):page58_i172:ddr1_odt(0)" )
			)
			( pin "U2D1.R48"
				( objectStatus "@baseboard_fab2_lib.baseboard_fab2(sch_1):page58_i172:ddr1_odt(1)" )
			)
			( pin "U2D1.M49"
				( objectStatus "@baseboard_fab2_lib.baseboard_fab2(sch_1):page58_i172:ddr1_odt(2)" )
			)
			( pin "U2D1.T47"
				( objectStatus "@baseboard_fab2_lib.baseboard_fab2(sch_1):page58_i172:ddr1_odt(3)" )
			)
			( pin "U2D1.K53"
				( objectStatus "@baseboard_fab2_lib.baseboard_fab2(sch_1):page58_i172:ddr1_par" )
			)
			( pin "U2D1.AB61"
				( objectStatus "@baseboard_fab2_lib.baseboard_fab2(sch_1):page59_i172:ddr2_act_n" )
			)
			( pin "U2D1.AD61"
				( objectStatus "@baseboard_fab2_lib.baseboard_fab2(sch_1):page59_i172:ddr2_alert_n" )
			)
			( pin "U2D1.W52"
				( objectStatus "@baseboard_fab2_lib.baseboard_fab2(sch_1):page59_i172:ddr2_ba(0)" )
			)
			( pin "U2D1.AE56"
				( objectStatus "@baseboard_fab2_lib.baseboard_fab2(sch_1):page59_i172:ddr2_ba(1)" )
			)
			( pin "U2D1.AA60"
				( objectStatus "@baseboard_fab2_lib.baseboard_fab2(sch_1):page59_i172:ddr2_bg(0)" )
			)
			( pin "U2D1.AE62"
				( objectStatus "@baseboard_fab2_lib.baseboard_fab2(sch_1):page59_i172:ddr2_bg(1)" )
			)
			( pin "U2D1.AB45"
				( objectStatus "@baseboard_fab2_lib.baseboard_fab2(sch_1):page59_i172:ddr2_cid(2)" )
			)
			( pin "U2D1.AA62"
				( objectStatus "@baseboard_fab2_lib.baseboard_fab2(sch_1):page59_i172:ddr2_cke(0)" )
			)
			( pin "U2D1.AD63"
				( objectStatus "@baseboard_fab2_lib.baseboard_fab2(sch_1):page59_i172:ddr2_cke(1)" )
			)
			( pin "U2D1.V63"
				( objectStatus "@baseboard_fab2_lib.baseboard_fab2(sch_1):page59_i172:ddr2_cke(2)" )
			)
			( pin "U2D1.AB63"
				( objectStatus "@baseboard_fab2_lib.baseboard_fab2(sch_1):page59_i172:ddr2_cke(3)" )
			)
			( pin "U2D1.AA54"
				( objectStatus "@baseboard_fab2_lib.baseboard_fab2(sch_1):page59_i172:ddr2_clk_dn(0)" )
			)
			( pin "U2D1.W54"
				( objectStatus "@baseboard_fab2_lib.baseboard_fab2(sch_1):page59_i172:ddr2_clk_dn(1)" )
			)
			( pin "U2D1.AA56"
				( objectStatus "@baseboard_fab2_lib.baseboard_fab2(sch_1):page59_i172:ddr2_clk_dn(2)" )
			)
			( pin "U2D1.W56"
				( objectStatus "@baseboard_fab2_lib.baseboard_fab2(sch_1):page59_i172:ddr2_clk_dn(3)" )
			)
			( pin "U2D1.AB55"
				( objectStatus "@baseboard_fab2_lib.baseboard_fab2(sch_1):page59_i172:ddr2_clk_dp(0)" )
			)
			( pin "U2D1.V55"
				( objectStatus "@baseboard_fab2_lib.baseboard_fab2(sch_1):page59_i172:ddr2_clk_dp(1)" )
			)
			( pin "U2D1.AB57"
				( objectStatus "@baseboard_fab2_lib.baseboard_fab2(sch_1):page59_i172:ddr2_clk_dp(2)" )
			)
			( pin "U2D1.V57"
				( objectStatus "@baseboard_fab2_lib.baseboard_fab2(sch_1):page59_i172:ddr2_clk_dp(3)" )
			)
			( pin "U2D1.V51"
				( objectStatus "@baseboard_fab2_lib.baseboard_fab2(sch_1):page59_i172:ddr2_cs_n(0)" )
			)
			( pin "U2D1.AB49"
				( objectStatus "@baseboard_fab2_lib.baseboard_fab2(sch_1):page59_i172:ddr2_cs_n(1)" )
			)
			( pin "U2D1.W46"
				( objectStatus "@baseboard_fab2_lib.baseboard_fab2(sch_1):page59_i172:ddr2_cs_n(2)" )
			)
			( pin "U2D1.AA46"
				( objectStatus "@baseboard_fab2_lib.baseboard_fab2(sch_1):page59_i172:ddr2_cs_n(3)" )
			)
			( pin "U2D1.AB51"
				( objectStatus "@baseboard_fab2_lib.baseboard_fab2(sch_1):page59_i172:ddr2_cs_n(4)" )
			)
			( pin "U2D1.W48"
				( objectStatus "@baseboard_fab2_lib.baseboard_fab2(sch_1):page59_i172:ddr2_cs_n(5)" )
			)
			( pin "U2D1.T45"
				( objectStatus "@baseboard_fab2_lib.baseboard_fab2(sch_1):page59_i172:ddr2_cs_n(6)" )
			)
			( pin "U2D1.V45"
				( objectStatus "@baseboard_fab2_lib.baseboard_fab2(sch_1):page59_i172:ddr2_cs_n(7)" )
			)
			( pin "U2D1.AR76"
				( objectStatus "@baseboard_fab2_lib.baseboard_fab2(sch_1):page59_i172:ddr2_dq(0)" )
			)
			( pin "U2D1.AN74"
				( objectStatus "@baseboard_fab2_lib.baseboard_fab2(sch_1):page59_i172:ddr2_dq(1)" )
			)
			( pin "U2D1.AK77"
				( objectStatus "@baseboard_fab2_lib.baseboard_fab2(sch_1):page59_i172:ddr2_dq(2)" )
			)
			( pin "U2D1.AJ76"
				( objectStatus "@baseboard_fab2_lib.baseboard_fab2(sch_1):page59_i172:ddr2_dq(3)" )
			)
			( pin "U2D1.AT75"
				( objectStatus "@baseboard_fab2_lib.baseboard_fab2(sch_1):page59_i172:ddr2_dq(4)" )
			)
			( pin "U2D1.AR74"
				( objectStatus "@baseboard_fab2_lib.baseboard_fab2(sch_1):page59_i172:ddr2_dq(5)" )
			)
			( pin "U2D1.AM77"
				( objectStatus "@baseboard_fab2_lib.baseboard_fab2(sch_1):page59_i172:ddr2_dq(6)" )
			)
			( pin "U2D1.AK75"
				( objectStatus "@baseboard_fab2_lib.baseboard_fab2(sch_1):page59_i172:ddr2_dq(7)" )
			)
			( pin "U2D1.AE76"
				( objectStatus "@baseboard_fab2_lib.baseboard_fab2(sch_1):page59_i172:ddr2_dq(8)" )
			)
			( pin "U2D1.AC74"
				( objectStatus "@baseboard_fab2_lib.baseboard_fab2(sch_1):page59_i172:ddr2_dq(9)" )
			)
			( pin "U2D1.Y77"
				( objectStatus "@baseboard_fab2_lib.baseboard_fab2(sch_1):page59_i172:ddr2_dq(10)" )
			)
			( pin "U2D1.W76"
				( objectStatus "@baseboard_fab2_lib.baseboard_fab2(sch_1):page59_i172:ddr2_dq(11)" )
			)
			( pin "U2D1.AF75"
				( objectStatus "@baseboard_fab2_lib.baseboard_fab2(sch_1):page59_i172:ddr2_dq(12)" )
			)
			( pin "U2D1.AE74"
				( objectStatus "@baseboard_fab2_lib.baseboard_fab2(sch_1):page59_i172:ddr2_dq(13)" )
			)
			( pin "U2D1.AB77"
				( objectStatus "@baseboard_fab2_lib.baseboard_fab2(sch_1):page59_i172:ddr2_dq(14)" )
			)
			( pin "U2D1.Y75"
				( objectStatus "@baseboard_fab2_lib.baseboard_fab2(sch_1):page59_i172:ddr2_dq(15)" )
			)
			( pin "U2D1.W72"
				( objectStatus "@baseboard_fab2_lib.baseboard_fab2(sch_1):page59_i172:ddr2_dq(16)" )
			)
			( pin "U2D1.AA70"
				( objectStatus "@baseboard_fab2_lib.baseboard_fab2(sch_1):page59_i172:ddr2_dq(17)" )
			)
			( pin "U2D1.R70"
				( objectStatus "@baseboard_fab2_lib.baseboard_fab2(sch_1):page59_i172:ddr2_dq(18)" )
			)
			( pin "U2D1.T69"
				( objectStatus "@baseboard_fab2_lib.baseboard_fab2(sch_1):page59_i172:ddr2_dq(19)" )
			)
			( pin "U2D1.AA72"
				( objectStatus "@baseboard_fab2_lib.baseboard_fab2(sch_1):page59_i172:ddr2_dq(20)" )
			)
			( pin "U2D1.AB71"
				( objectStatus "@baseboard_fab2_lib.baseboard_fab2(sch_1):page59_i172:ddr2_dq(21)" )
			)
			( pin "U2D1.T71"
				( objectStatus "@baseboard_fab2_lib.baseboard_fab2(sch_1):page59_i172:ddr2_dq(22)" )
			)
			( pin "U2D1.V69"
				( objectStatus "@baseboard_fab2_lib.baseboard_fab2(sch_1):page59_i172:ddr2_dq(23)" )
			)
			( pin "U2D1.AM67"
				( objectStatus "@baseboard_fab2_lib.baseboard_fab2(sch_1):page59_i172:ddr2_dq(24)" )
			)
			( pin "U2D1.AT67"
				( objectStatus "@baseboard_fab2_lib.baseboard_fab2(sch_1):page59_i172:ddr2_dq(25)" )
			)
			( pin "U2D1.AN64"
				( objectStatus "@baseboard_fab2_lib.baseboard_fab2(sch_1):page59_i172:ddr2_dq(26)" )
			)
			( pin "U2D1.AR64"
				( objectStatus "@baseboard_fab2_lib.baseboard_fab2(sch_1):page59_i172:ddr2_dq(27)" )
			)
			( pin "U2D1.AN68"
				( objectStatus "@baseboard_fab2_lib.baseboard_fab2(sch_1):page59_i172:ddr2_dq(28)" )
			)
			( pin "U2D1.AR68"
				( objectStatus "@baseboard_fab2_lib.baseboard_fab2(sch_1):page59_i172:ddr2_dq(29)" )
			)
			( pin "U2D1.AM65"
				( objectStatus "@baseboard_fab2_lib.baseboard_fab2(sch_1):page59_i172:ddr2_dq(30)" )
			)
			( pin "U2D1.AT65"
				( objectStatus "@baseboard_fab2_lib.baseboard_fab2(sch_1):page59_i172:ddr2_dq(31)" )
			)
			( pin "U2D1.U40"
				( objectStatus "@baseboard_fab2_lib.baseboard_fab2(sch_1):page59_i172:ddr2_dq(32)" )
			)
			( pin "U2D1.AA40"
				( objectStatus "@baseboard_fab2_lib.baseboard_fab2(sch_1):page59_i172:ddr2_dq(33)" )
			)
			( pin "U2D1.V37"
				( objectStatus "@baseboard_fab2_lib.baseboard_fab2(sch_1):page59_i172:ddr2_dq(34)" )
			)
			( pin "U2D1.Y37"
				( objectStatus "@baseboard_fab2_lib.baseboard_fab2(sch_1):page59_i172:ddr2_dq(35)" )
			)
			( pin "U2D1.V41"
				( objectStatus "@baseboard_fab2_lib.baseboard_fab2(sch_1):page59_i172:ddr2_dq(36)" )
			)
			( pin "U2D1.Y41"
				( objectStatus "@baseboard_fab2_lib.baseboard_fab2(sch_1):page59_i172:ddr2_dq(37)" )
			)
			( pin "U2D1.U38"
				( objectStatus "@baseboard_fab2_lib.baseboard_fab2(sch_1):page59_i172:ddr2_dq(38)" )
			)
			( pin "U2D1.AA38"
				( objectStatus "@baseboard_fab2_lib.baseboard_fab2(sch_1):page59_i172:ddr2_dq(39)" )
			)
			( pin "U2D1.U34"
				( objectStatus "@baseboard_fab2_lib.baseboard_fab2(sch_1):page59_i172:ddr2_dq(40)" )
			)
			( pin "U2D1.AA34"
				( objectStatus "@baseboard_fab2_lib.baseboard_fab2(sch_1):page59_i172:ddr2_dq(41)" )
			)
			( pin "U2D1.V31"
				( objectStatus "@baseboard_fab2_lib.baseboard_fab2(sch_1):page59_i172:ddr2_dq(42)" )
			)
			( pin "U2D1.Y31"
				( objectStatus "@baseboard_fab2_lib.baseboard_fab2(sch_1):page59_i172:ddr2_dq(43)" )
			)
			( pin "U2D1.V35"
				( objectStatus "@baseboard_fab2_lib.baseboard_fab2(sch_1):page59_i172:ddr2_dq(44)" )
			)
			( pin "U2D1.Y35"
				( objectStatus "@baseboard_fab2_lib.baseboard_fab2(sch_1):page59_i172:ddr2_dq(45)" )
			)
			( pin "U2D1.U32"
				( objectStatus "@baseboard_fab2_lib.baseboard_fab2(sch_1):page59_i172:ddr2_dq(46)" )
			)
			( pin "U2D1.AA32"
				( objectStatus "@baseboard_fab2_lib.baseboard_fab2(sch_1):page59_i172:ddr2_dq(47)" )
			)
			( pin "U2D1.AD31"
				( objectStatus "@baseboard_fab2_lib.baseboard_fab2(sch_1):page59_i172:ddr2_dq(48)" )
			)
			( pin "U2D1.AH31"
				( objectStatus "@baseboard_fab2_lib.baseboard_fab2(sch_1):page59_i172:ddr2_dq(49)" )
			)
			( pin "U2D1.AE28"
				( objectStatus "@baseboard_fab2_lib.baseboard_fab2(sch_1):page59_i172:ddr2_dq(50)" )
			)
			( pin "U2D1.AG28"
				( objectStatus "@baseboard_fab2_lib.baseboard_fab2(sch_1):page59_i172:ddr2_dq(51)" )
			)
			( pin "U2D1.AE32"
				( objectStatus "@baseboard_fab2_lib.baseboard_fab2(sch_1):page59_i172:ddr2_dq(52)" )
			)
			( pin "U2D1.AG32"
				( objectStatus "@baseboard_fab2_lib.baseboard_fab2(sch_1):page59_i172:ddr2_dq(53)" )
			)
			( pin "U2D1.AD29"
				( objectStatus "@baseboard_fab2_lib.baseboard_fab2(sch_1):page59_i172:ddr2_dq(54)" )
			)
			( pin "U2D1.AH29"
				( objectStatus "@baseboard_fab2_lib.baseboard_fab2(sch_1):page59_i172:ddr2_dq(55)" )
			)
			( pin "U2D1.AD25"
				( objectStatus "@baseboard_fab2_lib.baseboard_fab2(sch_1):page59_i172:ddr2_dq(56)" )
			)
			( pin "U2D1.AH25"
				( objectStatus "@baseboard_fab2_lib.baseboard_fab2(sch_1):page59_i172:ddr2_dq(57)" )
			)
			( pin "U2D1.AE22"
				( objectStatus "@baseboard_fab2_lib.baseboard_fab2(sch_1):page59_i172:ddr2_dq(58)" )
			)
			( pin "U2D1.AG22"
				( objectStatus "@baseboard_fab2_lib.baseboard_fab2(sch_1):page59_i172:ddr2_dq(59)" )
			)
			( pin "U2D1.AE26"
				( objectStatus "@baseboard_fab2_lib.baseboard_fab2(sch_1):page59_i172:ddr2_dq(60)" )
			)
			( pin "U2D1.AG26"
				( objectStatus "@baseboard_fab2_lib.baseboard_fab2(sch_1):page59_i172:ddr2_dq(61)" )
			)
			( pin "U2D1.AD23"
				( objectStatus "@baseboard_fab2_lib.baseboard_fab2(sch_1):page59_i172:ddr2_dq(62)" )
			)
			( pin "U2D1.AH23"
				( objectStatus "@baseboard_fab2_lib.baseboard_fab2(sch_1):page59_i172:ddr2_dq(63)" )
			)
			( pin "U2D1.AL74"
				( objectStatus "@baseboard_fab2_lib.baseboard_fab2(sch_1):page59_i172:ddr2_dqs_dn(0)" )
			)
			( pin "U2D1.AA74"
				( objectStatus "@baseboard_fab2_lib.baseboard_fab2(sch_1):page59_i172:ddr2_dqs_dn(1)" )
			)
			( pin "U2D1.Y69"
				( objectStatus "@baseboard_fab2_lib.baseboard_fab2(sch_1):page59_i172:ddr2_dqs_dn(2)" )
			)
			( pin "U2D1.AU66"
				( objectStatus "@baseboard_fab2_lib.baseboard_fab2(sch_1):page59_i172:ddr2_dqs_dn(3)" )
			)
			( pin "U2D1.AB39"
				( objectStatus "@baseboard_fab2_lib.baseboard_fab2(sch_1):page59_i172:ddr2_dqs_dn(4)" )
			)
			( pin "U2D1.AB33"
				( objectStatus "@baseboard_fab2_lib.baseboard_fab2(sch_1):page59_i172:ddr2_dqs_dn(5)" )
			)
			( pin "U2D1.AJ30"
				( objectStatus "@baseboard_fab2_lib.baseboard_fab2(sch_1):page59_i172:ddr2_dqs_dn(6)" )
			)
			( pin "U2D1.AJ24"
				( objectStatus "@baseboard_fab2_lib.baseboard_fab2(sch_1):page59_i172:ddr2_dqs_dn(7)" )
			)
			( pin "U2D1.BB71"
				( objectStatus "@baseboard_fab2_lib.baseboard_fab2(sch_1):page59_i172:ddr2_dqs_dn(8)" )
			)
			( pin "U2D1.AP77"
				( objectStatus "@baseboard_fab2_lib.baseboard_fab2(sch_1):page59_i172:ddr2_dqs_dn(9)" )
			)
			( pin "U2D1.AD77"
				( objectStatus "@baseboard_fab2_lib.baseboard_fab2(sch_1):page59_i172:ddr2_dqs_dn(10)" )
			)
			( pin "U2D1.U72"
				( objectStatus "@baseboard_fab2_lib.baseboard_fab2(sch_1):page59_i172:ddr2_dqs_dn(11)" )
			)
			( pin "U2D1.AL66"
				( objectStatus "@baseboard_fab2_lib.baseboard_fab2(sch_1):page59_i172:ddr2_dqs_dn(12)" )
			)
			( pin "U2D1.T39"
				( objectStatus "@baseboard_fab2_lib.baseboard_fab2(sch_1):page59_i172:ddr2_dqs_dn(13)" )
			)
			( pin "U2D1.T33"
				( objectStatus "@baseboard_fab2_lib.baseboard_fab2(sch_1):page59_i172:ddr2_dqs_dn(14)" )
			)
			( pin "U2D1.AC30"
				( objectStatus "@baseboard_fab2_lib.baseboard_fab2(sch_1):page59_i172:ddr2_dqs_dn(15)" )
			)
			( pin "U2D1.AC24"
				( objectStatus "@baseboard_fab2_lib.baseboard_fab2(sch_1):page59_i172:ddr2_dqs_dn(16)" )
			)
			( pin "U2D1.AT71"
				( objectStatus "@baseboard_fab2_lib.baseboard_fab2(sch_1):page59_i172:ddr2_dqs_dn(17)" )
			)
			( pin "U2D1.AM75"
				( objectStatus "@baseboard_fab2_lib.baseboard_fab2(sch_1):page59_i172:ddr2_dqs_dp(0)" )
			)
			( pin "U2D1.AB75"
				( objectStatus "@baseboard_fab2_lib.baseboard_fab2(sch_1):page59_i172:ddr2_dqs_dp(1)" )
			)
			( pin "U2D1.W70"
				( objectStatus "@baseboard_fab2_lib.baseboard_fab2(sch_1):page59_i172:ddr2_dqs_dp(2)" )
			)
			( pin "U2D1.AR66"
				( objectStatus "@baseboard_fab2_lib.baseboard_fab2(sch_1):page59_i172:ddr2_dqs_dp(3)" )
			)
			( pin "U2D1.Y39"
				( objectStatus "@baseboard_fab2_lib.baseboard_fab2(sch_1):page59_i172:ddr2_dqs_dp(4)" )
			)
			( pin "U2D1.Y33"
				( objectStatus "@baseboard_fab2_lib.baseboard_fab2(sch_1):page59_i172:ddr2_dqs_dp(5)" )
			)
			( pin "U2D1.AG30"
				( objectStatus "@baseboard_fab2_lib.baseboard_fab2(sch_1):page59_i172:ddr2_dqs_dp(6)" )
			)
			( pin "U2D1.AG24"
				( objectStatus "@baseboard_fab2_lib.baseboard_fab2(sch_1):page59_i172:ddr2_dqs_dp(7)" )
			)
			( pin "U2D1.AY71"
				( objectStatus "@baseboard_fab2_lib.baseboard_fab2(sch_1):page59_i172:ddr2_dqs_dp(8)" )
			)
			( pin "U2D1.AN76"
				( objectStatus "@baseboard_fab2_lib.baseboard_fab2(sch_1):page59_i172:ddr2_dqs_dp(9)" )
			)
			( pin "U2D1.AC76"
				( objectStatus "@baseboard_fab2_lib.baseboard_fab2(sch_1):page59_i172:ddr2_dqs_dp(10)" )
			)
			( pin "U2D1.V71"
				( objectStatus "@baseboard_fab2_lib.baseboard_fab2(sch_1):page59_i172:ddr2_dqs_dp(11)" )
			)
			( pin "U2D1.AN66"
				( objectStatus "@baseboard_fab2_lib.baseboard_fab2(sch_1):page59_i172:ddr2_dqs_dp(12)" )
			)
			( pin "U2D1.V39"
				( objectStatus "@baseboard_fab2_lib.baseboard_fab2(sch_1):page59_i172:ddr2_dqs_dp(13)" )
			)
			( pin "U2D1.V33"
				( objectStatus "@baseboard_fab2_lib.baseboard_fab2(sch_1):page59_i172:ddr2_dqs_dp(14)" )
			)
			( pin "U2D1.AE30"
				( objectStatus "@baseboard_fab2_lib.baseboard_fab2(sch_1):page59_i172:ddr2_dqs_dp(15)" )
			)
			( pin "U2D1.AE24"
				( objectStatus "@baseboard_fab2_lib.baseboard_fab2(sch_1):page59_i172:ddr2_dqs_dp(16)" )
			)
			( pin "U2D1.AV71"
				( objectStatus "@baseboard_fab2_lib.baseboard_fab2(sch_1):page59_i172:ddr2_dqs_dp(17)" )
			)
			( pin "U2D1.AU72"
				( objectStatus "@baseboard_fab2_lib.baseboard_fab2(sch_1):page59_i172:ddr2_ecc(0)" )
			)
			( pin "U2D1.BA72"
				( objectStatus "@baseboard_fab2_lib.baseboard_fab2(sch_1):page59_i172:ddr2_ecc(1)" )
			)
			( pin "U2D1.AV69"
				( objectStatus "@baseboard_fab2_lib.baseboard_fab2(sch_1):page59_i172:ddr2_ecc(2)" )
			)
			( pin "U2D1.AY69"
				( objectStatus "@baseboard_fab2_lib.baseboard_fab2(sch_1):page59_i172:ddr2_ecc(3)" )
			)
			( pin "U2D1.AV73"
				( objectStatus "@baseboard_fab2_lib.baseboard_fab2(sch_1):page59_i172:ddr2_ecc(4)" )
			)
			( pin "U2D1.AY73"
				( objectStatus "@baseboard_fab2_lib.baseboard_fab2(sch_1):page59_i172:ddr2_ecc(5)" )
			)
			( pin "U2D1.AU70"
				( objectStatus "@baseboard_fab2_lib.baseboard_fab2(sch_1):page59_i172:ddr2_ecc(6)" )
			)
			( pin "U2D1.BA70"
				( objectStatus "@baseboard_fab2_lib.baseboard_fab2(sch_1):page59_i172:ddr2_ecc(7)" )
			)
			( pin "U2D1.AB53"
				( objectStatus "@baseboard_fab2_lib.baseboard_fab2(sch_1):page59_i172:ddr2_ma(0)" )
			)
			( pin "U2D1.AE58"
				( objectStatus "@baseboard_fab2_lib.baseboard_fab2(sch_1):page59_i172:ddr2_ma(1)" )
			)
			( pin "U2D1.AD57"
				( objectStatus "@baseboard_fab2_lib.baseboard_fab2(sch_1):page59_i172:ddr2_ma(2)" )
			)
			( pin "U2D1.W58"
				( objectStatus "@baseboard_fab2_lib.baseboard_fab2(sch_1):page59_i172:ddr2_ma(3)" )
			)
			( pin "U2D1.AA58"
				( objectStatus "@baseboard_fab2_lib.baseboard_fab2(sch_1):page59_i172:ddr2_ma(4)" )
			)
			( pin "U2D1.V59"
				( objectStatus "@baseboard_fab2_lib.baseboard_fab2(sch_1):page59_i172:ddr2_ma(5)" )
			)
			( pin "U2D1.AB59"
				( objectStatus "@baseboard_fab2_lib.baseboard_fab2(sch_1):page59_i172:ddr2_ma(6)" )
			)
			( pin "U2D1.AE60"
				( objectStatus "@baseboard_fab2_lib.baseboard_fab2(sch_1):page59_i172:ddr2_ma(7)" )
			)
			( pin "U2D1.AD59"
				( objectStatus "@baseboard_fab2_lib.baseboard_fab2(sch_1):page59_i172:ddr2_ma(8)" )
			)
			( pin "U2D1.AG58"
				( objectStatus "@baseboard_fab2_lib.baseboard_fab2(sch_1):page59_i172:ddr2_ma(9)" )
			)
			( pin "U2D1.AD55"
				( objectStatus "@baseboard_fab2_lib.baseboard_fab2(sch_1):page59_i172:ddr2_ma(10)" )
			)
			( pin "U2D1.AG60"
				( objectStatus "@baseboard_fab2_lib.baseboard_fab2(sch_1):page59_i172:ddr2_ma(11)" )
			)
			( pin "U2D1.AG62"
				( objectStatus "@baseboard_fab2_lib.baseboard_fab2(sch_1):page59_i172:ddr2_ma(12)" )
			)
			( pin "U2D1.AD53"
				( objectStatus "@baseboard_fab2_lib.baseboard_fab2(sch_1):page59_i172:ddr2_ma(13)" )
			)
			( pin "U2D1.W50"
				( objectStatus "@baseboard_fab2_lib.baseboard_fab2(sch_1):page59_i172:ddr2_ma(14)" )
			)
			( pin "U2D1.AE54"
				( objectStatus "@baseboard_fab2_lib.baseboard_fab2(sch_1):page59_i172:ddr2_ma(15)" )
			)
			( pin "U2D1.AA52"
				( objectStatus "@baseboard_fab2_lib.baseboard_fab2(sch_1):page59_i172:ddr2_ma(16)" )
			)
			( pin "U2D1.AC46"
				( objectStatus "@baseboard_fab2_lib.baseboard_fab2(sch_1):page59_i172:ddr2_ma(17)" )
			)
			( pin "U2D1.AA50"
				( objectStatus "@baseboard_fab2_lib.baseboard_fab2(sch_1):page59_i172:ddr2_odt(0)" )
			)
			( pin "U2D1.AA48"
				( objectStatus "@baseboard_fab2_lib.baseboard_fab2(sch_1):page59_i172:ddr2_odt(1)" )
			)
			( pin "U2D1.V49"
				( objectStatus "@baseboard_fab2_lib.baseboard_fab2(sch_1):page59_i172:ddr2_odt(2)" )
			)
			( pin "U2D1.AB47"
				( objectStatus "@baseboard_fab2_lib.baseboard_fab2(sch_1):page59_i172:ddr2_odt(3)" )
			)
			( pin "U2D1.V53"
				( objectStatus "@baseboard_fab2_lib.baseboard_fab2(sch_1):page59_i172:ddr2_par" )
			)
			( pin "U2D1.DW60"
				( objectStatus "@baseboard_fab2_lib.baseboard_fab2(sch_1):page60_i172:ddr3_act_n" )
			)
			( pin "U2D1.ED63"
				( objectStatus "@baseboard_fab2_lib.baseboard_fab2(sch_1):page60_i172:ddr3_alert_n" )
			)
			( pin "U2D1.EE52"
				( objectStatus "@baseboard_fab2_lib.baseboard_fab2(sch_1):page60_i172:ddr3_ba(0)" )
			)
			( pin "U2D1.EA54"
				( objectStatus "@baseboard_fab2_lib.baseboard_fab2(sch_1):page60_i172:ddr3_ba(1)" )
			)
			( pin "U2D1.ED61"
				( objectStatus "@baseboard_fab2_lib.baseboard_fab2(sch_1):page60_i172:ddr3_bg(0)" )
			)
			( pin "U2D1.DW62"
				( objectStatus "@baseboard_fab2_lib.baseboard_fab2(sch_1):page60_i172:ddr3_bg(1)" )
			)
			( pin "U2D1.DV47"
				( objectStatus "@baseboard_fab2_lib.baseboard_fab2(sch_1):page60_i172:ddr3_cid(2)" )
			)
			( pin "U2D1.EE62"
				( objectStatus "@baseboard_fab2_lib.baseboard_fab2(sch_1):page60_i172:ddr3_cke(0)" )
			)
			( pin "U2D1.EF63"
				( objectStatus "@baseboard_fab2_lib.baseboard_fab2(sch_1):page60_i172:ddr3_cke(1)" )
			)
			( pin "U2D1.EA62"
				( objectStatus "@baseboard_fab2_lib.baseboard_fab2(sch_1):page60_i172:ddr3_cke(2)" )
			)
			( pin "U2D1.EB63"
				( objectStatus "@baseboard_fab2_lib.baseboard_fab2(sch_1):page60_i172:ddr3_cke(3)" )
			)
			( pin "U2D1.ED55"
				( objectStatus "@baseboard_fab2_lib.baseboard_fab2(sch_1):page60_i172:ddr3_clk_dn(0)" )
			)
			( pin "U2D1.EF55"
				( objectStatus "@baseboard_fab2_lib.baseboard_fab2(sch_1):page60_i172:ddr3_clk_dn(1)" )
			)
			( pin "U2D1.DW56"
				( objectStatus "@baseboard_fab2_lib.baseboard_fab2(sch_1):page60_i172:ddr3_clk_dn(2)" )
			)
			( pin "U2D1.EF57"
				( objectStatus "@baseboard_fab2_lib.baseboard_fab2(sch_1):page60_i172:ddr3_clk_dn(3)" )
			)
			( pin "U2D1.EB55"
				( objectStatus "@baseboard_fab2_lib.baseboard_fab2(sch_1):page60_i172:ddr3_clk_dp(0)" )
			)
			( pin "U2D1.EE54"
				( objectStatus "@baseboard_fab2_lib.baseboard_fab2(sch_1):page60_i172:ddr3_clk_dp(1)" )
			)
			( pin "U2D1.EA56"
				( objectStatus "@baseboard_fab2_lib.baseboard_fab2(sch_1):page60_i172:ddr3_clk_dp(2)" )
			)
			( pin "U2D1.EE56"
				( objectStatus "@baseboard_fab2_lib.baseboard_fab2(sch_1):page60_i172:ddr3_clk_dp(3)" )
			)
			( pin "U2D1.EF51"
				( objectStatus "@baseboard_fab2_lib.baseboard_fab2(sch_1):page60_i172:ddr3_cs_n(0)" )
			)
			( pin "U2D1.ED49"
				( objectStatus "@baseboard_fab2_lib.baseboard_fab2(sch_1):page60_i172:ddr3_cs_n(1)" )
			)
			( pin "U2D1.ED47"
				( objectStatus "@baseboard_fab2_lib.baseboard_fab2(sch_1):page60_i172:ddr3_cs_n(2)" )
			)
			( pin "U2D1.EB47"
				( objectStatus "@baseboard_fab2_lib.baseboard_fab2(sch_1):page60_i172:ddr3_cs_n(3)" )
			)
			( pin "U2D1.EB51"
				( objectStatus "@baseboard_fab2_lib.baseboard_fab2(sch_1):page60_i172:ddr3_cs_n(4)" )
			)
			( pin "U2D1.EB49"
				( objectStatus "@baseboard_fab2_lib.baseboard_fab2(sch_1):page60_i172:ddr3_cs_n(5)" )
			)
			( pin "U2D1.DV45"
				( objectStatus "@baseboard_fab2_lib.baseboard_fab2(sch_1):page60_i172:ddr3_cs_n(6)" )
			)
			( pin "U2D1.EB45"
				( objectStatus "@baseboard_fab2_lib.baseboard_fab2(sch_1):page60_i172:ddr3_cs_n(7)" )
			)
			( pin "U2D1.CN84"
				( objectStatus "@baseboard_fab2_lib.baseboard_fab2(sch_1):page60_i172:ddr3_dq(0)" )
			)
			( pin "U2D1.CN86"
				( objectStatus "@baseboard_fab2_lib.baseboard_fab2(sch_1):page60_i172:ddr3_dq(1)" )
			)
			( pin "U2D1.DA86"
				( objectStatus "@baseboard_fab2_lib.baseboard_fab2(sch_1):page60_i172:ddr3_dq(2)" )
			)
			( pin "U2D1.DA84"
				( objectStatus "@baseboard_fab2_lib.baseboard_fab2(sch_1):page60_i172:ddr3_dq(3)" )
			)
			( pin "U2D1.CL84"
				( objectStatus "@baseboard_fab2_lib.baseboard_fab2(sch_1):page60_i172:ddr3_dq(4)" )
			)
			( pin "U2D1.CL86"
				( objectStatus "@baseboard_fab2_lib.baseboard_fab2(sch_1):page60_i172:ddr3_dq(5)" )
			)
			( pin "U2D1.CW86"
				( objectStatus "@baseboard_fab2_lib.baseboard_fab2(sch_1):page60_i172:ddr3_dq(6)" )
			)
			( pin "U2D1.CW84"
				( objectStatus "@baseboard_fab2_lib.baseboard_fab2(sch_1):page60_i172:ddr3_dq(7)" )
			)
			( pin "U2D1.DG84"
				( objectStatus "@baseboard_fab2_lib.baseboard_fab2(sch_1):page60_i172:ddr3_dq(8)" )
			)
			( pin "U2D1.DH85"
				( objectStatus "@baseboard_fab2_lib.baseboard_fab2(sch_1):page60_i172:ddr3_dq(9)" )
			)
			( pin "U2D1.DV83"
				( objectStatus "@baseboard_fab2_lib.baseboard_fab2(sch_1):page60_i172:ddr3_dq(10)" )
			)
			( pin "U2D1.DY83"
				( objectStatus "@baseboard_fab2_lib.baseboard_fab2(sch_1):page60_i172:ddr3_dq(11)" )
			)
			( pin "U2D1.DD85"
				( objectStatus "@baseboard_fab2_lib.baseboard_fab2(sch_1):page60_i172:ddr3_dq(12)" )
			)
			( pin "U2D1.DE84"
				( objectStatus "@baseboard_fab2_lib.baseboard_fab2(sch_1):page60_i172:ddr3_dq(13)" )
			)
			( pin "U2D1.DR84"
				( objectStatus "@baseboard_fab2_lib.baseboard_fab2(sch_1):page60_i172:ddr3_dq(14)" )
			)
			( pin "U2D1.DV85"
				( objectStatus "@baseboard_fab2_lib.baseboard_fab2(sch_1):page60_i172:ddr3_dq(15)" )
			)
			( pin "U2D1.DM79"
				( objectStatus "@baseboard_fab2_lib.baseboard_fab2(sch_1):page60_i172:ddr3_dq(16)" )
			)
			( pin "U2D1.DK81"
				( objectStatus "@baseboard_fab2_lib.baseboard_fab2(sch_1):page60_i172:ddr3_dq(17)" )
			)
			( pin "U2D1.DT81"
				( objectStatus "@baseboard_fab2_lib.baseboard_fab2(sch_1):page60_i172:ddr3_dq(18)" )
			)
			( pin "U2D1.DR82"
				( objectStatus "@baseboard_fab2_lib.baseboard_fab2(sch_1):page60_i172:ddr3_dq(19)" )
			)
			( pin "U2D1.DK79"
				( objectStatus "@baseboard_fab2_lib.baseboard_fab2(sch_1):page60_i172:ddr3_dq(20)" )
			)
			( pin "U2D1.DJ80"
				( objectStatus "@baseboard_fab2_lib.baseboard_fab2(sch_1):page60_i172:ddr3_dq(21)" )
			)
			( pin "U2D1.DR80"
				( objectStatus "@baseboard_fab2_lib.baseboard_fab2(sch_1):page60_i172:ddr3_dq(22)" )
			)
			( pin "U2D1.DN82"
				( objectStatus "@baseboard_fab2_lib.baseboard_fab2(sch_1):page60_i172:ddr3_dq(23)" )
			)
			( pin "U2D1.DN76"
				( objectStatus "@baseboard_fab2_lib.baseboard_fab2(sch_1):page60_i172:ddr3_dq(24)" )
			)
			( pin "U2D1.DU76"
				( objectStatus "@baseboard_fab2_lib.baseboard_fab2(sch_1):page60_i172:ddr3_dq(25)" )
			)
			( pin "U2D1.DP73"
				( objectStatus "@baseboard_fab2_lib.baseboard_fab2(sch_1):page60_i172:ddr3_dq(26)" )
			)
			( pin "U2D1.DT73"
				( objectStatus "@baseboard_fab2_lib.baseboard_fab2(sch_1):page60_i172:ddr3_dq(27)" )
			)
			( pin "U2D1.DP77"
				( objectStatus "@baseboard_fab2_lib.baseboard_fab2(sch_1):page60_i172:ddr3_dq(28)" )
			)
			( pin "U2D1.DT77"
				( objectStatus "@baseboard_fab2_lib.baseboard_fab2(sch_1):page60_i172:ddr3_dq(29)" )
			)
			( pin "U2D1.DN74"
				( objectStatus "@baseboard_fab2_lib.baseboard_fab2(sch_1):page60_i172:ddr3_dq(30)" )
			)
			( pin "U2D1.DU74"
				( objectStatus "@baseboard_fab2_lib.baseboard_fab2(sch_1):page60_i172:ddr3_dq(31)" )
			)
			( pin "U2D1.EC40"
				( objectStatus "@baseboard_fab2_lib.baseboard_fab2(sch_1):page60_i172:ddr3_dq(32)" )
			)
			( pin "U2D1.ED39"
				( objectStatus "@baseboard_fab2_lib.baseboard_fab2(sch_1):page60_i172:ddr3_dq(33)" )
			)
			( pin "U2D1.EA36"
				( objectStatus "@baseboard_fab2_lib.baseboard_fab2(sch_1):page60_i172:ddr3_dq(34)" )
			)
			( pin "U2D1.EC36"
				( objectStatus "@baseboard_fab2_lib.baseboard_fab2(sch_1):page60_i172:ddr3_dq(35)" )
			)
			( pin "U2D1.DY39"
				( objectStatus "@baseboard_fab2_lib.baseboard_fab2(sch_1):page60_i172:ddr3_dq(36)" )
			)
			( pin "U2D1.EA40"
				( objectStatus "@baseboard_fab2_lib.baseboard_fab2(sch_1):page60_i172:ddr3_dq(37)" )
			)
			( pin "U2D1.DY37"
				( objectStatus "@baseboard_fab2_lib.baseboard_fab2(sch_1):page60_i172:ddr3_dq(38)" )
			)
			( pin "U2D1.ED37"
				( objectStatus "@baseboard_fab2_lib.baseboard_fab2(sch_1):page60_i172:ddr3_dq(39)" )
			)
			( pin "U2D1.DN36"
				( objectStatus "@baseboard_fab2_lib.baseboard_fab2(sch_1):page60_i172:ddr3_dq(40)" )
			)
			( pin "U2D1.DU36"
				( objectStatus "@baseboard_fab2_lib.baseboard_fab2(sch_1):page60_i172:ddr3_dq(41)" )
			)
			( pin "U2D1.DP33"
				( objectStatus "@baseboard_fab2_lib.baseboard_fab2(sch_1):page60_i172:ddr3_dq(42)" )
			)
			( pin "U2D1.DT33"
				( objectStatus "@baseboard_fab2_lib.baseboard_fab2(sch_1):page60_i172:ddr3_dq(43)" )
			)
			( pin "U2D1.DP37"
				( objectStatus "@baseboard_fab2_lib.baseboard_fab2(sch_1):page60_i172:ddr3_dq(44)" )
			)
			( pin "U2D1.DT37"
				( objectStatus "@baseboard_fab2_lib.baseboard_fab2(sch_1):page60_i172:ddr3_dq(45)" )
			)
			( pin "U2D1.DN34"
				( objectStatus "@baseboard_fab2_lib.baseboard_fab2(sch_1):page60_i172:ddr3_dq(46)" )
			)
			( pin "U2D1.DU34"
				( objectStatus "@baseboard_fab2_lib.baseboard_fab2(sch_1):page60_i172:ddr3_dq(47)" )
			)
			( pin "U2D1.DN30"
				( objectStatus "@baseboard_fab2_lib.baseboard_fab2(sch_1):page60_i172:ddr3_dq(48)" )
			)
			( pin "U2D1.DU30"
				( objectStatus "@baseboard_fab2_lib.baseboard_fab2(sch_1):page60_i172:ddr3_dq(49)" )
			)
			( pin "U2D1.DP27"
				( objectStatus "@baseboard_fab2_lib.baseboard_fab2(sch_1):page60_i172:ddr3_dq(50)" )
			)
			( pin "U2D1.DT27"
				( objectStatus "@baseboard_fab2_lib.baseboard_fab2(sch_1):page60_i172:ddr3_dq(51)" )
			)
			( pin "U2D1.DP31"
				( objectStatus "@baseboard_fab2_lib.baseboard_fab2(sch_1):page60_i172:ddr3_dq(52)" )
			)
			( pin "U2D1.DT31"
				( objectStatus "@baseboard_fab2_lib.baseboard_fab2(sch_1):page60_i172:ddr3_dq(53)" )
			)
			( pin "U2D1.DN28"
				( objectStatus "@baseboard_fab2_lib.baseboard_fab2(sch_1):page60_i172:ddr3_dq(54)" )
			)
			( pin "U2D1.DU28"
				( objectStatus "@baseboard_fab2_lib.baseboard_fab2(sch_1):page60_i172:ddr3_dq(55)" )
			)
			( pin "U2D1.DN24"
				( objectStatus "@baseboard_fab2_lib.baseboard_fab2(sch_1):page60_i172:ddr3_dq(56)" )
			)
			( pin "U2D1.DU24"
				( objectStatus "@baseboard_fab2_lib.baseboard_fab2(sch_1):page60_i172:ddr3_dq(57)" )
			)
			( pin "U2D1.DY21"
				( objectStatus "@baseboard_fab2_lib.baseboard_fab2(sch_1):page60_i172:ddr3_dq(58)" )
			)
			( pin "U2D1.EB21"
				( objectStatus "@baseboard_fab2_lib.baseboard_fab2(sch_1):page60_i172:ddr3_dq(59)" )
			)
			( pin "U2D1.DP25"
				( objectStatus "@baseboard_fab2_lib.baseboard_fab2(sch_1):page60_i172:ddr3_dq(60)" )
			)
			( pin "U2D1.DT25"
				( objectStatus "@baseboard_fab2_lib.baseboard_fab2(sch_1):page60_i172:ddr3_dq(61)" )
			)
			( pin "U2D1.EC22"
				( objectStatus "@baseboard_fab2_lib.baseboard_fab2(sch_1):page60_i172:ddr3_dq(62)" )
			)
			( pin "U2D1.DW22"
				( objectStatus "@baseboard_fab2_lib.baseboard_fab2(sch_1):page60_i172:ddr3_dq(63)" )
			)
			( pin "U2D1.CU84"
				( objectStatus "@baseboard_fab2_lib.baseboard_fab2(sch_1):page60_i172:ddr3_dqs_dn(0)" )
			)
			( pin "U2D1.DN84"
				( objectStatus "@baseboard_fab2_lib.baseboard_fab2(sch_1):page60_i172:ddr3_dqs_dn(1)" )
			)
			( pin "U2D1.DL82"
				( objectStatus "@baseboard_fab2_lib.baseboard_fab2(sch_1):page60_i172:ddr3_dqs_dn(2)" )
			)
			( pin "U2D1.DV75"
				( objectStatus "@baseboard_fab2_lib.baseboard_fab2(sch_1):page60_i172:ddr3_dqs_dn(3)" )
			)
			( pin "U2D1.EE38"
				( objectStatus "@baseboard_fab2_lib.baseboard_fab2(sch_1):page60_i172:ddr3_dqs_dn(4)" )
			)
			( pin "U2D1.DV35"
				( objectStatus "@baseboard_fab2_lib.baseboard_fab2(sch_1):page60_i172:ddr3_dqs_dn(5)" )
			)
			( pin "U2D1.DV29"
				( objectStatus "@baseboard_fab2_lib.baseboard_fab2(sch_1):page60_i172:ddr3_dqs_dn(6)" )
			)
			( pin "U2D1.DV23"
				( objectStatus "@baseboard_fab2_lib.baseboard_fab2(sch_1):page60_i172:ddr3_dqs_dn(7)" )
			)
			( pin "U2D1.DF67"
				( objectStatus "@baseboard_fab2_lib.baseboard_fab2(sch_1):page60_i172:ddr3_dqs_dn(8)" )
			)
			( pin "U2D1.CR84"
				( objectStatus "@baseboard_fab2_lib.baseboard_fab2(sch_1):page60_i172:ddr3_dqs_dn(9)" )
			)
			( pin "U2D1.DM85"
				( objectStatus "@baseboard_fab2_lib.baseboard_fab2(sch_1):page60_i172:ddr3_dqs_dn(10)" )
			)
			( pin "U2D1.DN80"
				( objectStatus "@baseboard_fab2_lib.baseboard_fab2(sch_1):page60_i172:ddr3_dqs_dn(11)" )
			)
			( pin "U2D1.DP75"
				( objectStatus "@baseboard_fab2_lib.baseboard_fab2(sch_1):page60_i172:ddr3_dqs_dn(12)" )
			)
			( pin "U2D1.EA38"
				( objectStatus "@baseboard_fab2_lib.baseboard_fab2(sch_1):page60_i172:ddr3_dqs_dn(13)" )
			)
			( pin "U2D1.DP35"
				( objectStatus "@baseboard_fab2_lib.baseboard_fab2(sch_1):page60_i172:ddr3_dqs_dn(14)" )
			)
			( pin "U2D1.DM29"
				( objectStatus "@baseboard_fab2_lib.baseboard_fab2(sch_1):page60_i172:ddr3_dqs_dn(15)" )
			)
			( pin "U2D1.DM23"
				( objectStatus "@baseboard_fab2_lib.baseboard_fab2(sch_1):page60_i172:ddr3_dqs_dn(16)" )
			)
			( pin "U2D1.DB67"
				( objectStatus "@baseboard_fab2_lib.baseboard_fab2(sch_1):page60_i172:ddr3_dqs_dn(17)" )
			)
			( pin "U2D1.CV85"
				( objectStatus "@baseboard_fab2_lib.baseboard_fab2(sch_1):page60_i172:ddr3_dqs_dp(0)" )
			)
			( pin "U2D1.DP85"
				( objectStatus "@baseboard_fab2_lib.baseboard_fab2(sch_1):page60_i172:ddr3_dqs_dp(1)" )
			)
			( pin "U2D1.DM81"
				( objectStatus "@baseboard_fab2_lib.baseboard_fab2(sch_1):page60_i172:ddr3_dqs_dp(2)" )
			)
			( pin "U2D1.DT75"
				( objectStatus "@baseboard_fab2_lib.baseboard_fab2(sch_1):page60_i172:ddr3_dqs_dp(3)" )
			)
			( pin "U2D1.EC38"
				( objectStatus "@baseboard_fab2_lib.baseboard_fab2(sch_1):page60_i172:ddr3_dqs_dp(4)" )
			)
			( pin "U2D1.DT35"
				( objectStatus "@baseboard_fab2_lib.baseboard_fab2(sch_1):page60_i172:ddr3_dqs_dp(5)" )
			)
			( pin "U2D1.DT29"
				( objectStatus "@baseboard_fab2_lib.baseboard_fab2(sch_1):page60_i172:ddr3_dqs_dp(6)" )
			)
			( pin "U2D1.DT23"
				( objectStatus "@baseboard_fab2_lib.baseboard_fab2(sch_1):page60_i172:ddr3_dqs_dp(7)" )
			)
			( pin "U2D1.DD67"
				( objectStatus "@baseboard_fab2_lib.baseboard_fab2(sch_1):page60_i172:ddr3_dqs_dp(8)" )
			)
			( pin "U2D1.CP85"
				( objectStatus "@baseboard_fab2_lib.baseboard_fab2(sch_1):page60_i172:ddr3_dqs_dp(9)" )
			)
			( pin "U2D1.DL84"
				( objectStatus "@baseboard_fab2_lib.baseboard_fab2(sch_1):page60_i172:ddr3_dqs_dp(10)" )
			)
			( pin "U2D1.DP79"
				( objectStatus "@baseboard_fab2_lib.baseboard_fab2(sch_1):page60_i172:ddr3_dqs_dp(11)" )
			)
			( pin "U2D1.DM75"
				( objectStatus "@baseboard_fab2_lib.baseboard_fab2(sch_1):page60_i172:ddr3_dqs_dp(12)" )
			)
			( pin "U2D1.DW38"
				( objectStatus "@baseboard_fab2_lib.baseboard_fab2(sch_1):page60_i172:ddr3_dqs_dp(13)" )
			)
			( pin "U2D1.DM35"
				( objectStatus "@baseboard_fab2_lib.baseboard_fab2(sch_1):page60_i172:ddr3_dqs_dp(14)" )
			)
			( pin "U2D1.DP29"
				( objectStatus "@baseboard_fab2_lib.baseboard_fab2(sch_1):page60_i172:ddr3_dqs_dp(15)" )
			)
			( pin "U2D1.DP23"
				( objectStatus "@baseboard_fab2_lib.baseboard_fab2(sch_1):page60_i172:ddr3_dqs_dp(16)" )
			)
			( pin "U2D1.CY67"
				( objectStatus "@baseboard_fab2_lib.baseboard_fab2(sch_1):page60_i172:ddr3_dqs_dp(17)" )
			)
			( pin "U2D1.DA68"
				( objectStatus "@baseboard_fab2_lib.baseboard_fab2(sch_1):page60_i172:ddr3_ecc(0)" )
			)
			( pin "U2D1.DE68"
				( objectStatus "@baseboard_fab2_lib.baseboard_fab2(sch_1):page60_i172:ddr3_ecc(1)" )
			)
			( pin "U2D1.DB65"
				( objectStatus "@baseboard_fab2_lib.baseboard_fab2(sch_1):page60_i172:ddr3_ecc(2)" )
			)
			( pin "U2D1.DD65"
				( objectStatus "@baseboard_fab2_lib.baseboard_fab2(sch_1):page60_i172:ddr3_ecc(3)" )
			)
			( pin "U2D1.DB69"
				( objectStatus "@baseboard_fab2_lib.baseboard_fab2(sch_1):page60_i172:ddr3_ecc(4)" )
			)
			( pin "U2D1.DD69"
				( objectStatus "@baseboard_fab2_lib.baseboard_fab2(sch_1):page60_i172:ddr3_ecc(5)" )
			)
			( pin "U2D1.DA66"
				( objectStatus "@baseboard_fab2_lib.baseboard_fab2(sch_1):page60_i172:ddr3_ecc(6)" )
			)
			( pin "U2D1.DE66"
				( objectStatus "@baseboard_fab2_lib.baseboard_fab2(sch_1):page60_i172:ddr3_ecc(7)" )
			)
			( pin "U2D1.EB53"
				( objectStatus "@baseboard_fab2_lib.baseboard_fab2(sch_1):page60_i172:ddr3_ma(0)" )
			)
			( pin "U2D1.ED57"
				( objectStatus "@baseboard_fab2_lib.baseboard_fab2(sch_1):page60_i172:ddr3_ma(1)" )
			)
			( pin "U2D1.EE58"
				( objectStatus "@baseboard_fab2_lib.baseboard_fab2(sch_1):page60_i172:ddr3_ma(2)" )
			)
			( pin "U2D1.EB57"
				( objectStatus "@baseboard_fab2_lib.baseboard_fab2(sch_1):page60_i172:ddr3_ma(3)" )
			)
			( pin "U2D1.ED59"
				( objectStatus "@baseboard_fab2_lib.baseboard_fab2(sch_1):page60_i172:ddr3_ma(4)" )
			)
			( pin "U2D1.EA58"
				( objectStatus "@baseboard_fab2_lib.baseboard_fab2(sch_1):page60_i172:ddr3_ma(5)" )
			)
			( pin "U2D1.EE60"
				( objectStatus "@baseboard_fab2_lib.baseboard_fab2(sch_1):page60_i172:ddr3_ma(6)" )
			)
			( pin "U2D1.EA60"
				( objectStatus "@baseboard_fab2_lib.baseboard_fab2(sch_1):page60_i172:ddr3_ma(7)" )
			)
			( pin "U2D1.EB59"
				( objectStatus "@baseboard_fab2_lib.baseboard_fab2(sch_1):page60_i172:ddr3_ma(8)" )
			)
			( pin "U2D1.EF61"
				( objectStatus "@baseboard_fab2_lib.baseboard_fab2(sch_1):page60_i172:ddr3_ma(9)" )
			)
			( pin "U2D1.DW54"
				( objectStatus "@baseboard_fab2_lib.baseboard_fab2(sch_1):page60_i172:ddr3_ma(10)" )
			)
			( pin "U2D1.EB61"
				( objectStatus "@baseboard_fab2_lib.baseboard_fab2(sch_1):page60_i172:ddr3_ma(11)" )
			)
			( pin "U2D1.DT63"
				( objectStatus "@baseboard_fab2_lib.baseboard_fab2(sch_1):page60_i172:ddr3_ma(12)" )
			)
			( pin "U2D1.DW48"
				( objectStatus "@baseboard_fab2_lib.baseboard_fab2(sch_1):page60_i172:ddr3_ma(13)" )
			)
			( pin "U2D1.ED51"
				( objectStatus "@baseboard_fab2_lib.baseboard_fab2(sch_1):page60_i172:ddr3_ma(14)" )
			)
			( pin "U2D1.DV49"
				( objectStatus "@baseboard_fab2_lib.baseboard_fab2(sch_1):page60_i172:ddr3_ma(15)" )
			)
			( pin "U2D1.EA52"
				( objectStatus "@baseboard_fab2_lib.baseboard_fab2(sch_1):page60_i172:ddr3_ma(16)" )
			)
			( pin "U2D1.EA46"
				( objectStatus "@baseboard_fab2_lib.baseboard_fab2(sch_1):page60_i172:ddr3_ma(17)" )
			)
			( pin "U2D1.EE50"
				( objectStatus "@baseboard_fab2_lib.baseboard_fab2(sch_1):page60_i172:ddr3_odt(0)" )
			)
			( pin "U2D1.EE48"
				( objectStatus "@baseboard_fab2_lib.baseboard_fab2(sch_1):page60_i172:ddr3_odt(1)" )
			)
			( pin "U2D1.EA50"
				( objectStatus "@baseboard_fab2_lib.baseboard_fab2(sch_1):page60_i172:ddr3_odt(2)" )
			)
			( pin "U2D1.EA48"
				( objectStatus "@baseboard_fab2_lib.baseboard_fab2(sch_1):page60_i172:ddr3_odt(3)" )
			)
			( pin "U2D1.ED53"
				( objectStatus "@baseboard_fab2_lib.baseboard_fab2(sch_1):page60_i172:ddr3_par" )
			)
			( pin "U2D1.DR62"
				( objectStatus "@baseboard_fab2_lib.baseboard_fab2(sch_1):page61_i172:ddr4_act_n" )
			)
			( pin "U2D1.DT61"
				( objectStatus "@baseboard_fab2_lib.baseboard_fab2(sch_1):page61_i172:ddr4_alert_n" )
			)
			( pin "U2D1.DM53"
				( objectStatus "@baseboard_fab2_lib.baseboard_fab2(sch_1):page61_i172:ddr4_ba(0)" )
			)
			( pin "U2D1.DV55"
				( objectStatus "@baseboard_fab2_lib.baseboard_fab2(sch_1):page61_i172:ddr4_ba(1)" )
			)
			( pin "U2D1.DJ62"
				( objectStatus "@baseboard_fab2_lib.baseboard_fab2(sch_1):page61_i172:ddr4_bg(0)" )
			)
			( pin "U2D1.DM61"
				( objectStatus "@baseboard_fab2_lib.baseboard_fab2(sch_1):page61_i172:ddr4_bg(1)" )
			)
			( pin "U2D1.DT47"
				( objectStatus "@baseboard_fab2_lib.baseboard_fab2(sch_1):page61_i172:ddr4_cid(2)" )
			)
			( pin "U2D1.DM63"
				( objectStatus "@baseboard_fab2_lib.baseboard_fab2(sch_1):page61_i172:ddr4_cke(0)" )
			)
			( pin "U2D1.DN64"
				( objectStatus "@baseboard_fab2_lib.baseboard_fab2(sch_1):page61_i172:ddr4_cke(1)" )
			)
			( pin "U2D1.DL64"
				( objectStatus "@baseboard_fab2_lib.baseboard_fab2(sch_1):page61_i172:ddr4_cke(2)" )
			)
			( pin "U2D1.DR64"
				( objectStatus "@baseboard_fab2_lib.baseboard_fab2(sch_1):page61_i172:ddr4_cke(3)" )
			)
			( pin "U2D1.DM55"
				( objectStatus "@baseboard_fab2_lib.baseboard_fab2(sch_1):page61_i172:ddr4_clk_dn(0)" )
			)
			( pin "U2D1.DR54"
				( objectStatus "@baseboard_fab2_lib.baseboard_fab2(sch_1):page61_i172:ddr4_clk_dn(1)" )
			)
			( pin "U2D1.DM57"
				( objectStatus "@baseboard_fab2_lib.baseboard_fab2(sch_1):page61_i172:ddr4_clk_dn(2)" )
			)
			( pin "U2D1.DT57"
				( objectStatus "@baseboard_fab2_lib.baseboard_fab2(sch_1):page61_i172:ddr4_clk_dn(3)" )
			)
			( pin "U2D1.DN54"
				( objectStatus "@baseboard_fab2_lib.baseboard_fab2(sch_1):page61_i172:ddr4_clk_dp(0)" )
			)
			( pin "U2D1.DT53"
				( objectStatus "@baseboard_fab2_lib.baseboard_fab2(sch_1):page61_i172:ddr4_clk_dp(1)" )
			)
			( pin "U2D1.DN56"
				( objectStatus "@baseboard_fab2_lib.baseboard_fab2(sch_1):page61_i172:ddr4_clk_dp(2)" )
			)
			( pin "U2D1.DR56"
				( objectStatus "@baseboard_fab2_lib.baseboard_fab2(sch_1):page61_i172:ddr4_clk_dp(3)" )
			)
			( pin "U2D1.DV51"
				( objectStatus "@baseboard_fab2_lib.baseboard_fab2(sch_1):page61_i172:ddr4_cs_n(0)" )
			)
			( pin "U2D1.DN50"
				( objectStatus "@baseboard_fab2_lib.baseboard_fab2(sch_1):page61_i172:ddr4_cs_n(1)" )
			)
			( pin "U2D1.DR46"
				( objectStatus "@baseboard_fab2_lib.baseboard_fab2(sch_1):page61_i172:ddr4_cs_n(2)" )
			)
			( pin "U2D1.DK47"
				( objectStatus "@baseboard_fab2_lib.baseboard_fab2(sch_1):page61_i172:ddr4_cs_n(3)" )
			)
			( pin "U2D1.DW50"
				( objectStatus "@baseboard_fab2_lib.baseboard_fab2(sch_1):page61_i172:ddr4_cs_n(4)" )
			)
			( pin "U2D1.DM49"
				( objectStatus "@baseboard_fab2_lib.baseboard_fab2(sch_1):page61_i172:ddr4_cs_n(5)" )
			)
			( pin "U2D1.DT45"
				( objectStatus "@baseboard_fab2_lib.baseboard_fab2(sch_1):page61_i172:ddr4_cs_n(6)" )
			)
			( pin "U2D1.DN46"
				( objectStatus "@baseboard_fab2_lib.baseboard_fab2(sch_1):page61_i172:ddr4_cs_n(7)" )
			)
			( pin "U2D1.CM79"
				( objectStatus "@baseboard_fab2_lib.baseboard_fab2(sch_1):page61_i172:ddr4_dq(0)" )
			)
			( pin "U2D1.CK81"
				( objectStatus "@baseboard_fab2_lib.baseboard_fab2(sch_1):page61_i172:ddr4_dq(1)" )
			)
			( pin "U2D1.CT81"
				( objectStatus "@baseboard_fab2_lib.baseboard_fab2(sch_1):page61_i172:ddr4_dq(2)" )
			)
			( pin "U2D1.CR82"
				( objectStatus "@baseboard_fab2_lib.baseboard_fab2(sch_1):page61_i172:ddr4_dq(3)" )
			)
			( pin "U2D1.CK79"
				( objectStatus "@baseboard_fab2_lib.baseboard_fab2(sch_1):page61_i172:ddr4_dq(4)" )
			)
			( pin "U2D1.CJ80"
				( objectStatus "@baseboard_fab2_lib.baseboard_fab2(sch_1):page61_i172:ddr4_dq(5)" )
			)
			( pin "U2D1.CR80"
				( objectStatus "@baseboard_fab2_lib.baseboard_fab2(sch_1):page61_i172:ddr4_dq(6)" )
			)
			( pin "U2D1.CN82"
				( objectStatus "@baseboard_fab2_lib.baseboard_fab2(sch_1):page61_i172:ddr4_dq(7)" )
			)
			( pin "U2D1.DB79"
				( objectStatus "@baseboard_fab2_lib.baseboard_fab2(sch_1):page61_i172:ddr4_dq(8)" )
			)
			( pin "U2D1.CY81"
				( objectStatus "@baseboard_fab2_lib.baseboard_fab2(sch_1):page61_i172:ddr4_dq(9)" )
			)
			( pin "U2D1.DE80"
				( objectStatus "@baseboard_fab2_lib.baseboard_fab2(sch_1):page61_i172:ddr4_dq(10)" )
			)
			( pin "U2D1.DF81"
				( objectStatus "@baseboard_fab2_lib.baseboard_fab2(sch_1):page61_i172:ddr4_dq(11)" )
			)
			( pin "U2D1.CY79"
				( objectStatus "@baseboard_fab2_lib.baseboard_fab2(sch_1):page61_i172:ddr4_dq(12)" )
			)
			( pin "U2D1.CW80"
				( objectStatus "@baseboard_fab2_lib.baseboard_fab2(sch_1):page61_i172:ddr4_dq(13)" )
			)
			( pin "U2D1.DC82"
				( objectStatus "@baseboard_fab2_lib.baseboard_fab2(sch_1):page61_i172:ddr4_dq(14)" )
			)
			( pin "U2D1.DE82"
				( objectStatus "@baseboard_fab2_lib.baseboard_fab2(sch_1):page61_i172:ddr4_dq(15)" )
			)
			( pin "U2D1.DW80"
				( objectStatus "@baseboard_fab2_lib.baseboard_fab2(sch_1):page61_i172:ddr4_dq(16)" )
			)
			( pin "U2D1.EC80"
				( objectStatus "@baseboard_fab2_lib.baseboard_fab2(sch_1):page61_i172:ddr4_dq(17)" )
			)
			( pin "U2D1.DY77"
				( objectStatus "@baseboard_fab2_lib.baseboard_fab2(sch_1):page61_i172:ddr4_dq(18)" )
			)
			( pin "U2D1.EB77"
				( objectStatus "@baseboard_fab2_lib.baseboard_fab2(sch_1):page61_i172:ddr4_dq(19)" )
			)
			( pin "U2D1.DY81"
				( objectStatus "@baseboard_fab2_lib.baseboard_fab2(sch_1):page61_i172:ddr4_dq(20)" )
			)
			( pin "U2D1.EB81"
				( objectStatus "@baseboard_fab2_lib.baseboard_fab2(sch_1):page61_i172:ddr4_dq(21)" )
			)
			( pin "U2D1.DW78"
				( objectStatus "@baseboard_fab2_lib.baseboard_fab2(sch_1):page61_i172:ddr4_dq(22)" )
			)
			( pin "U2D1.EC78"
				( objectStatus "@baseboard_fab2_lib.baseboard_fab2(sch_1):page61_i172:ddr4_dq(23)" )
			)
			( pin "U2D1.ED75"
				( objectStatus "@baseboard_fab2_lib.baseboard_fab2(sch_1):page61_i172:ddr4_dq(24)" )
			)
			( pin "U2D1.EE74"
				( objectStatus "@baseboard_fab2_lib.baseboard_fab2(sch_1):page61_i172:ddr4_dq(25)" )
			)
			( pin "U2D1.EB71"
				( objectStatus "@baseboard_fab2_lib.baseboard_fab2(sch_1):page61_i172:ddr4_dq(26)" )
			)
			( pin "U2D1.ED71"
				( objectStatus "@baseboard_fab2_lib.baseboard_fab2(sch_1):page61_i172:ddr4_dq(27)" )
			)
			( pin "U2D1.EA74"
				( objectStatus "@baseboard_fab2_lib.baseboard_fab2(sch_1):page61_i172:ddr4_dq(28)" )
			)
			( pin "U2D1.EB75"
				( objectStatus "@baseboard_fab2_lib.baseboard_fab2(sch_1):page61_i172:ddr4_dq(29)" )
			)
			( pin "U2D1.EA72"
				( objectStatus "@baseboard_fab2_lib.baseboard_fab2(sch_1):page61_i172:ddr4_dq(30)" )
			)
			( pin "U2D1.EE72"
				( objectStatus "@baseboard_fab2_lib.baseboard_fab2(sch_1):page61_i172:ddr4_dq(31)" )
			)
			( pin "U2D1.DU42"
				( objectStatus "@baseboard_fab2_lib.baseboard_fab2(sch_1):page61_i172:ddr4_dq(32)" )
			)
			( pin "U2D1.DW42"
				( objectStatus "@baseboard_fab2_lib.baseboard_fab2(sch_1):page61_i172:ddr4_dq(33)" )
			)
			( pin "U2D1.DP39"
				( objectStatus "@baseboard_fab2_lib.baseboard_fab2(sch_1):page61_i172:ddr4_dq(34)" )
			)
			( pin "U2D1.DT39"
				( objectStatus "@baseboard_fab2_lib.baseboard_fab2(sch_1):page61_i172:ddr4_dq(35)" )
			)
			( pin "U2D1.DL42"
				( objectStatus "@baseboard_fab2_lib.baseboard_fab2(sch_1):page61_i172:ddr4_dq(36)" )
			)
			( pin "U2D1.DN42"
				( objectStatus "@baseboard_fab2_lib.baseboard_fab2(sch_1):page61_i172:ddr4_dq(37)" )
			)
			( pin "U2D1.DN40"
				( objectStatus "@baseboard_fab2_lib.baseboard_fab2(sch_1):page61_i172:ddr4_dq(38)" )
			)
			( pin "U2D1.DU40"
				( objectStatus "@baseboard_fab2_lib.baseboard_fab2(sch_1):page61_i172:ddr4_dq(39)" )
			)
			( pin "U2D1.EC34"
				( objectStatus "@baseboard_fab2_lib.baseboard_fab2(sch_1):page61_i172:ddr4_dq(40)" )
			)
			( pin "U2D1.ED33"
				( objectStatus "@baseboard_fab2_lib.baseboard_fab2(sch_1):page61_i172:ddr4_dq(41)" )
			)
			( pin "U2D1.EA30"
				( objectStatus "@baseboard_fab2_lib.baseboard_fab2(sch_1):page61_i172:ddr4_dq(42)" )
			)
			( pin "U2D1.EC30"
				( objectStatus "@baseboard_fab2_lib.baseboard_fab2(sch_1):page61_i172:ddr4_dq(43)" )
			)
			( pin "U2D1.DY33"
				( objectStatus "@baseboard_fab2_lib.baseboard_fab2(sch_1):page61_i172:ddr4_dq(44)" )
			)
			( pin "U2D1.EA34"
				( objectStatus "@baseboard_fab2_lib.baseboard_fab2(sch_1):page61_i172:ddr4_dq(45)" )
			)
			( pin "U2D1.DY31"
				( objectStatus "@baseboard_fab2_lib.baseboard_fab2(sch_1):page61_i172:ddr4_dq(46)" )
			)
			( pin "U2D1.ED31"
				( objectStatus "@baseboard_fab2_lib.baseboard_fab2(sch_1):page61_i172:ddr4_dq(47)" )
			)
			( pin "U2D1.EC28"
				( objectStatus "@baseboard_fab2_lib.baseboard_fab2(sch_1):page61_i172:ddr4_dq(48)" )
			)
			( pin "U2D1.ED27"
				( objectStatus "@baseboard_fab2_lib.baseboard_fab2(sch_1):page61_i172:ddr4_dq(49)" )
			)
			( pin "U2D1.EA24"
				( objectStatus "@baseboard_fab2_lib.baseboard_fab2(sch_1):page61_i172:ddr4_dq(50)" )
			)
			( pin "U2D1.EC24"
				( objectStatus "@baseboard_fab2_lib.baseboard_fab2(sch_1):page61_i172:ddr4_dq(51)" )
			)
			( pin "U2D1.DY27"
				( objectStatus "@baseboard_fab2_lib.baseboard_fab2(sch_1):page61_i172:ddr4_dq(52)" )
			)
			( pin "U2D1.EA28"
				( objectStatus "@baseboard_fab2_lib.baseboard_fab2(sch_1):page61_i172:ddr4_dq(53)" )
			)
			( pin "U2D1.DY25"
				( objectStatus "@baseboard_fab2_lib.baseboard_fab2(sch_1):page61_i172:ddr4_dq(54)" )
			)
			( pin "U2D1.ED25"
				( objectStatus "@baseboard_fab2_lib.baseboard_fab2(sch_1):page61_i172:ddr4_dq(55)" )
			)
			( pin "U2D1.DF27"
				( objectStatus "@baseboard_fab2_lib.baseboard_fab2(sch_1):page61_i172:ddr4_dq(56)" )
			)
			( pin "U2D1.DK27"
				( objectStatus "@baseboard_fab2_lib.baseboard_fab2(sch_1):page61_i172:ddr4_dq(57)" )
			)
			( pin "U2D1.DD25"
				( objectStatus "@baseboard_fab2_lib.baseboard_fab2(sch_1):page61_i172:ddr4_dq(58)" )
			)
			( pin "U2D1.DJ24"
				( objectStatus "@baseboard_fab2_lib.baseboard_fab2(sch_1):page61_i172:ddr4_dq(59)" )
			)
			( pin "U2D1.DG28"
				( objectStatus "@baseboard_fab2_lib.baseboard_fab2(sch_1):page61_i172:ddr4_dq(60)" )
			)
			( pin "U2D1.DJ28"
				( objectStatus "@baseboard_fab2_lib.baseboard_fab2(sch_1):page61_i172:ddr4_dq(61)" )
			)
			( pin "U2D1.DF25"
				( objectStatus "@baseboard_fab2_lib.baseboard_fab2(sch_1):page61_i172:ddr4_dq(62)" )
			)
			( pin "U2D1.DK25"
				( objectStatus "@baseboard_fab2_lib.baseboard_fab2(sch_1):page61_i172:ddr4_dq(63)" )
			)
			( pin "U2D1.CL82"
				( objectStatus "@baseboard_fab2_lib.baseboard_fab2(sch_1):page61_i172:ddr4_dqs_dn(0)" )
			)
			( pin "U2D1.DA82"
				( objectStatus "@baseboard_fab2_lib.baseboard_fab2(sch_1):page61_i172:ddr4_dqs_dn(1)" )
			)
			( pin "U2D1.ED79"
				( objectStatus "@baseboard_fab2_lib.baseboard_fab2(sch_1):page61_i172:ddr4_dqs_dn(2)" )
			)
			( pin "U2D1.EF73"
				( objectStatus "@baseboard_fab2_lib.baseboard_fab2(sch_1):page61_i172:ddr4_dqs_dn(3)" )
			)
			( pin "U2D1.DV41"
				( objectStatus "@baseboard_fab2_lib.baseboard_fab2(sch_1):page61_i172:ddr4_dqs_dn(4)" )
			)
			( pin "U2D1.EE32"
				( objectStatus "@baseboard_fab2_lib.baseboard_fab2(sch_1):page61_i172:ddr4_dqs_dn(5)" )
			)
			( pin "U2D1.EE26"
				( objectStatus "@baseboard_fab2_lib.baseboard_fab2(sch_1):page61_i172:ddr4_dqs_dn(6)" )
			)
			( pin "U2D1.DL26"
				( objectStatus "@baseboard_fab2_lib.baseboard_fab2(sch_1):page61_i172:ddr4_dqs_dn(7)" )
			)
			( pin "U2D1.EB67"
				( objectStatus "@baseboard_fab2_lib.baseboard_fab2(sch_1):page61_i172:ddr4_dqs_dn(8)" )
			)
			( pin "U2D1.CN80"
				( objectStatus "@baseboard_fab2_lib.baseboard_fab2(sch_1):page61_i172:ddr4_dqs_dn(9)" )
			)
			( pin "U2D1.DC80"
				( objectStatus "@baseboard_fab2_lib.baseboard_fab2(sch_1):page61_i172:ddr4_dqs_dn(10)" )
			)
			( pin "U2D1.DY79"
				( objectStatus "@baseboard_fab2_lib.baseboard_fab2(sch_1):page61_i172:ddr4_dqs_dn(11)" )
			)
			( pin "U2D1.EB73"
				( objectStatus "@baseboard_fab2_lib.baseboard_fab2(sch_1):page61_i172:ddr4_dqs_dn(12)" )
			)
			( pin "U2D1.DP41"
				( objectStatus "@baseboard_fab2_lib.baseboard_fab2(sch_1):page61_i172:ddr4_dqs_dn(13)" )
			)
			( pin "U2D1.EA32"
				( objectStatus "@baseboard_fab2_lib.baseboard_fab2(sch_1):page61_i172:ddr4_dqs_dn(14)" )
			)
			( pin "U2D1.EA26"
				( objectStatus "@baseboard_fab2_lib.baseboard_fab2(sch_1):page61_i172:ddr4_dqs_dn(15)" )
			)
			( pin "U2D1.DG26"
				( objectStatus "@baseboard_fab2_lib.baseboard_fab2(sch_1):page61_i172:ddr4_dqs_dn(16)" )
			)
			( pin "U2D1.DV67"
				( objectStatus "@baseboard_fab2_lib.baseboard_fab2(sch_1):page61_i172:ddr4_dqs_dn(17)" )
			)
			( pin "U2D1.CM81"
				( objectStatus "@baseboard_fab2_lib.baseboard_fab2(sch_1):page61_i172:ddr4_dqs_dp(0)" )
			)
			( pin "U2D1.DB81"
				( objectStatus "@baseboard_fab2_lib.baseboard_fab2(sch_1):page61_i172:ddr4_dqs_dp(1)" )
			)
			( pin "U2D1.EB79"
				( objectStatus "@baseboard_fab2_lib.baseboard_fab2(sch_1):page61_i172:ddr4_dqs_dp(2)" )
			)
			( pin "U2D1.ED73"
				( objectStatus "@baseboard_fab2_lib.baseboard_fab2(sch_1):page61_i172:ddr4_dqs_dp(3)" )
			)
			( pin "U2D1.DT41"
				( objectStatus "@baseboard_fab2_lib.baseboard_fab2(sch_1):page61_i172:ddr4_dqs_dp(4)" )
			)
			( pin "U2D1.EC32"
				( objectStatus "@baseboard_fab2_lib.baseboard_fab2(sch_1):page61_i172:ddr4_dqs_dp(5)" )
			)
			( pin "U2D1.EC26"
				( objectStatus "@baseboard_fab2_lib.baseboard_fab2(sch_1):page61_i172:ddr4_dqs_dp(6)" )
			)
			( pin "U2D1.DJ26"
				( objectStatus "@baseboard_fab2_lib.baseboard_fab2(sch_1):page61_i172:ddr4_dqs_dp(7)" )
			)
			( pin "U2D1.DY67"
				( objectStatus "@baseboard_fab2_lib.baseboard_fab2(sch_1):page61_i172:ddr4_dqs_dp(8)" )
			)
			( pin "U2D1.CP79"
				( objectStatus "@baseboard_fab2_lib.baseboard_fab2(sch_1):page61_i172:ddr4_dqs_dp(9)" )
			)
			( pin "U2D1.DD79"
				( objectStatus "@baseboard_fab2_lib.baseboard_fab2(sch_1):page61_i172:ddr4_dqs_dp(10)" )
			)
			( pin "U2D1.DV79"
				( objectStatus "@baseboard_fab2_lib.baseboard_fab2(sch_1):page61_i172:ddr4_dqs_dp(11)" )
			)
			( pin "U2D1.DY73"
				( objectStatus "@baseboard_fab2_lib.baseboard_fab2(sch_1):page61_i172:ddr4_dqs_dp(12)" )
			)
			( pin "U2D1.DM41"
				( objectStatus "@baseboard_fab2_lib.baseboard_fab2(sch_1):page61_i172:ddr4_dqs_dp(13)" )
			)
			( pin "U2D1.DW32"
				( objectStatus "@baseboard_fab2_lib.baseboard_fab2(sch_1):page61_i172:ddr4_dqs_dp(14)" )
			)
			( pin "U2D1.DW26"
				( objectStatus "@baseboard_fab2_lib.baseboard_fab2(sch_1):page61_i172:ddr4_dqs_dp(15)" )
			)
			( pin "U2D1.DE26"
				( objectStatus "@baseboard_fab2_lib.baseboard_fab2(sch_1):page61_i172:ddr4_dqs_dp(16)" )
			)
			( pin "U2D1.DT67"
				( objectStatus "@baseboard_fab2_lib.baseboard_fab2(sch_1):page61_i172:ddr4_dqs_dp(17)" )
			)
			( pin "U2D1.DY69"
				( objectStatus "@baseboard_fab2_lib.baseboard_fab2(sch_1):page61_i172:ddr4_ecc(0)" )
			)
			( pin "U2D1.EA68"
				( objectStatus "@baseboard_fab2_lib.baseboard_fab2(sch_1):page61_i172:ddr4_ecc(1)" )
			)
			( pin "U2D1.DV65"
				( objectStatus "@baseboard_fab2_lib.baseboard_fab2(sch_1):page61_i172:ddr4_ecc(2)" )
			)
			( pin "U2D1.DY65"
				( objectStatus "@baseboard_fab2_lib.baseboard_fab2(sch_1):page61_i172:ddr4_ecc(3)" )
			)
			( pin "U2D1.DU68"
				( objectStatus "@baseboard_fab2_lib.baseboard_fab2(sch_1):page61_i172:ddr4_ecc(4)" )
			)
			( pin "U2D1.DV69"
				( objectStatus "@baseboard_fab2_lib.baseboard_fab2(sch_1):page61_i172:ddr4_ecc(5)" )
			)
			( pin "U2D1.DU66"
				( objectStatus "@baseboard_fab2_lib.baseboard_fab2(sch_1):page61_i172:ddr4_ecc(6)" )
			)
			( pin "U2D1.EA66"
				( objectStatus "@baseboard_fab2_lib.baseboard_fab2(sch_1):page61_i172:ddr4_ecc(7)" )
			)
			( pin "U2D1.DW52"
				( objectStatus "@baseboard_fab2_lib.baseboard_fab2(sch_1):page61_i172:ddr4_ma(0)" )
			)
			( pin "U2D1.DW58"
				( objectStatus "@baseboard_fab2_lib.baseboard_fab2(sch_1):page61_i172:ddr4_ma(1)" )
			)
			( pin "U2D1.DV57"
				( objectStatus "@baseboard_fab2_lib.baseboard_fab2(sch_1):page61_i172:ddr4_ma(2)" )
			)
			( pin "U2D1.DR58"
				( objectStatus "@baseboard_fab2_lib.baseboard_fab2(sch_1):page61_i172:ddr4_ma(3)" )
			)
			( pin "U2D1.DT59"
				( objectStatus "@baseboard_fab2_lib.baseboard_fab2(sch_1):page61_i172:ddr4_ma(4)" )
			)
			( pin "U2D1.DN58"
				( objectStatus "@baseboard_fab2_lib.baseboard_fab2(sch_1):page61_i172:ddr4_ma(5)" )
			)
			( pin "U2D1.DM59"
				( objectStatus "@baseboard_fab2_lib.baseboard_fab2(sch_1):page61_i172:ddr4_ma(6)" )
			)
			( pin "U2D1.DK61"
				( objectStatus "@baseboard_fab2_lib.baseboard_fab2(sch_1):page61_i172:ddr4_ma(7)" )
			)
			( pin "U2D1.DJ60"
				( objectStatus "@baseboard_fab2_lib.baseboard_fab2(sch_1):page61_i172:ddr4_ma(8)" )
			)
			( pin "U2D1.DV59"
				( objectStatus "@baseboard_fab2_lib.baseboard_fab2(sch_1):page61_i172:ddr4_ma(9)" )
			)
			( pin "U2D1.DT55"
				( objectStatus "@baseboard_fab2_lib.baseboard_fab2(sch_1):page61_i172:ddr4_ma(10)" )
			)
			( pin "U2D1.DR60"
				( objectStatus "@baseboard_fab2_lib.baseboard_fab2(sch_1):page61_i172:ddr4_ma(11)" )
			)
			( pin "U2D1.DN60"
				( objectStatus "@baseboard_fab2_lib.baseboard_fab2(sch_1):page61_i172:ddr4_ma(12)" )
			)
			( pin "U2D1.DT51"
				( objectStatus "@baseboard_fab2_lib.baseboard_fab2(sch_1):page61_i172:ddr4_ma(13)" )
			)
			( pin "U2D1.DM51"
				( objectStatus "@baseboard_fab2_lib.baseboard_fab2(sch_1):page61_i172:ddr4_ma(14)" )
			)
			( pin "U2D1.DR52"
				( objectStatus "@baseboard_fab2_lib.baseboard_fab2(sch_1):page61_i172:ddr4_ma(15)" )
			)
			( pin "U2D1.DN52"
				( objectStatus "@baseboard_fab2_lib.baseboard_fab2(sch_1):page61_i172:ddr4_ma(16)" )
			)
			( pin "U2D1.DR48"
				( objectStatus "@baseboard_fab2_lib.baseboard_fab2(sch_1):page61_i172:ddr4_ma(17)" )
			)
			( pin "U2D1.DR50"
				( objectStatus "@baseboard_fab2_lib.baseboard_fab2(sch_1):page61_i172:ddr4_odt(0)" )
			)
			( pin "U2D1.DN48"
				( objectStatus "@baseboard_fab2_lib.baseboard_fab2(sch_1):page61_i172:ddr4_odt(1)" )
			)
			( pin "U2D1.DT49"
				( objectStatus "@baseboard_fab2_lib.baseboard_fab2(sch_1):page61_i172:ddr4_odt(2)" )
			)
			( pin "U2D1.DM47"
				( objectStatus "@baseboard_fab2_lib.baseboard_fab2(sch_1):page61_i172:ddr4_odt(3)" )
			)
			( pin "U2D1.DV53"
				( objectStatus "@baseboard_fab2_lib.baseboard_fab2(sch_1):page61_i172:ddr4_par" )
			)
			( pin "U2D1.DC62"
				( objectStatus "@baseboard_fab2_lib.baseboard_fab2(sch_1):page62_i172:ddr5_act_n" )
			)
			( pin "U2D1.DD61"
				( objectStatus "@baseboard_fab2_lib.baseboard_fab2(sch_1):page62_i172:ddr5_alert_n" )
			)
			( pin "U2D1.DJ52"
				( objectStatus "@baseboard_fab2_lib.baseboard_fab2(sch_1):page62_i172:ddr5_ba(0)" )
			)
			( pin "U2D1.DC56"
				( objectStatus "@baseboard_fab2_lib.baseboard_fab2(sch_1):page62_i172:ddr5_ba(1)" )
			)
			( pin "U2D1.DA62"
				( objectStatus "@baseboard_fab2_lib.baseboard_fab2(sch_1):page62_i172:ddr5_bg(0)" )
			)
			( pin "U2D1.DF61"
				( objectStatus "@baseboard_fab2_lib.baseboard_fab2(sch_1):page62_i172:ddr5_bg(1)" )
			)
			( pin "U2D1.DF45"
				( objectStatus "@baseboard_fab2_lib.baseboard_fab2(sch_1):page62_i172:ddr5_cid(2)" )
			)
			( pin "U2D1.DG62"
				( objectStatus "@baseboard_fab2_lib.baseboard_fab2(sch_1):page62_i172:ddr5_cke(0)" )
			)
			( pin "U2D1.DD63"
				( objectStatus "@baseboard_fab2_lib.baseboard_fab2(sch_1):page62_i172:ddr5_cke(1)" )
			)
			( pin "U2D1.DK63"
				( objectStatus "@baseboard_fab2_lib.baseboard_fab2(sch_1):page62_i172:ddr5_cke(2)" )
			)
			( pin "U2D1.DF63"
				( objectStatus "@baseboard_fab2_lib.baseboard_fab2(sch_1):page62_i172:ddr5_cke(3)" )
			)
			( pin "U2D1.DK55"
				( objectStatus "@baseboard_fab2_lib.baseboard_fab2(sch_1):page62_i172:ddr5_clk_dn(0)" )
			)
			( pin "U2D1.DF55"
				( objectStatus "@baseboard_fab2_lib.baseboard_fab2(sch_1):page62_i172:ddr5_clk_dn(1)" )
			)
			( pin "U2D1.DK57"
				( objectStatus "@baseboard_fab2_lib.baseboard_fab2(sch_1):page62_i172:ddr5_clk_dn(2)" )
			)
			( pin "U2D1.DF57"
				( objectStatus "@baseboard_fab2_lib.baseboard_fab2(sch_1):page62_i172:ddr5_clk_dn(3)" )
			)
			( pin "U2D1.DJ54"
				( objectStatus "@baseboard_fab2_lib.baseboard_fab2(sch_1):page62_i172:ddr5_clk_dp(0)" )
			)
			( pin "U2D1.DG54"
				( objectStatus "@baseboard_fab2_lib.baseboard_fab2(sch_1):page62_i172:ddr5_clk_dp(1)" )
			)
			( pin "U2D1.DJ56"
				( objectStatus "@baseboard_fab2_lib.baseboard_fab2(sch_1):page62_i172:ddr5_clk_dp(2)" )
			)
			( pin "U2D1.DG56"
				( objectStatus "@baseboard_fab2_lib.baseboard_fab2(sch_1):page62_i172:ddr5_clk_dp(3)" )
			)
			( pin "U2D1.DK51"
				( objectStatus "@baseboard_fab2_lib.baseboard_fab2(sch_1):page62_i172:ddr5_cs_n(0)" )
			)
			( pin "U2D1.DF49"
				( objectStatus "@baseboard_fab2_lib.baseboard_fab2(sch_1):page62_i172:ddr5_cs_n(1)" )
			)
			( pin "U2D1.DJ46"
				( objectStatus "@baseboard_fab2_lib.baseboard_fab2(sch_1):page62_i172:ddr5_cs_n(2)" )
			)
			( pin "U2D1.DG46"
				( objectStatus "@baseboard_fab2_lib.baseboard_fab2(sch_1):page62_i172:ddr5_cs_n(3)" )
			)
			( pin "U2D1.DF51"
				( objectStatus "@baseboard_fab2_lib.baseboard_fab2(sch_1):page62_i172:ddr5_cs_n(4)" )
			)
			( pin "U2D1.DJ48"
				( objectStatus "@baseboard_fab2_lib.baseboard_fab2(sch_1):page62_i172:ddr5_cs_n(5)" )
			)
			( pin "U2D1.DM45"
				( objectStatus "@baseboard_fab2_lib.baseboard_fab2(sch_1):page62_i172:ddr5_cs_n(6)" )
			)
			( pin "U2D1.DK45"
				( objectStatus "@baseboard_fab2_lib.baseboard_fab2(sch_1):page62_i172:ddr5_cs_n(7)" )
			)
			( pin "U2D1.CR74"
				( objectStatus "@baseboard_fab2_lib.baseboard_fab2(sch_1):page62_i172:ddr5_dq(0)" )
			)
			( pin "U2D1.CN76"
				( objectStatus "@baseboard_fab2_lib.baseboard_fab2(sch_1):page62_i172:ddr5_dq(1)" )
			)
			( pin "U2D1.CW76"
				( objectStatus "@baseboard_fab2_lib.baseboard_fab2(sch_1):page62_i172:ddr5_dq(2)" )
			)
			( pin "U2D1.CV77"
				( objectStatus "@baseboard_fab2_lib.baseboard_fab2(sch_1):page62_i172:ddr5_dq(3)" )
			)
			( pin "U2D1.CN74"
				( objectStatus "@baseboard_fab2_lib.baseboard_fab2(sch_1):page62_i172:ddr5_dq(4)" )
			)
			( pin "U2D1.CM75"
				( objectStatus "@baseboard_fab2_lib.baseboard_fab2(sch_1):page62_i172:ddr5_dq(5)" )
			)
			( pin "U2D1.CV75"
				( objectStatus "@baseboard_fab2_lib.baseboard_fab2(sch_1):page62_i172:ddr5_dq(6)" )
			)
			( pin "U2D1.CT77"
				( objectStatus "@baseboard_fab2_lib.baseboard_fab2(sch_1):page62_i172:ddr5_dq(7)" )
			)
			( pin "U2D1.DE74"
				( objectStatus "@baseboard_fab2_lib.baseboard_fab2(sch_1):page62_i172:ddr5_dq(8)" )
			)
			( pin "U2D1.DC76"
				( objectStatus "@baseboard_fab2_lib.baseboard_fab2(sch_1):page62_i172:ddr5_dq(9)" )
			)
			( pin "U2D1.DH75"
				( objectStatus "@baseboard_fab2_lib.baseboard_fab2(sch_1):page62_i172:ddr5_dq(10)" )
			)
			( pin "U2D1.DJ76"
				( objectStatus "@baseboard_fab2_lib.baseboard_fab2(sch_1):page62_i172:ddr5_dq(11)" )
			)
			( pin "U2D1.DC74"
				( objectStatus "@baseboard_fab2_lib.baseboard_fab2(sch_1):page62_i172:ddr5_dq(12)" )
			)
			( pin "U2D1.DB75"
				( objectStatus "@baseboard_fab2_lib.baseboard_fab2(sch_1):page62_i172:ddr5_dq(13)" )
			)
			( pin "U2D1.DF77"
				( objectStatus "@baseboard_fab2_lib.baseboard_fab2(sch_1):page62_i172:ddr5_dq(14)" )
			)
			( pin "U2D1.DH77"
				( objectStatus "@baseboard_fab2_lib.baseboard_fab2(sch_1):page62_i172:ddr5_dq(15)" )
			)
			( pin "U2D1.DG70"
				( objectStatus "@baseboard_fab2_lib.baseboard_fab2(sch_1):page62_i172:ddr5_dq(16)" )
			)
			( pin "U2D1.DJ72"
				( objectStatus "@baseboard_fab2_lib.baseboard_fab2(sch_1):page62_i172:ddr5_dq(17)" )
			)
			( pin "U2D1.DM69"
				( objectStatus "@baseboard_fab2_lib.baseboard_fab2(sch_1):page62_i172:ddr5_dq(18)" )
			)
			( pin "U2D1.DN70"
				( objectStatus "@baseboard_fab2_lib.baseboard_fab2(sch_1):page62_i172:ddr5_dq(19)" )
			)
			( pin "U2D1.DF71"
				( objectStatus "@baseboard_fab2_lib.baseboard_fab2(sch_1):page62_i172:ddr5_dq(20)" )
			)
			( pin "U2D1.DG72"
				( objectStatus "@baseboard_fab2_lib.baseboard_fab2(sch_1):page62_i172:ddr5_dq(21)" )
			)
			( pin "U2D1.DK69"
				( objectStatus "@baseboard_fab2_lib.baseboard_fab2(sch_1):page62_i172:ddr5_dq(22)" )
			)
			( pin "U2D1.DM71"
				( objectStatus "@baseboard_fab2_lib.baseboard_fab2(sch_1):page62_i172:ddr5_dq(23)" )
			)
			( pin "U2D1.CN66"
				( objectStatus "@baseboard_fab2_lib.baseboard_fab2(sch_1):page62_i172:ddr5_dq(24)" )
			)
			( pin "U2D1.CU66"
				( objectStatus "@baseboard_fab2_lib.baseboard_fab2(sch_1):page62_i172:ddr5_dq(25)" )
			)
			( pin "U2D1.CP63"
				( objectStatus "@baseboard_fab2_lib.baseboard_fab2(sch_1):page62_i172:ddr5_dq(26)" )
			)
			( pin "U2D1.CT63"
				( objectStatus "@baseboard_fab2_lib.baseboard_fab2(sch_1):page62_i172:ddr5_dq(27)" )
			)
			( pin "U2D1.CP67"
				( objectStatus "@baseboard_fab2_lib.baseboard_fab2(sch_1):page62_i172:ddr5_dq(28)" )
			)
			( pin "U2D1.CT67"
				( objectStatus "@baseboard_fab2_lib.baseboard_fab2(sch_1):page62_i172:ddr5_dq(29)" )
			)
			( pin "U2D1.CN64"
				( objectStatus "@baseboard_fab2_lib.baseboard_fab2(sch_1):page62_i172:ddr5_dq(30)" )
			)
			( pin "U2D1.CU64"
				( objectStatus "@baseboard_fab2_lib.baseboard_fab2(sch_1):page62_i172:ddr5_dq(31)" )
			)
			( pin "U2D1.DD41"
				( objectStatus "@baseboard_fab2_lib.baseboard_fab2(sch_1):page62_i172:ddr5_dq(32)" )
			)
			( pin "U2D1.DG42"
				( objectStatus "@baseboard_fab2_lib.baseboard_fab2(sch_1):page62_i172:ddr5_dq(33)" )
			)
			( pin "U2D1.DE38"
				( objectStatus "@baseboard_fab2_lib.baseboard_fab2(sch_1):page62_i172:ddr5_dq(34)" )
			)
			( pin "U2D1.DG38"
				( objectStatus "@baseboard_fab2_lib.baseboard_fab2(sch_1):page62_i172:ddr5_dq(35)" )
			)
			( pin "U2D1.DA42"
				( objectStatus "@baseboard_fab2_lib.baseboard_fab2(sch_1):page62_i172:ddr5_dq(36)" )
			)
			( pin "U2D1.DE42"
				( objectStatus "@baseboard_fab2_lib.baseboard_fab2(sch_1):page62_i172:ddr5_dq(37)" )
			)
			( pin "U2D1.DD39"
				( objectStatus "@baseboard_fab2_lib.baseboard_fab2(sch_1):page62_i172:ddr5_dq(38)" )
			)
			( pin "U2D1.DH39"
				( objectStatus "@baseboard_fab2_lib.baseboard_fab2(sch_1):page62_i172:ddr5_dq(39)" )
			)
			( pin "U2D1.DF33"
				( objectStatus "@baseboard_fab2_lib.baseboard_fab2(sch_1):page62_i172:ddr5_dq(40)" )
			)
			( pin "U2D1.DK33"
				( objectStatus "@baseboard_fab2_lib.baseboard_fab2(sch_1):page62_i172:ddr5_dq(41)" )
			)
			( pin "U2D1.DG30"
				( objectStatus "@baseboard_fab2_lib.baseboard_fab2(sch_1):page62_i172:ddr5_dq(42)" )
			)
			( pin "U2D1.DJ30"
				( objectStatus "@baseboard_fab2_lib.baseboard_fab2(sch_1):page62_i172:ddr5_dq(43)" )
			)
			( pin "U2D1.DG34"
				( objectStatus "@baseboard_fab2_lib.baseboard_fab2(sch_1):page62_i172:ddr5_dq(44)" )
			)
			( pin "U2D1.DJ34"
				( objectStatus "@baseboard_fab2_lib.baseboard_fab2(sch_1):page62_i172:ddr5_dq(45)" )
			)
			( pin "U2D1.DF31"
				( objectStatus "@baseboard_fab2_lib.baseboard_fab2(sch_1):page62_i172:ddr5_dq(46)" )
			)
			( pin "U2D1.DK31"
				( objectStatus "@baseboard_fab2_lib.baseboard_fab2(sch_1):page62_i172:ddr5_dq(47)" )
			)
			( pin "U2D1.CW36"
				( objectStatus "@baseboard_fab2_lib.baseboard_fab2(sch_1):page62_i172:ddr5_dq(48)" )
			)
			( pin "U2D1.DC36"
				( objectStatus "@baseboard_fab2_lib.baseboard_fab2(sch_1):page62_i172:ddr5_dq(49)" )
			)
			( pin "U2D1.CY33"
				( objectStatus "@baseboard_fab2_lib.baseboard_fab2(sch_1):page62_i172:ddr5_dq(50)" )
			)
			( pin "U2D1.DB33"
				( objectStatus "@baseboard_fab2_lib.baseboard_fab2(sch_1):page62_i172:ddr5_dq(51)" )
			)
			( pin "U2D1.CY37"
				( objectStatus "@baseboard_fab2_lib.baseboard_fab2(sch_1):page62_i172:ddr5_dq(52)" )
			)
			( pin "U2D1.DB37"
				( objectStatus "@baseboard_fab2_lib.baseboard_fab2(sch_1):page62_i172:ddr5_dq(53)" )
			)
			( pin "U2D1.CW34"
				( objectStatus "@baseboard_fab2_lib.baseboard_fab2(sch_1):page62_i172:ddr5_dq(54)" )
			)
			( pin "U2D1.DC34"
				( objectStatus "@baseboard_fab2_lib.baseboard_fab2(sch_1):page62_i172:ddr5_dq(55)" )
			)
			( pin "U2D1.CW30"
				( objectStatus "@baseboard_fab2_lib.baseboard_fab2(sch_1):page62_i172:ddr5_dq(56)" )
			)
			( pin "U2D1.DC30"
				( objectStatus "@baseboard_fab2_lib.baseboard_fab2(sch_1):page62_i172:ddr5_dq(57)" )
			)
			( pin "U2D1.CY27"
				( objectStatus "@baseboard_fab2_lib.baseboard_fab2(sch_1):page62_i172:ddr5_dq(58)" )
			)
			( pin "U2D1.DB27"
				( objectStatus "@baseboard_fab2_lib.baseboard_fab2(sch_1):page62_i172:ddr5_dq(59)" )
			)
			( pin "U2D1.CY31"
				( objectStatus "@baseboard_fab2_lib.baseboard_fab2(sch_1):page62_i172:ddr5_dq(60)" )
			)
			( pin "U2D1.DB31"
				( objectStatus "@baseboard_fab2_lib.baseboard_fab2(sch_1):page62_i172:ddr5_dq(61)" )
			)
			( pin "U2D1.CW28"
				( objectStatus "@baseboard_fab2_lib.baseboard_fab2(sch_1):page62_i172:ddr5_dq(62)" )
			)
			( pin "U2D1.DC28"
				( objectStatus "@baseboard_fab2_lib.baseboard_fab2(sch_1):page62_i172:ddr5_dq(63)" )
			)
			( pin "U2D1.CP77"
				( objectStatus "@baseboard_fab2_lib.baseboard_fab2(sch_1):page62_i172:ddr5_dqs_dn(0)" )
			)
			( pin "U2D1.DD77"
				( objectStatus "@baseboard_fab2_lib.baseboard_fab2(sch_1):page62_i172:ddr5_dqs_dn(1)" )
			)
			( pin "U2D1.DL72"
				( objectStatus "@baseboard_fab2_lib.baseboard_fab2(sch_1):page62_i172:ddr5_dqs_dn(2)" )
			)
			( pin "U2D1.CV65"
				( objectStatus "@baseboard_fab2_lib.baseboard_fab2(sch_1):page62_i172:ddr5_dqs_dn(3)" )
			)
			( pin "U2D1.DG40"
				( objectStatus "@baseboard_fab2_lib.baseboard_fab2(sch_1):page62_i172:ddr5_dqs_dn(4)" )
			)
			( pin "U2D1.DL32"
				( objectStatus "@baseboard_fab2_lib.baseboard_fab2(sch_1):page62_i172:ddr5_dqs_dn(5)" )
			)
			( pin "U2D1.DD35"
				( objectStatus "@baseboard_fab2_lib.baseboard_fab2(sch_1):page62_i172:ddr5_dqs_dn(6)" )
			)
			( pin "U2D1.DD29"
				( objectStatus "@baseboard_fab2_lib.baseboard_fab2(sch_1):page62_i172:ddr5_dqs_dn(7)" )
			)
			( pin "U2D1.CN70"
				( objectStatus "@baseboard_fab2_lib.baseboard_fab2(sch_1):page62_i172:ddr5_dqs_dn(8)" )
			)
			( pin "U2D1.CT75"
				( objectStatus "@baseboard_fab2_lib.baseboard_fab2(sch_1):page62_i172:ddr5_dqs_dn(9)" )
			)
			( pin "U2D1.DF75"
				( objectStatus "@baseboard_fab2_lib.baseboard_fab2(sch_1):page62_i172:ddr5_dqs_dn(10)" )
			)
			( pin "U2D1.DJ70"
				( objectStatus "@baseboard_fab2_lib.baseboard_fab2(sch_1):page62_i172:ddr5_dqs_dn(11)" )
			)
			( pin "U2D1.CP65"
				( objectStatus "@baseboard_fab2_lib.baseboard_fab2(sch_1):page62_i172:ddr5_dqs_dn(12)" )
			)
			( pin "U2D1.DE40"
				( objectStatus "@baseboard_fab2_lib.baseboard_fab2(sch_1):page62_i172:ddr5_dqs_dn(13)" )
			)
			( pin "U2D1.DG32"
				( objectStatus "@baseboard_fab2_lib.baseboard_fab2(sch_1):page62_i172:ddr5_dqs_dn(14)" )
			)
			( pin "U2D1.CY35"
				( objectStatus "@baseboard_fab2_lib.baseboard_fab2(sch_1):page62_i172:ddr5_dqs_dn(15)" )
			)
			( pin "U2D1.CY29"
				( objectStatus "@baseboard_fab2_lib.baseboard_fab2(sch_1):page62_i172:ddr5_dqs_dn(16)" )
			)
			( pin "U2D1.CJ70"
				( objectStatus "@baseboard_fab2_lib.baseboard_fab2(sch_1):page62_i172:ddr5_dqs_dn(17)" )
			)
			( pin "U2D1.CR76"
				( objectStatus "@baseboard_fab2_lib.baseboard_fab2(sch_1):page62_i172:ddr5_dqs_dp(0)" )
			)
			( pin "U2D1.DE76"
				( objectStatus "@baseboard_fab2_lib.baseboard_fab2(sch_1):page62_i172:ddr5_dqs_dp(1)" )
			)
			( pin "U2D1.DK71"
				( objectStatus "@baseboard_fab2_lib.baseboard_fab2(sch_1):page62_i172:ddr5_dqs_dp(2)" )
			)
			( pin "U2D1.CT65"
				( objectStatus "@baseboard_fab2_lib.baseboard_fab2(sch_1):page62_i172:ddr5_dqs_dp(3)" )
			)
			( pin "U2D1.DJ40"
				( objectStatus "@baseboard_fab2_lib.baseboard_fab2(sch_1):page62_i172:ddr5_dqs_dp(4)" )
			)
			( pin "U2D1.DJ32"
				( objectStatus "@baseboard_fab2_lib.baseboard_fab2(sch_1):page62_i172:ddr5_dqs_dp(5)" )
			)
			( pin "U2D1.DB35"
				( objectStatus "@baseboard_fab2_lib.baseboard_fab2(sch_1):page62_i172:ddr5_dqs_dp(6)" )
			)
			( pin "U2D1.DB29"
				( objectStatus "@baseboard_fab2_lib.baseboard_fab2(sch_1):page62_i172:ddr5_dqs_dp(7)" )
			)
			( pin "U2D1.CL70"
				( objectStatus "@baseboard_fab2_lib.baseboard_fab2(sch_1):page62_i172:ddr5_dqs_dp(8)" )
			)
			( pin "U2D1.CU74"
				( objectStatus "@baseboard_fab2_lib.baseboard_fab2(sch_1):page62_i172:ddr5_dqs_dp(9)" )
			)
			( pin "U2D1.DG74"
				( objectStatus "@baseboard_fab2_lib.baseboard_fab2(sch_1):page62_i172:ddr5_dqs_dp(10)" )
			)
			( pin "U2D1.DH69"
				( objectStatus "@baseboard_fab2_lib.baseboard_fab2(sch_1):page62_i172:ddr5_dqs_dp(11)" )
			)
			( pin "U2D1.CM65"
				( objectStatus "@baseboard_fab2_lib.baseboard_fab2(sch_1):page62_i172:ddr5_dqs_dp(12)" )
			)
			( pin "U2D1.DC40"
				( objectStatus "@baseboard_fab2_lib.baseboard_fab2(sch_1):page62_i172:ddr5_dqs_dp(13)" )
			)
			( pin "U2D1.DE32"
				( objectStatus "@baseboard_fab2_lib.baseboard_fab2(sch_1):page62_i172:ddr5_dqs_dp(14)" )
			)
			( pin "U2D1.CV35"
				( objectStatus "@baseboard_fab2_lib.baseboard_fab2(sch_1):page62_i172:ddr5_dqs_dp(15)" )
			)
			( pin "U2D1.CV29"
				( objectStatus "@baseboard_fab2_lib.baseboard_fab2(sch_1):page62_i172:ddr5_dqs_dp(16)" )
			)
			( pin "U2D1.CG70"
				( objectStatus "@baseboard_fab2_lib.baseboard_fab2(sch_1):page62_i172:ddr5_dqs_dp(17)" )
			)
			( pin "U2D1.CH71"
				( objectStatus "@baseboard_fab2_lib.baseboard_fab2(sch_1):page62_i172:ddr5_ecc(0)" )
			)
			( pin "U2D1.CM71"
				( objectStatus "@baseboard_fab2_lib.baseboard_fab2(sch_1):page62_i172:ddr5_ecc(1)" )
			)
			( pin "U2D1.CJ68"
				( objectStatus "@baseboard_fab2_lib.baseboard_fab2(sch_1):page62_i172:ddr5_ecc(2)" )
			)
			( pin "U2D1.CL68"
				( objectStatus "@baseboard_fab2_lib.baseboard_fab2(sch_1):page62_i172:ddr5_ecc(3)" )
			)
			( pin "U2D1.CJ72"
				( objectStatus "@baseboard_fab2_lib.baseboard_fab2(sch_1):page62_i172:ddr5_ecc(4)" )
			)
			( pin "U2D1.CL72"
				( objectStatus "@baseboard_fab2_lib.baseboard_fab2(sch_1):page62_i172:ddr5_ecc(5)" )
			)
			( pin "U2D1.CH69"
				( objectStatus "@baseboard_fab2_lib.baseboard_fab2(sch_1):page62_i172:ddr5_ecc(6)" )
			)
			( pin "U2D1.CM69"
				( objectStatus "@baseboard_fab2_lib.baseboard_fab2(sch_1):page62_i172:ddr5_ecc(7)" )
			)
			( pin "U2D1.DF53"
				( objectStatus "@baseboard_fab2_lib.baseboard_fab2(sch_1):page62_i172:ddr5_ma(0)" )
			)
			( pin "U2D1.DC58"
				( objectStatus "@baseboard_fab2_lib.baseboard_fab2(sch_1):page62_i172:ddr5_ma(1)" )
			)
			( pin "U2D1.DD57"
				( objectStatus "@baseboard_fab2_lib.baseboard_fab2(sch_1):page62_i172:ddr5_ma(2)" )
			)
			( pin "U2D1.DG58"
				( objectStatus "@baseboard_fab2_lib.baseboard_fab2(sch_1):page62_i172:ddr5_ma(3)" )
			)
			( pin "U2D1.DJ58"
				( objectStatus "@baseboard_fab2_lib.baseboard_fab2(sch_1):page62_i172:ddr5_ma(4)" )
			)
			( pin "U2D1.DF59"
				( objectStatus "@baseboard_fab2_lib.baseboard_fab2(sch_1):page62_i172:ddr5_ma(5)" )
			)
			( pin "U2D1.DK59"
				( objectStatus "@baseboard_fab2_lib.baseboard_fab2(sch_1):page62_i172:ddr5_ma(6)" )
			)
			( pin "U2D1.DC60"
				( objectStatus "@baseboard_fab2_lib.baseboard_fab2(sch_1):page62_i172:ddr5_ma(7)" )
			)
			( pin "U2D1.DD59"
				( objectStatus "@baseboard_fab2_lib.baseboard_fab2(sch_1):page62_i172:ddr5_ma(8)" )
			)
			( pin "U2D1.DA58"
				( objectStatus "@baseboard_fab2_lib.baseboard_fab2(sch_1):page62_i172:ddr5_ma(9)" )
			)
			( pin "U2D1.DD55"
				( objectStatus "@baseboard_fab2_lib.baseboard_fab2(sch_1):page62_i172:ddr5_ma(10)" )
			)
			( pin "U2D1.DA60"
				( objectStatus "@baseboard_fab2_lib.baseboard_fab2(sch_1):page62_i172:ddr5_ma(11)" )
			)
			( pin "U2D1.DG60"
				( objectStatus "@baseboard_fab2_lib.baseboard_fab2(sch_1):page62_i172:ddr5_ma(12)" )
			)
			( pin "U2D1.DD53"
				( objectStatus "@baseboard_fab2_lib.baseboard_fab2(sch_1):page62_i172:ddr5_ma(13)" )
			)
			( pin "U2D1.DJ50"
				( objectStatus "@baseboard_fab2_lib.baseboard_fab2(sch_1):page62_i172:ddr5_ma(14)" )
			)
			( pin "U2D1.DC54"
				( objectStatus "@baseboard_fab2_lib.baseboard_fab2(sch_1):page62_i172:ddr5_ma(15)" )
			)
			( pin "U2D1.DG52"
				( objectStatus "@baseboard_fab2_lib.baseboard_fab2(sch_1):page62_i172:ddr5_ma(16)" )
			)
			( pin "U2D1.DE46"
				( objectStatus "@baseboard_fab2_lib.baseboard_fab2(sch_1):page62_i172:ddr5_ma(17)" )
			)
			( pin "U2D1.DG50"
				( objectStatus "@baseboard_fab2_lib.baseboard_fab2(sch_1):page62_i172:ddr5_odt(0)" )
			)
			( pin "U2D1.DG48"
				( objectStatus "@baseboard_fab2_lib.baseboard_fab2(sch_1):page62_i172:ddr5_odt(1)" )
			)
			( pin "U2D1.DK49"
				( objectStatus "@baseboard_fab2_lib.baseboard_fab2(sch_1):page62_i172:ddr5_odt(2)" )
			)
			( pin "U2D1.DF47"
				( objectStatus "@baseboard_fab2_lib.baseboard_fab2(sch_1):page62_i172:ddr5_odt(3)" )
			)
			( pin "U2D1.DK53"
				( objectStatus "@baseboard_fab2_lib.baseboard_fab2(sch_1):page62_i172:ddr5_par" )
			)
			( pin "U2D1.BN22"
				( objectStatus "@baseboard_fab2_lib.baseboard_fab2(sch_1):page63_i23:cd_hfi0_i2cclk" )
			)
			( pin "U2D1.BP23"
				( objectStatus "@baseboard_fab2_lib.baseboard_fab2(sch_1):page63_i23:cd_hfi0_i2cdat" )
			)
			( pin "U2D1.BP19"
				( objectStatus "@baseboard_fab2_lib.baseboard_fab2(sch_1):page63_i23:cd_hfi0_int_n" )
			)
			( pin "U2D1.BK21"
				( objectStatus "@baseboard_fab2_lib.baseboard_fab2(sch_1):page63_i23:cd_hfi0_led_n" )
			)
			( pin "U2D1.BR20"
				( objectStatus "@baseboard_fab2_lib.baseboard_fab2(sch_1):page63_i23:cd_hfi0_modprst_n" )
			)
			( pin "U2D1.BN24"
				( objectStatus "@baseboard_fab2_lib.baseboard_fab2(sch_1):page63_i23:cd_hfi0_reset_n" )
			)
			( pin "U2D1.BJ22"
				( objectStatus "@baseboard_fab2_lib.baseboard_fab2(sch_1):page63_i23:cd_hfi1_i2cclk" )
			)
			( pin "U2D1.BH23"
				( objectStatus "@baseboard_fab2_lib.baseboard_fab2(sch_1):page63_i23:cd_hfi1_i2cdat" )
			)
			( pin "U2D1.BM21"
				( objectStatus "@baseboard_fab2_lib.baseboard_fab2(sch_1):page63_i23:cd_hfi1_int_n" )
			)
			( pin "U2D1.BM23"
				( objectStatus "@baseboard_fab2_lib.baseboard_fab2(sch_1):page63_i23:cd_hfi1_led_n" )
			)
			( pin "U2D1.BT19"
				( objectStatus "@baseboard_fab2_lib.baseboard_fab2(sch_1):page63_i23:cd_hfi1_modprst_n" )
			)
			( pin "U2D1.BK23"
				( objectStatus "@baseboard_fab2_lib.baseboard_fab2(sch_1):page63_i23:cd_hfi1_reset_n" )
			)
			( pin "U2D1.BE16"
				( objectStatus "@baseboard_fab2_lib.baseboard_fab2(sch_1):page63_i23:cd_hfi_refclk_dn" )
			)
			( pin "U2D1.BG16"
				( objectStatus "@baseboard_fab2_lib.baseboard_fab2(sch_1):page63_i23:cd_hfi_refclk_dp" )
			)
			( pin "U2D1.BU24"
				( objectStatus "@baseboard_fab2_lib.baseboard_fab2(sch_1):page63_i23:cd_pe_refclk_dn" )
			)
			( pin "U2D1.BW24"
				( objectStatus "@baseboard_fab2_lib.baseboard_fab2(sch_1):page63_i23:cd_pe_refclk_dp" )
			)
			( pin "U2D1.CF25"
				( objectStatus "@baseboard_fab2_lib.baseboard_fab2(sch_1):page63_i23:cd_por_n" )
			)
			( pin "U2D1.CB23"
				( objectStatus "@baseboard_fab2_lib.baseboard_fab2(sch_1):page63_i23:cd_tclk" )
			)
			( pin "U2D1.BY21"
				( objectStatus "@baseboard_fab2_lib.baseboard_fab2(sch_1):page63_i23:cd_tdi" )
			)
			( pin "U2D1.CC22"
				( objectStatus "@baseboard_fab2_lib.baseboard_fab2(sch_1):page63_i23:cd_tdo" )
			)
			( pin "U2D1.CE24"
				( objectStatus "@baseboard_fab2_lib.baseboard_fab2(sch_1):page63_i23:cd_tms" )
			)
			( pin "U2D1.CD23"
				( objectStatus "@baseboard_fab2_lib.baseboard_fab2(sch_1):page63_i23:cd_trst_n" )
			)
			( pin "U2D1.CK9"
				( objectStatus "@baseboard_fab2_lib.baseboard_fab2(sch_1):page63_i23:dmi_rx_dn(0)" )
			)
			( pin "U2D1.CM11"
				( objectStatus "@baseboard_fab2_lib.baseboard_fab2(sch_1):page63_i23:dmi_rx_dn(1)" )
			)
			( pin "U2D1.CR12"
				( objectStatus "@baseboard_fab2_lib.baseboard_fab2(sch_1):page63_i23:dmi_rx_dn(2)" )
			)
			( pin "U2D1.CT11"
				( objectStatus "@baseboard_fab2_lib.baseboard_fab2(sch_1):page63_i23:dmi_rx_dn(3)" )
			)
			( pin "U2D1.CL10"
				( objectStatus "@baseboard_fab2_lib.baseboard_fab2(sch_1):page63_i23:dmi_rx_dp(0)" )
			)
			( pin "U2D1.CN10"
				( objectStatus "@baseboard_fab2_lib.baseboard_fab2(sch_1):page63_i23:dmi_rx_dp(1)" )
			)
			( pin "U2D1.CP11"
				( objectStatus "@baseboard_fab2_lib.baseboard_fab2(sch_1):page63_i23:dmi_rx_dp(2)" )
			)
			( pin "U2D1.CV11"
				( objectStatus "@baseboard_fab2_lib.baseboard_fab2(sch_1):page63_i23:dmi_rx_dp(3)" )
			)
			( pin "U2D1.CG4"
				( objectStatus "@baseboard_fab2_lib.baseboard_fab2(sch_1):page63_i23:dmi_tx_dn(0)" )
			)
			( pin "U2D1.CJ4"
				( objectStatus "@baseboard_fab2_lib.baseboard_fab2(sch_1):page63_i23:dmi_tx_dn(1)" )
			)
			( pin "U2D1.CN4"
				( objectStatus "@baseboard_fab2_lib.baseboard_fab2(sch_1):page63_i23:dmi_tx_dn(2)" )
			)
			( pin "U2D1.CP5"
				( objectStatus "@baseboard_fab2_lib.baseboard_fab2(sch_1):page63_i23:dmi_tx_dn(3)" )
			)
			( pin "U2D1.CH5"
				( objectStatus "@baseboard_fab2_lib.baseboard_fab2(sch_1):page63_i23:dmi_tx_dp(0)" )
			)
			( pin "U2D1.CL4"
				( objectStatus "@baseboard_fab2_lib.baseboard_fab2(sch_1):page63_i23:dmi_tx_dp(1)" )
			)
			( pin "U2D1.CM3"
				( objectStatus "@baseboard_fab2_lib.baseboard_fab2(sch_1):page63_i23:dmi_tx_dp(2)" )
			)
			( pin "U2D1.CR4"
				( objectStatus "@baseboard_fab2_lib.baseboard_fab2(sch_1):page63_i23:dmi_tx_dp(3)" )
			)
			( pin "U2D1.BA76"
				( objectStatus "@baseboard_fab2_lib.baseboard_fab2(sch_1):page63_i23:rsvd(172)" )
			)
			( pin "U2D1.BA66"
				( objectStatus "@baseboard_fab2_lib.baseboard_fab2(sch_1):page63_i23:rsvd(173)" )
			)
			( pin "U2D1.BA64"
				( objectStatus "@baseboard_fab2_lib.baseboard_fab2(sch_1):page63_i23:rsvd(174)" )
			)
			( pin "U2D1.BA22"
				( objectStatus "@baseboard_fab2_lib.baseboard_fab2(sch_1):page63_i23:rsvd(175)" )
			)
			( pin "U2D1.BA18"
				( objectStatus "@baseboard_fab2_lib.baseboard_fab2(sch_1):page63_i23:rsvd(176)" )
			)
			( pin "U2D1.BA16"
				( objectStatus "@baseboard_fab2_lib.baseboard_fab2(sch_1):page63_i23:rsvd(177)" )
			)
			( pin "U2D1.BA14"
				( objectStatus "@baseboard_fab2_lib.baseboard_fab2(sch_1):page63_i23:rsvd(178)" )
			)
			( pin "U2D1.AY77"
				( objectStatus "@baseboard_fab2_lib.baseboard_fab2(sch_1):page63_i23:rsvd(179)" )
			)
			( pin "U2D1.AY75"
				( objectStatus "@baseboard_fab2_lib.baseboard_fab2(sch_1):page63_i23:rsvd(180)" )
			)
			( pin "U2D1.AY67"
				( objectStatus "@baseboard_fab2_lib.baseboard_fab2(sch_1):page63_i23:rsvd(181)" )
			)
			( pin "U2D1.AY65"
				( objectStatus "@baseboard_fab2_lib.baseboard_fab2(sch_1):page63_i23:rsvd(182)" )
			)
			( pin "U2D1.AW76"
				( objectStatus "@baseboard_fab2_lib.baseboard_fab2(sch_1):page63_i23:rsvd(183)" )
			)
			( pin "U2D1.AW64"
				( objectStatus "@baseboard_fab2_lib.baseboard_fab2(sch_1):page63_i23:rsvd(184)" )
			)
			( pin "U2D1.AV77"
				( objectStatus "@baseboard_fab2_lib.baseboard_fab2(sch_1):page63_i23:rsvd(186)" )
			)
			( pin "U2D1.AT25"
				( objectStatus "@baseboard_fab2_lib.baseboard_fab2(sch_1):page63_i23:rsvd(187)" )
			)
			( pin "U2D1.AT23"
				( objectStatus "@baseboard_fab2_lib.baseboard_fab2(sch_1):page63_i23:rsvd(188)" )
			)
			( pin "U2D1.AT13"
				( objectStatus "@baseboard_fab2_lib.baseboard_fab2(sch_1):page63_i23:rsvd(189)" )
			)
			( pin "U2D1.AR62"
				( objectStatus "@baseboard_fab2_lib.baseboard_fab2(sch_1):page63_i23:rsvd(190)" )
			)
			( pin "U2D1.AR26"
				( objectStatus "@baseboard_fab2_lib.baseboard_fab2(sch_1):page63_i23:rsvd(191)" )
			)
			( pin "U2D1.AR22"
				( objectStatus "@baseboard_fab2_lib.baseboard_fab2(sch_1):page63_i23:rsvd(192)" )
			)
			( pin "U2D1.AR20"
				( objectStatus "@baseboard_fab2_lib.baseboard_fab2(sch_1):page63_i23:rsvd(193)" )
			)
			( pin "U2D1.CW8"
				( objectStatus "@baseboard_fab2_lib.baseboard_fab2(sch_1):page64_i68:pe1_rx_dn(0)" )
			)
			( pin "U2D1.DA8"
				( objectStatus "@baseboard_fab2_lib.baseboard_fab2(sch_1):page64_i68:pe1_rx_dn(1)" )
			)
			( pin "U2D1.DC8"
				( objectStatus "@baseboard_fab2_lib.baseboard_fab2(sch_1):page64_i68:pe1_rx_dn(2)" )
			)
			( pin "U2D1.DC10"
				( objectStatus "@baseboard_fab2_lib.baseboard_fab2(sch_1):page64_i68:pe1_rx_dn(3)" )
			)
			( pin "U2D1.DE10"
				( objectStatus "@baseboard_fab2_lib.baseboard_fab2(sch_1):page64_i68:pe1_rx_dn(4)" )
			)
			( pin "U2D1.DH9"
				( objectStatus "@baseboard_fab2_lib.baseboard_fab2(sch_1):page64_i68:pe1_rx_dn(5)" )
			)
			( pin "U2D1.DK9"
				( objectStatus "@baseboard_fab2_lib.baseboard_fab2(sch_1):page64_i68:pe1_rx_dn(6)" )
			)
			( pin "U2D1.DM9"
				( objectStatus "@baseboard_fab2_lib.baseboard_fab2(sch_1):page64_i68:pe1_rx_dn(7)" )
			)
			( pin "U2D1.DM11"
				( objectStatus "@baseboard_fab2_lib.baseboard_fab2(sch_1):page64_i68:pe1_rx_dn(8)" )
			)
			( pin "U2D1.DP11"
				( objectStatus "@baseboard_fab2_lib.baseboard_fab2(sch_1):page64_i68:pe1_rx_dn(9)" )
			)
			( pin "U2D1.DT11"
				( objectStatus "@baseboard_fab2_lib.baseboard_fab2(sch_1):page64_i68:pe1_rx_dn(10)" )
			)
			( pin "U2D1.DT13"
				( objectStatus "@baseboard_fab2_lib.baseboard_fab2(sch_1):page64_i68:pe1_rx_dn(11)" )
			)
			( pin "U2D1.DV13"
				( objectStatus "@baseboard_fab2_lib.baseboard_fab2(sch_1):page64_i68:pe1_rx_dn(12)" )
			)
			( pin "U2D1.DW14"
				( objectStatus "@baseboard_fab2_lib.baseboard_fab2(sch_1):page64_i68:pe1_rx_dn(13)" )
			)
			( pin "U2D1.DY15"
				( objectStatus "@baseboard_fab2_lib.baseboard_fab2(sch_1):page64_i68:pe1_rx_dn(14)" )
			)
			( pin "U2D1.DU16"
				( objectStatus "@baseboard_fab2_lib.baseboard_fab2(sch_1):page64_i68:pe1_rx_dn(15)" )
			)
			( pin "U2D1.CU8"
				( objectStatus "@baseboard_fab2_lib.baseboard_fab2(sch_1):page64_i68:pe1_rx_dp(0)" )
			)
			( pin "U2D1.CY7"
				( objectStatus "@baseboard_fab2_lib.baseboard_fab2(sch_1):page64_i68:pe1_rx_dp(1)" )
			)
			( pin "U2D1.DB9"
				( objectStatus "@baseboard_fab2_lib.baseboard_fab2(sch_1):page64_i68:pe1_rx_dp(2)" )
			)
			( pin "U2D1.DA10"
				( objectStatus "@baseboard_fab2_lib.baseboard_fab2(sch_1):page64_i68:pe1_rx_dp(3)" )
			)
			( pin "U2D1.DD9"
				( objectStatus "@baseboard_fab2_lib.baseboard_fab2(sch_1):page64_i68:pe1_rx_dp(4)" )
			)
			( pin "U2D1.DF9"
				( objectStatus "@baseboard_fab2_lib.baseboard_fab2(sch_1):page64_i68:pe1_rx_dp(5)" )
			)
			( pin "U2D1.DJ8"
				( objectStatus "@baseboard_fab2_lib.baseboard_fab2(sch_1):page64_i68:pe1_rx_dp(6)" )
			)
			( pin "U2D1.DL10"
				( objectStatus "@baseboard_fab2_lib.baseboard_fab2(sch_1):page64_i68:pe1_rx_dp(7)" )
			)
			( pin "U2D1.DK11"
				( objectStatus "@baseboard_fab2_lib.baseboard_fab2(sch_1):page64_i68:pe1_rx_dp(8)" )
			)
			( pin "U2D1.DN10"
				( objectStatus "@baseboard_fab2_lib.baseboard_fab2(sch_1):page64_i68:pe1_rx_dp(9)" )
			)
			( pin "U2D1.DR12"
				( objectStatus "@baseboard_fab2_lib.baseboard_fab2(sch_1):page64_i68:pe1_rx_dp(10)" )
			)
			( pin "U2D1.DP13"
				( objectStatus "@baseboard_fab2_lib.baseboard_fab2(sch_1):page64_i68:pe1_rx_dp(11)" )
			)
			( pin "U2D1.DU12"
				( objectStatus "@baseboard_fab2_lib.baseboard_fab2(sch_1):page64_i68:pe1_rx_dp(12)" )
			)
			( pin "U2D1.DY13"
				( objectStatus "@baseboard_fab2_lib.baseboard_fab2(sch_1):page64_i68:pe1_rx_dp(13)" )
			)
			( pin "U2D1.DV15"
				( objectStatus "@baseboard_fab2_lib.baseboard_fab2(sch_1):page64_i68:pe1_rx_dp(14)" )
			)
			( pin "U2D1.DT15"
				( objectStatus "@baseboard_fab2_lib.baseboard_fab2(sch_1):page64_i68:pe1_rx_dp(15)" )
			)
			( pin "U2D1.DA2"
				( objectStatus "@baseboard_fab2_lib.baseboard_fab2(sch_1):page64_i68:pe1_tx_dn(0)" )
			)
			( pin "U2D1.DC2"
				( objectStatus "@baseboard_fab2_lib.baseboard_fab2(sch_1):page64_i68:pe1_tx_dn(1)" )
			)
			( pin "U2D1.DE2"
				( objectStatus "@baseboard_fab2_lib.baseboard_fab2(sch_1):page64_i68:pe1_tx_dn(2)" )
			)
			( pin "U2D1.DE4"
				( objectStatus "@baseboard_fab2_lib.baseboard_fab2(sch_1):page64_i68:pe1_tx_dn(3)" )
			)
			( pin "U2D1.DG4"
				( objectStatus "@baseboard_fab2_lib.baseboard_fab2(sch_1):page64_i68:pe1_tx_dn(4)" )
			)
			( pin "U2D1.DK3"
				( objectStatus "@baseboard_fab2_lib.baseboard_fab2(sch_1):page64_i68:pe1_tx_dn(5)" )
			)
			( pin "U2D1.DM3"
				( objectStatus "@baseboard_fab2_lib.baseboard_fab2(sch_1):page64_i68:pe1_tx_dn(6)" )
			)
			( pin "U2D1.DN4"
				( objectStatus "@baseboard_fab2_lib.baseboard_fab2(sch_1):page64_i68:pe1_tx_dn(7)" )
			)
			( pin "U2D1.DT5"
				( objectStatus "@baseboard_fab2_lib.baseboard_fab2(sch_1):page64_i68:pe1_tx_dn(8)" )
			)
			( pin "U2D1.DV3"
				( objectStatus "@baseboard_fab2_lib.baseboard_fab2(sch_1):page64_i68:pe1_tx_dn(9)" )
			)
			( pin "U2D1.DW4"
				( objectStatus "@baseboard_fab2_lib.baseboard_fab2(sch_1):page64_i68:pe1_tx_dn(10)" )
			)
			( pin "U2D1.DU6"
				( objectStatus "@baseboard_fab2_lib.baseboard_fab2(sch_1):page64_i68:pe1_tx_dn(11)" )
			)
			( pin "U2D1.DV7"
				( objectStatus "@baseboard_fab2_lib.baseboard_fab2(sch_1):page64_i68:pe1_tx_dn(12)" )
			)
			( pin "U2D1.DY7"
				( objectStatus "@baseboard_fab2_lib.baseboard_fab2(sch_1):page64_i68:pe1_tx_dn(13)" )
			)
			( pin "U2D1.EA8"
				( objectStatus "@baseboard_fab2_lib.baseboard_fab2(sch_1):page64_i68:pe1_tx_dn(14)" )
			)
			( pin "U2D1.ED9"
				( objectStatus "@baseboard_fab2_lib.baseboard_fab2(sch_1):page64_i68:pe1_tx_dn(15)" )
			)
			( pin "U2D1.CW2"
				( objectStatus "@baseboard_fab2_lib.baseboard_fab2(sch_1):page64_i68:pe1_tx_dp(0)" )
			)
			( pin "U2D1.DB1"
				( objectStatus "@baseboard_fab2_lib.baseboard_fab2(sch_1):page64_i68:pe1_tx_dp(1)" )
			)
			( pin "U2D1.DD3"
				( objectStatus "@baseboard_fab2_lib.baseboard_fab2(sch_1):page64_i68:pe1_tx_dp(2)" )
			)
			( pin "U2D1.DC4"
				( objectStatus "@baseboard_fab2_lib.baseboard_fab2(sch_1):page64_i68:pe1_tx_dp(3)" )
			)
			( pin "U2D1.DF3"
				( objectStatus "@baseboard_fab2_lib.baseboard_fab2(sch_1):page64_i68:pe1_tx_dp(4)" )
			)
			( pin "U2D1.DH3"
				( objectStatus "@baseboard_fab2_lib.baseboard_fab2(sch_1):page64_i68:pe1_tx_dp(5)" )
			)
			( pin "U2D1.DL2"
				( objectStatus "@baseboard_fab2_lib.baseboard_fab2(sch_1):page64_i68:pe1_tx_dp(6)" )
			)
			( pin "U2D1.DP3"
				( objectStatus "@baseboard_fab2_lib.baseboard_fab2(sch_1):page64_i68:pe1_tx_dp(7)" )
			)
			( pin "U2D1.DR4"
				( objectStatus "@baseboard_fab2_lib.baseboard_fab2(sch_1):page64_i68:pe1_tx_dp(8)" )
			)
			( pin "U2D1.DU2"
				( objectStatus "@baseboard_fab2_lib.baseboard_fab2(sch_1):page64_i68:pe1_tx_dp(9)" )
			)
			( pin "U2D1.DU4"
				( objectStatus "@baseboard_fab2_lib.baseboard_fab2(sch_1):page64_i68:pe1_tx_dp(10)" )
			)
			( pin "U2D1.DV5"
				( objectStatus "@baseboard_fab2_lib.baseboard_fab2(sch_1):page64_i68:pe1_tx_dp(11)" )
			)
			( pin "U2D1.DT7"
				( objectStatus "@baseboard_fab2_lib.baseboard_fab2(sch_1):page64_i68:pe1_tx_dp(12)" )
			)
			( pin "U2D1.DW6"
				( objectStatus "@baseboard_fab2_lib.baseboard_fab2(sch_1):page64_i68:pe1_tx_dp(13)" )
			)
			( pin "U2D1.EB7"
				( objectStatus "@baseboard_fab2_lib.baseboard_fab2(sch_1):page64_i68:pe1_tx_dp(14)" )
			)
			( pin "U2D1.EC8"
				( objectStatus "@baseboard_fab2_lib.baseboard_fab2(sch_1):page64_i68:pe1_tx_dp(15)" )
			)
			( pin "U2D1.CT9"
				( objectStatus "@baseboard_fab2_lib.baseboard_fab2(sch_1):page65_i68:pe2_rx_dn(0)" )
			)
			( pin "U2D1.CP9"
				( objectStatus "@baseboard_fab2_lib.baseboard_fab2(sch_1):page65_i68:pe2_rx_dn(1)" )
			)
			( pin "U2D1.CP7"
				( objectStatus "@baseboard_fab2_lib.baseboard_fab2(sch_1):page65_i68:pe2_rx_dn(2)" )
			)
			( pin "U2D1.CM7"
				( objectStatus "@baseboard_fab2_lib.baseboard_fab2(sch_1):page65_i68:pe2_rx_dn(3)" )
			)
			( pin "U2D1.CK7"
				( objectStatus "@baseboard_fab2_lib.baseboard_fab2(sch_1):page65_i68:pe2_rx_dn(4)" )
			)
			( pin "U2D1.CG8"
				( objectStatus "@baseboard_fab2_lib.baseboard_fab2(sch_1):page65_i68:pe2_rx_dn(5)" )
			)
			( pin "U2D1.CE6"
				( objectStatus "@baseboard_fab2_lib.baseboard_fab2(sch_1):page65_i68:pe2_rx_dn(6)" )
			)
			( pin "U2D1.CE8"
				( objectStatus "@baseboard_fab2_lib.baseboard_fab2(sch_1):page65_i68:pe2_rx_dn(7)" )
			)
			( pin "U2D1.BY9"
				( objectStatus "@baseboard_fab2_lib.baseboard_fab2(sch_1):page65_i68:pe2_rx_dn(8)" )
			)
			( pin "U2D1.BY7"
				( objectStatus "@baseboard_fab2_lib.baseboard_fab2(sch_1):page65_i68:pe2_rx_dn(9)" )
			)
			( pin "U2D1.BV7"
				( objectStatus "@baseboard_fab2_lib.baseboard_fab2(sch_1):page65_i68:pe2_rx_dn(10)" )
			)
			( pin "U2D1.BT7"
				( objectStatus "@baseboard_fab2_lib.baseboard_fab2(sch_1):page65_i68:pe2_rx_dn(11)" )
			)
			( pin "U2D1.BR8"
				( objectStatus "@baseboard_fab2_lib.baseboard_fab2(sch_1):page65_i68:pe2_rx_dn(12)" )
			)
			( pin "U2D1.BN8"
				( objectStatus "@baseboard_fab2_lib.baseboard_fab2(sch_1):page65_i68:pe2_rx_dn(13)" )
			)
			( pin "U2D1.BL8"
				( objectStatus "@baseboard_fab2_lib.baseboard_fab2(sch_1):page65_i68:pe2_rx_dn(14)" )
			)
			( pin "U2D1.BK9"
				( objectStatus "@baseboard_fab2_lib.baseboard_fab2(sch_1):page65_i68:pe2_rx_dn(15)" )
			)
			( pin "U2D1.CR8"
				( objectStatus "@baseboard_fab2_lib.baseboard_fab2(sch_1):page65_i68:pe2_rx_dp(0)" )
			)
			( pin "U2D1.CM9"
				( objectStatus "@baseboard_fab2_lib.baseboard_fab2(sch_1):page65_i68:pe2_rx_dp(1)" )
			)
			( pin "U2D1.CN8"
				( objectStatus "@baseboard_fab2_lib.baseboard_fab2(sch_1):page65_i68:pe2_rx_dp(2)" )
			)
			( pin "U2D1.CL6"
				( objectStatus "@baseboard_fab2_lib.baseboard_fab2(sch_1):page65_i68:pe2_rx_dp(3)" )
			)
			( pin "U2D1.CH7"
				( objectStatus "@baseboard_fab2_lib.baseboard_fab2(sch_1):page65_i68:pe2_rx_dp(4)" )
			)
			( pin "U2D1.CF7"
				( objectStatus "@baseboard_fab2_lib.baseboard_fab2(sch_1):page65_i68:pe2_rx_dp(5)" )
			)
			( pin "U2D1.CD7"
				( objectStatus "@baseboard_fab2_lib.baseboard_fab2(sch_1):page65_i68:pe2_rx_dp(6)" )
			)
			( pin "U2D1.CC8"
				( objectStatus "@baseboard_fab2_lib.baseboard_fab2(sch_1):page65_i68:pe2_rx_dp(7)" )
			)
			( pin "U2D1.BV9"
				( objectStatus "@baseboard_fab2_lib.baseboard_fab2(sch_1):page65_i68:pe2_rx_dp(8)" )
			)
			( pin "U2D1.BW8"
				( objectStatus "@baseboard_fab2_lib.baseboard_fab2(sch_1):page65_i68:pe2_rx_dp(9)" )
			)
			( pin "U2D1.BU6"
				( objectStatus "@baseboard_fab2_lib.baseboard_fab2(sch_1):page65_i68:pe2_rx_dp(10)" )
			)
			( pin "U2D1.BP7"
				( objectStatus "@baseboard_fab2_lib.baseboard_fab2(sch_1):page65_i68:pe2_rx_dp(11)" )
			)
			( pin "U2D1.BP9"
				( objectStatus "@baseboard_fab2_lib.baseboard_fab2(sch_1):page65_i68:pe2_rx_dp(12)" )
			)
			( pin "U2D1.BM7"
				( objectStatus "@baseboard_fab2_lib.baseboard_fab2(sch_1):page65_i68:pe2_rx_dp(13)" )
			)
			( pin "U2D1.BJ8"
				( objectStatus "@baseboard_fab2_lib.baseboard_fab2(sch_1):page65_i68:pe2_rx_dp(14)" )
			)
			( pin "U2D1.BJ10"
				( objectStatus "@baseboard_fab2_lib.baseboard_fab2(sch_1):page65_i68:pe2_rx_dp(15)" )
			)
			( pin "U2D1.CY3"
				( objectStatus "@baseboard_fab2_lib.baseboard_fab2(sch_1):page65_i68:pe2_tx_dn(0)" )
			)
			( pin "U2D1.CV3"
				( objectStatus "@baseboard_fab2_lib.baseboard_fab2(sch_1):page65_i68:pe2_tx_dn(1)" )
			)
			( pin "U2D1.CT1"
				( objectStatus "@baseboard_fab2_lib.baseboard_fab2(sch_1):page65_i68:pe2_tx_dn(2)" )
			)
			( pin "U2D1.CT3"
				( objectStatus "@baseboard_fab2_lib.baseboard_fab2(sch_1):page65_i68:pe2_tx_dn(3)" )
			)
			( pin "U2D1.CM1"
				( objectStatus "@baseboard_fab2_lib.baseboard_fab2(sch_1):page65_i68:pe2_tx_dn(4)" )
			)
			( pin "U2D1.CL2"
				( objectStatus "@baseboard_fab2_lib.baseboard_fab2(sch_1):page65_i68:pe2_tx_dn(5)" )
			)
			( pin "U2D1.CG2"
				( objectStatus "@baseboard_fab2_lib.baseboard_fab2(sch_1):page65_i68:pe2_tx_dn(6)" )
			)
			( pin "U2D1.CF3"
				( objectStatus "@baseboard_fab2_lib.baseboard_fab2(sch_1):page65_i68:pe2_tx_dn(7)" )
			)
			( pin "U2D1.CC2"
				( objectStatus "@baseboard_fab2_lib.baseboard_fab2(sch_1):page65_i68:pe2_tx_dn(8)" )
			)
			( pin "U2D1.CB3"
				( objectStatus "@baseboard_fab2_lib.baseboard_fab2(sch_1):page65_i68:pe2_tx_dn(9)" )
			)
			( pin "U2D1.CA4"
				( objectStatus "@baseboard_fab2_lib.baseboard_fab2(sch_1):page65_i68:pe2_tx_dn(10)" )
			)
			( pin "U2D1.BW4"
				( objectStatus "@baseboard_fab2_lib.baseboard_fab2(sch_1):page65_i68:pe2_tx_dn(11)" )
			)
			( pin "U2D1.BU4"
				( objectStatus "@baseboard_fab2_lib.baseboard_fab2(sch_1):page65_i68:pe2_tx_dn(12)" )
			)
			( pin "U2D1.BP5"
				( objectStatus "@baseboard_fab2_lib.baseboard_fab2(sch_1):page65_i68:pe2_tx_dn(13)" )
			)
			( pin "U2D1.BL4"
				( objectStatus "@baseboard_fab2_lib.baseboard_fab2(sch_1):page65_i68:pe2_tx_dn(14)" )
			)
			( pin "U2D1.BM5"
				( objectStatus "@baseboard_fab2_lib.baseboard_fab2(sch_1):page65_i68:pe2_tx_dn(15)" )
			)
			( pin "U2D1.CW4"
				( objectStatus "@baseboard_fab2_lib.baseboard_fab2(sch_1):page65_i68:pe2_tx_dp(0)" )
			)
			( pin "U2D1.CU2"
				( objectStatus "@baseboard_fab2_lib.baseboard_fab2(sch_1):page65_i68:pe2_tx_dp(1)" )
			)
			( pin "U2D1.CR2"
				( objectStatus "@baseboard_fab2_lib.baseboard_fab2(sch_1):page65_i68:pe2_tx_dp(2)" )
			)
			( pin "U2D1.CP3"
				( objectStatus "@baseboard_fab2_lib.baseboard_fab2(sch_1):page65_i68:pe2_tx_dp(3)" )
			)
			( pin "U2D1.CK1"
				( objectStatus "@baseboard_fab2_lib.baseboard_fab2(sch_1):page65_i68:pe2_tx_dp(4)" )
			)
			( pin "U2D1.CK3"
				( objectStatus "@baseboard_fab2_lib.baseboard_fab2(sch_1):page65_i68:pe2_tx_dp(5)" )
			)
			( pin "U2D1.CE2"
				( objectStatus "@baseboard_fab2_lib.baseboard_fab2(sch_1):page65_i68:pe2_tx_dp(6)" )
			)
			( pin "U2D1.CE4"
				( objectStatus "@baseboard_fab2_lib.baseboard_fab2(sch_1):page65_i68:pe2_tx_dp(7)" )
			)
			( pin "U2D1.CD3"
				( objectStatus "@baseboard_fab2_lib.baseboard_fab2(sch_1):page65_i68:pe2_tx_dp(8)" )
			)
			( pin "U2D1.BY3"
				( objectStatus "@baseboard_fab2_lib.baseboard_fab2(sch_1):page65_i68:pe2_tx_dp(9)" )
			)
			( pin "U2D1.BY5"
				( objectStatus "@baseboard_fab2_lib.baseboard_fab2(sch_1):page65_i68:pe2_tx_dp(10)" )
			)
			( pin "U2D1.BV3"
				( objectStatus "@baseboard_fab2_lib.baseboard_fab2(sch_1):page65_i68:pe2_tx_dp(11)" )
			)
			( pin "U2D1.BR4"
				( objectStatus "@baseboard_fab2_lib.baseboard_fab2(sch_1):page65_i68:pe2_tx_dp(12)" )
			)
			( pin "U2D1.BN4"
				( objectStatus "@baseboard_fab2_lib.baseboard_fab2(sch_1):page65_i68:pe2_tx_dp(13)" )
			)
			( pin "U2D1.BM3"
				( objectStatus "@baseboard_fab2_lib.baseboard_fab2(sch_1):page65_i68:pe2_tx_dp(14)" )
			)
			( pin "U2D1.BK5"
				( objectStatus "@baseboard_fab2_lib.baseboard_fab2(sch_1):page65_i68:pe2_tx_dp(15)" )
			)
			( pin "U2D1.EA18"
				( objectStatus "@baseboard_fab2_lib.baseboard_fab2(sch_1):page66_i84:pe3_rx_dn(0)" )
			)
			( pin "U2D1.DW18"
				( objectStatus "@baseboard_fab2_lib.baseboard_fab2(sch_1):page66_i84:pe3_rx_dn(1)" )
			)
			( pin "U2D1.DW16"
				( objectStatus "@baseboard_fab2_lib.baseboard_fab2(sch_1):page66_i84:pe3_rx_dn(2)" )
			)
			( pin "U2D1.DT19"
				( objectStatus "@baseboard_fab2_lib.baseboard_fab2(sch_1):page66_i84:pe3_rx_dn(3)" )
			)
			( pin "U2D1.DR16"
				( objectStatus "@baseboard_fab2_lib.baseboard_fab2(sch_1):page66_i84:pe3_rx_dn(4)" )
			)
			( pin "U2D1.DR14"
				( objectStatus "@baseboard_fab2_lib.baseboard_fab2(sch_1):page66_i84:pe3_rx_dn(5)" )
			)
			( pin "U2D1.DN14"
				( objectStatus "@baseboard_fab2_lib.baseboard_fab2(sch_1):page66_i84:pe3_rx_dn(6)" )
			)
			( pin "U2D1.DL14"
				( objectStatus "@baseboard_fab2_lib.baseboard_fab2(sch_1):page66_i84:pe3_rx_dn(7)" )
			)
			( pin "U2D1.DL12"
				( objectStatus "@baseboard_fab2_lib.baseboard_fab2(sch_1):page66_i84:pe3_rx_dn(8)" )
			)
			( pin "U2D1.DJ12"
				( objectStatus "@baseboard_fab2_lib.baseboard_fab2(sch_1):page66_i84:pe3_rx_dn(9)" )
			)
			( pin "U2D1.DG12"
				( objectStatus "@baseboard_fab2_lib.baseboard_fab2(sch_1):page66_i84:pe3_rx_dn(10)" )
			)
			( pin "U2D1.DG10"
				( objectStatus "@baseboard_fab2_lib.baseboard_fab2(sch_1):page66_i84:pe3_rx_dn(11)" )
			)
			( pin "U2D1.DD13"
				( objectStatus "@baseboard_fab2_lib.baseboard_fab2(sch_1):page66_i84:pe3_rx_dn(12)" )
			)
			( pin "U2D1.DB11"
				( objectStatus "@baseboard_fab2_lib.baseboard_fab2(sch_1):page66_i84:pe3_rx_dn(13)" )
			)
			( pin "U2D1.CY11"
				( objectStatus "@baseboard_fab2_lib.baseboard_fab2(sch_1):page66_i84:pe3_rx_dn(14)" )
			)
			( pin "U2D1.CV9"
				( objectStatus "@baseboard_fab2_lib.baseboard_fab2(sch_1):page66_i84:pe3_rx_dn(15)" )
			)
			( pin "U2D1.DY17"
				( objectStatus "@baseboard_fab2_lib.baseboard_fab2(sch_1):page66_i84:pe3_rx_dp(0)" )
			)
			( pin "U2D1.DU18"
				( objectStatus "@baseboard_fab2_lib.baseboard_fab2(sch_1):page66_i84:pe3_rx_dp(1)" )
			)
			( pin "U2D1.DV17"
				( objectStatus "@baseboard_fab2_lib.baseboard_fab2(sch_1):page66_i84:pe3_rx_dp(2)" )
			)
			( pin "U2D1.DR18"
				( objectStatus "@baseboard_fab2_lib.baseboard_fab2(sch_1):page66_i84:pe3_rx_dp(3)" )
			)
			( pin "U2D1.DN16"
				( objectStatus "@baseboard_fab2_lib.baseboard_fab2(sch_1):page66_i84:pe3_rx_dp(4)" )
			)
			( pin "U2D1.DP15"
				( objectStatus "@baseboard_fab2_lib.baseboard_fab2(sch_1):page66_i84:pe3_rx_dp(5)" )
			)
			( pin "U2D1.DM13"
				( objectStatus "@baseboard_fab2_lib.baseboard_fab2(sch_1):page66_i84:pe3_rx_dp(6)" )
			)
			( pin "U2D1.DJ14"
				( objectStatus "@baseboard_fab2_lib.baseboard_fab2(sch_1):page66_i84:pe3_rx_dp(7)" )
			)
			( pin "U2D1.DK13"
				( objectStatus "@baseboard_fab2_lib.baseboard_fab2(sch_1):page66_i84:pe3_rx_dp(8)" )
			)
			( pin "U2D1.DH11"
				( objectStatus "@baseboard_fab2_lib.baseboard_fab2(sch_1):page66_i84:pe3_rx_dp(9)" )
			)
			( pin "U2D1.DE12"
				( objectStatus "@baseboard_fab2_lib.baseboard_fab2(sch_1):page66_i84:pe3_rx_dp(10)" )
			)
			( pin "U2D1.DF11"
				( objectStatus "@baseboard_fab2_lib.baseboard_fab2(sch_1):page66_i84:pe3_rx_dp(11)" )
			)
			( pin "U2D1.DC12"
				( objectStatus "@baseboard_fab2_lib.baseboard_fab2(sch_1):page66_i84:pe3_rx_dp(12)" )
			)
			( pin "U2D1.DA12"
				( objectStatus "@baseboard_fab2_lib.baseboard_fab2(sch_1):page66_i84:pe3_rx_dp(13)" )
			)
			( pin "U2D1.CW10"
				( objectStatus "@baseboard_fab2_lib.baseboard_fab2(sch_1):page66_i84:pe3_rx_dp(14)" )
			)
			( pin "U2D1.CU10"
				( objectStatus "@baseboard_fab2_lib.baseboard_fab2(sch_1):page66_i84:pe3_rx_dp(15)" )
			)
			( pin "U2D1.EE14"
				( objectStatus "@baseboard_fab2_lib.baseboard_fab2(sch_1):page66_i84:pe3_tx_dn(0)" )
			)
			( pin "U2D1.EE12"
				( objectStatus "@baseboard_fab2_lib.baseboard_fab2(sch_1):page66_i84:pe3_tx_dn(1)" )
			)
			( pin "U2D1.EC12"
				( objectStatus "@baseboard_fab2_lib.baseboard_fab2(sch_1):page66_i84:pe3_tx_dn(2)" )
			)
			( pin "U2D1.DY11"
				( objectStatus "@baseboard_fab2_lib.baseboard_fab2(sch_1):page66_i84:pe3_tx_dn(3)" )
			)
			( pin "U2D1.EB9"
				( objectStatus "@baseboard_fab2_lib.baseboard_fab2(sch_1):page66_i84:pe3_tx_dn(4)" )
			)
			( pin "U2D1.DW10"
				( objectStatus "@baseboard_fab2_lib.baseboard_fab2(sch_1):page66_i84:pe3_tx_dn(5)" )
			)
			( pin "U2D1.DU8"
				( objectStatus "@baseboard_fab2_lib.baseboard_fab2(sch_1):page66_i84:pe3_tx_dn(6)" )
			)
			( pin "U2D1.DR8"
				( objectStatus "@baseboard_fab2_lib.baseboard_fab2(sch_1):page66_i84:pe3_tx_dn(7)" )
			)
			( pin "U2D1.DM7"
				( objectStatus "@baseboard_fab2_lib.baseboard_fab2(sch_1):page66_i84:pe3_tx_dn(8)" )
			)
			( pin "U2D1.DP5"
				( objectStatus "@baseboard_fab2_lib.baseboard_fab2(sch_1):page66_i84:pe3_tx_dn(9)" )
			)
			( pin "U2D1.DL6"
				( objectStatus "@baseboard_fab2_lib.baseboard_fab2(sch_1):page66_i84:pe3_tx_dn(10)" )
			)
			( pin "U2D1.DJ4"
				( objectStatus "@baseboard_fab2_lib.baseboard_fab2(sch_1):page66_i84:pe3_tx_dn(11)" )
			)
			( pin "U2D1.DJ6"
				( objectStatus "@baseboard_fab2_lib.baseboard_fab2(sch_1):page66_i84:pe3_tx_dn(12)" )
			)
			( pin "U2D1.DD5"
				( objectStatus "@baseboard_fab2_lib.baseboard_fab2(sch_1):page66_i84:pe3_tx_dn(13)" )
			)
			( pin "U2D1.DB5"
				( objectStatus "@baseboard_fab2_lib.baseboard_fab2(sch_1):page66_i84:pe3_tx_dn(14)" )
			)
			( pin "U2D1.CY5"
				( objectStatus "@baseboard_fab2_lib.baseboard_fab2(sch_1):page66_i84:pe3_tx_dn(15)" )
			)
			( pin "U2D1.EC14"
				( objectStatus "@baseboard_fab2_lib.baseboard_fab2(sch_1):page66_i84:pe3_tx_dp(0)" )
			)
			( pin "U2D1.ED13"
				( objectStatus "@baseboard_fab2_lib.baseboard_fab2(sch_1):page66_i84:pe3_tx_dp(1)" )
			)
			( pin "U2D1.EB11"
				( objectStatus "@baseboard_fab2_lib.baseboard_fab2(sch_1):page66_i84:pe3_tx_dp(2)" )
			)
			( pin "U2D1.EA10"
				( objectStatus "@baseboard_fab2_lib.baseboard_fab2(sch_1):page66_i84:pe3_tx_dp(3)" )
			)
			( pin "U2D1.DY9"
				( objectStatus "@baseboard_fab2_lib.baseboard_fab2(sch_1):page66_i84:pe3_tx_dp(4)" )
			)
			( pin "U2D1.DV9"
				( objectStatus "@baseboard_fab2_lib.baseboard_fab2(sch_1):page66_i84:pe3_tx_dp(5)" )
			)
			( pin "U2D1.DT9"
				( objectStatus "@baseboard_fab2_lib.baseboard_fab2(sch_1):page66_i84:pe3_tx_dp(6)" )
			)
			( pin "U2D1.DP7"
				( objectStatus "@baseboard_fab2_lib.baseboard_fab2(sch_1):page66_i84:pe3_tx_dp(7)" )
			)
			( pin "U2D1.DN6"
				( objectStatus "@baseboard_fab2_lib.baseboard_fab2(sch_1):page66_i84:pe3_tx_dp(8)" )
			)
			( pin "U2D1.DM5"
				( objectStatus "@baseboard_fab2_lib.baseboard_fab2(sch_1):page66_i84:pe3_tx_dp(9)" )
			)
			( pin "U2D1.DK5"
				( objectStatus "@baseboard_fab2_lib.baseboard_fab2(sch_1):page66_i84:pe3_tx_dp(10)" )
			)
			( pin "U2D1.DH5"
				( objectStatus "@baseboard_fab2_lib.baseboard_fab2(sch_1):page66_i84:pe3_tx_dp(11)" )
			)
			( pin "U2D1.DG6"
				( objectStatus "@baseboard_fab2_lib.baseboard_fab2(sch_1):page66_i84:pe3_tx_dp(12)" )
			)
			( pin "U2D1.DC6"
				( objectStatus "@baseboard_fab2_lib.baseboard_fab2(sch_1):page66_i84:pe3_tx_dp(13)" )
			)
			( pin "U2D1.DA4"
				( objectStatus "@baseboard_fab2_lib.baseboard_fab2(sch_1):page66_i84:pe3_tx_dp(14)" )
			)
			( pin "U2D1.CV5"
				( objectStatus "@baseboard_fab2_lib.baseboard_fab2(sch_1):page66_i84:pe3_tx_dp(15)" )
			)
			( pin "U2D1.AC10"
				( objectStatus "@baseboard_fab2_lib.baseboard_fab2(sch_1):page67_i132:upi0_rx_dn(0)" )
			)
			( pin "U2D1.AA8"
				( objectStatus "@baseboard_fab2_lib.baseboard_fab2(sch_1):page67_i132:upi0_rx_dn(1)" )
			)
			( pin "U2D1.AB7"
				( objectStatus "@baseboard_fab2_lib.baseboard_fab2(sch_1):page67_i132:upi0_rx_dn(2)" )
			)
			( pin "U2D1.AD5"
				( objectStatus "@baseboard_fab2_lib.baseboard_fab2(sch_1):page67_i132:upi0_rx_dn(3)" )
			)
			( pin "U2D1.AE6"
				( objectStatus "@baseboard_fab2_lib.baseboard_fab2(sch_1):page67_i132:upi0_rx_dn(4)" )
			)
			( pin "U2D1.AG8"
				( objectStatus "@baseboard_fab2_lib.baseboard_fab2(sch_1):page67_i132:upi0_rx_dn(5)" )
			)
			( pin "U2D1.AJ6"
				( objectStatus "@baseboard_fab2_lib.baseboard_fab2(sch_1):page67_i132:upi0_rx_dn(6)" )
			)
			( pin "U2D1.AL6"
				( objectStatus "@baseboard_fab2_lib.baseboard_fab2(sch_1):page67_i132:upi0_rx_dn(7)" )
			)
			( pin "U2D1.AK7"
				( objectStatus "@baseboard_fab2_lib.baseboard_fab2(sch_1):page67_i132:upi0_rx_dn(8)" )
			)
			( pin "U2D1.AM9"
				( objectStatus "@baseboard_fab2_lib.baseboard_fab2(sch_1):page67_i132:upi0_rx_dn(9)" )
			)
			( pin "U2D1.AP7"
				( objectStatus "@baseboard_fab2_lib.baseboard_fab2(sch_1):page67_i132:upi0_rx_dn(10)" )
			)
			( pin "U2D1.AR8"
				( objectStatus "@baseboard_fab2_lib.baseboard_fab2(sch_1):page67_i132:upi0_rx_dn(11)" )
			)
			( pin "U2D1.AU10"
				( objectStatus "@baseboard_fab2_lib.baseboard_fab2(sch_1):page67_i132:upi0_rx_dn(12)" )
			)
			( pin "U2D1.BA8"
				( objectStatus "@baseboard_fab2_lib.baseboard_fab2(sch_1):page67_i132:upi0_rx_dn(13)" )
			)
			( pin "U2D1.BC6"
				( objectStatus "@baseboard_fab2_lib.baseboard_fab2(sch_1):page67_i132:upi0_rx_dn(14)" )
			)
			( pin "U2D1.BD7"
				( objectStatus "@baseboard_fab2_lib.baseboard_fab2(sch_1):page67_i132:upi0_rx_dn(15)" )
			)
			( pin "U2D1.AW8"
				( objectStatus "@baseboard_fab2_lib.baseboard_fab2(sch_1):page67_i132:upi0_rx_dn(16)" )
			)
			( pin "U2D1.AY9"
				( objectStatus "@baseboard_fab2_lib.baseboard_fab2(sch_1):page67_i132:upi0_rx_dn(17)" )
			)
			( pin "U2D1.BD9"
				( objectStatus "@baseboard_fab2_lib.baseboard_fab2(sch_1):page67_i132:upi0_rx_dn(18)" )
			)
			( pin "U2D1.BB11"
				( objectStatus "@baseboard_fab2_lib.baseboard_fab2(sch_1):page67_i132:upi0_rx_dn(19)" )
			)
			( pin "U2D1.AB9"
				( objectStatus "@baseboard_fab2_lib.baseboard_fab2(sch_1):page67_i132:upi0_rx_dp(0)" )
			)
			( pin "U2D1.AC8"
				( objectStatus "@baseboard_fab2_lib.baseboard_fab2(sch_1):page67_i132:upi0_rx_dp(1)" )
			)
			( pin "U2D1.AA6"
				( objectStatus "@baseboard_fab2_lib.baseboard_fab2(sch_1):page67_i132:upi0_rx_dp(2)" )
			)
			( pin "U2D1.AC6"
				( objectStatus "@baseboard_fab2_lib.baseboard_fab2(sch_1):page67_i132:upi0_rx_dp(3)" )
			)
			( pin "U2D1.AG6"
				( objectStatus "@baseboard_fab2_lib.baseboard_fab2(sch_1):page67_i132:upi0_rx_dp(4)" )
			)
			( pin "U2D1.AF7"
				( objectStatus "@baseboard_fab2_lib.baseboard_fab2(sch_1):page67_i132:upi0_rx_dp(5)" )
			)
			( pin "U2D1.AH7"
				( objectStatus "@baseboard_fab2_lib.baseboard_fab2(sch_1):page67_i132:upi0_rx_dp(6)" )
			)
			( pin "U2D1.AK5"
				( objectStatus "@baseboard_fab2_lib.baseboard_fab2(sch_1):page67_i132:upi0_rx_dp(7)" )
			)
			( pin "U2D1.AM7"
				( objectStatus "@baseboard_fab2_lib.baseboard_fab2(sch_1):page67_i132:upi0_rx_dp(8)" )
			)
			( pin "U2D1.AL8"
				( objectStatus "@baseboard_fab2_lib.baseboard_fab2(sch_1):page67_i132:upi0_rx_dp(9)" )
			)
			( pin "U2D1.AN8"
				( objectStatus "@baseboard_fab2_lib.baseboard_fab2(sch_1):page67_i132:upi0_rx_dp(10)" )
			)
			( pin "U2D1.AU8"
				( objectStatus "@baseboard_fab2_lib.baseboard_fab2(sch_1):page67_i132:upi0_rx_dp(11)" )
			)
			( pin "U2D1.AT9"
				( objectStatus "@baseboard_fab2_lib.baseboard_fab2(sch_1):page67_i132:upi0_rx_dp(12)" )
			)
			( pin "U2D1.AY7"
				( objectStatus "@baseboard_fab2_lib.baseboard_fab2(sch_1):page67_i132:upi0_rx_dp(13)" )
			)
			( pin "U2D1.BB7"
				( objectStatus "@baseboard_fab2_lib.baseboard_fab2(sch_1):page67_i132:upi0_rx_dp(14)" )
			)
			( pin "U2D1.BF7"
				( objectStatus "@baseboard_fab2_lib.baseboard_fab2(sch_1):page67_i132:upi0_rx_dp(15)" )
			)
			( pin "U2D1.AV9"
				( objectStatus "@baseboard_fab2_lib.baseboard_fab2(sch_1):page67_i132:upi0_rx_dp(16)" )
			)
			( pin "U2D1.BB9"
				( objectStatus "@baseboard_fab2_lib.baseboard_fab2(sch_1):page67_i132:upi0_rx_dp(17)" )
			)
			( pin "U2D1.BC10"
				( objectStatus "@baseboard_fab2_lib.baseboard_fab2(sch_1):page67_i132:upi0_rx_dp(18)" )
			)
			( pin "U2D1.BA10"
				( objectStatus "@baseboard_fab2_lib.baseboard_fab2(sch_1):page67_i132:upi0_rx_dp(19)" )
			)
			( pin "U2D1.N2"
				( objectStatus "@baseboard_fab2_lib.baseboard_fab2(sch_1):page67_i132:upi0_tx_dn(0)" )
			)
			( pin "U2D1.P1"
				( objectStatus "@baseboard_fab2_lib.baseboard_fab2(sch_1):page67_i132:upi0_tx_dn(1)" )
			)
			( pin "U2D1.V3"
				( objectStatus "@baseboard_fab2_lib.baseboard_fab2(sch_1):page67_i132:upi0_tx_dn(2)" )
			)
			( pin "U2D1.Y1"
				( objectStatus "@baseboard_fab2_lib.baseboard_fab2(sch_1):page67_i132:upi0_tx_dn(3)" )
			)
			( pin "U2D1.AB3"
				( objectStatus "@baseboard_fab2_lib.baseboard_fab2(sch_1):page67_i132:upi0_tx_dn(4)" )
			)
			( pin "U2D1.AC2"
				( objectStatus "@baseboard_fab2_lib.baseboard_fab2(sch_1):page67_i132:upi0_tx_dn(5)" )
			)
			( pin "U2D1.AG4"
				( objectStatus "@baseboard_fab2_lib.baseboard_fab2(sch_1):page67_i132:upi0_tx_dn(6)" )
			)
			( pin "U2D1.AE2"
				( objectStatus "@baseboard_fab2_lib.baseboard_fab2(sch_1):page67_i132:upi0_tx_dn(7)" )
			)
			( pin "U2D1.AH3"
				( objectStatus "@baseboard_fab2_lib.baseboard_fab2(sch_1):page67_i132:upi0_tx_dn(8)" )
			)
			( pin "U2D1.AL2"
				( objectStatus "@baseboard_fab2_lib.baseboard_fab2(sch_1):page67_i132:upi0_tx_dn(9)" )
			)
			( pin "U2D1.AM3"
				( objectStatus "@baseboard_fab2_lib.baseboard_fab2(sch_1):page67_i132:upi0_tx_dn(10)" )
			)
			( pin "U2D1.AN4"
				( objectStatus "@baseboard_fab2_lib.baseboard_fab2(sch_1):page67_i132:upi0_tx_dn(11)" )
			)
			( pin "U2D1.AT1"
				( objectStatus "@baseboard_fab2_lib.baseboard_fab2(sch_1):page67_i132:upi0_tx_dn(12)" )
			)
			( pin "U2D1.AT3"
				( objectStatus "@baseboard_fab2_lib.baseboard_fab2(sch_1):page67_i132:upi0_tx_dn(13)" )
			)
			( pin "U2D1.AU4"
				( objectStatus "@baseboard_fab2_lib.baseboard_fab2(sch_1):page67_i132:upi0_tx_dn(14)" )
			)
			( pin "U2D1.AV5"
				( objectStatus "@baseboard_fab2_lib.baseboard_fab2(sch_1):page67_i132:upi0_tx_dn(15)" )
			)
			( pin "U2D1.BA4"
				( objectStatus "@baseboard_fab2_lib.baseboard_fab2(sch_1):page67_i132:upi0_tx_dn(16)" )
			)
			( pin "U2D1.BB3"
				( objectStatus "@baseboard_fab2_lib.baseboard_fab2(sch_1):page67_i132:upi0_tx_dn(17)" )
			)
			( pin "U2D1.BF3"
				( objectStatus "@baseboard_fab2_lib.baseboard_fab2(sch_1):page67_i132:upi0_tx_dn(18)" )
			)
			( pin "U2D1.BG4"
				( objectStatus "@baseboard_fab2_lib.baseboard_fab2(sch_1):page67_i132:upi0_tx_dn(19)" )
			)
			( pin "U2D1.M1"
				( objectStatus "@baseboard_fab2_lib.baseboard_fab2(sch_1):page67_i132:upi0_tx_dp(0)" )
			)
			( pin "U2D1.T1"
				( objectStatus "@baseboard_fab2_lib.baseboard_fab2(sch_1):page67_i132:upi0_tx_dp(1)" )
			)
			( pin "U2D1.Y3"
				( objectStatus "@baseboard_fab2_lib.baseboard_fab2(sch_1):page67_i132:upi0_tx_dp(2)" )
			)
			( pin "U2D1.W2"
				( objectStatus "@baseboard_fab2_lib.baseboard_fab2(sch_1):page67_i132:upi0_tx_dp(3)" )
			)
			( pin "U2D1.AA2"
				( objectStatus "@baseboard_fab2_lib.baseboard_fab2(sch_1):page67_i132:upi0_tx_dp(4)" )
			)
			( pin "U2D1.AD1"
				( objectStatus "@baseboard_fab2_lib.baseboard_fab2(sch_1):page67_i132:upi0_tx_dp(5)" )
			)
			( pin "U2D1.AF3"
				( objectStatus "@baseboard_fab2_lib.baseboard_fab2(sch_1):page67_i132:upi0_tx_dp(6)" )
			)
			( pin "U2D1.AG2"
				( objectStatus "@baseboard_fab2_lib.baseboard_fab2(sch_1):page67_i132:upi0_tx_dp(7)" )
			)
			( pin "U2D1.AJ2"
				( objectStatus "@baseboard_fab2_lib.baseboard_fab2(sch_1):page67_i132:upi0_tx_dp(8)" )
			)
			( pin "U2D1.AK1"
				( objectStatus "@baseboard_fab2_lib.baseboard_fab2(sch_1):page67_i132:upi0_tx_dp(9)" )
			)
			( pin "U2D1.AK3"
				( objectStatus "@baseboard_fab2_lib.baseboard_fab2(sch_1):page67_i132:upi0_tx_dp(10)" )
			)
			( pin "U2D1.AP3"
				( objectStatus "@baseboard_fab2_lib.baseboard_fab2(sch_1):page67_i132:upi0_tx_dp(11)" )
			)
			( pin "U2D1.AP1"
				( objectStatus "@baseboard_fab2_lib.baseboard_fab2(sch_1):page67_i132:upi0_tx_dp(12)" )
			)
			( pin "U2D1.AR2"
				( objectStatus "@baseboard_fab2_lib.baseboard_fab2(sch_1):page67_i132:upi0_tx_dp(13)" )
			)
			( pin "U2D1.AR4"
				( objectStatus "@baseboard_fab2_lib.baseboard_fab2(sch_1):page67_i132:upi0_tx_dp(14)" )
			)
			( pin "U2D1.AW4"
				( objectStatus "@baseboard_fab2_lib.baseboard_fab2(sch_1):page67_i132:upi0_tx_dp(15)" )
			)
			( pin "U2D1.AY3"
				( objectStatus "@baseboard_fab2_lib.baseboard_fab2(sch_1):page67_i132:upi0_tx_dp(16)" )
			)
			( pin "U2D1.BC2"
				( objectStatus "@baseboard_fab2_lib.baseboard_fab2(sch_1):page67_i132:upi0_tx_dp(17)" )
			)
			( pin "U2D1.BD3"
				( objectStatus "@baseboard_fab2_lib.baseboard_fab2(sch_1):page67_i132:upi0_tx_dp(18)" )
			)
			( pin "U2D1.BH3"
				( objectStatus "@baseboard_fab2_lib.baseboard_fab2(sch_1):page67_i132:upi0_tx_dp(19)" )
			)
			( pin "U2D1.T5"
				( objectStatus "@baseboard_fab2_lib.baseboard_fab2(sch_1):page68_i125:upi1_rx_dn(0)" )
			)
			( pin "U2D1.P7"
				( objectStatus "@baseboard_fab2_lib.baseboard_fab2(sch_1):page68_i125:upi1_rx_dn(1)" )
			)
			( pin "U2D1.V7"
				( objectStatus "@baseboard_fab2_lib.baseboard_fab2(sch_1):page68_i125:upi1_rx_dn(2)" )
			)
			( pin "U2D1.T9"
				( objectStatus "@baseboard_fab2_lib.baseboard_fab2(sch_1):page68_i125:upi1_rx_dn(3)" )
			)
			( pin "U2D1.P9"
				( objectStatus "@baseboard_fab2_lib.baseboard_fab2(sch_1):page68_i125:upi1_rx_dn(4)" )
			)
			( pin "U2D1.R10"
				( objectStatus "@baseboard_fab2_lib.baseboard_fab2(sch_1):page68_i125:upi1_rx_dn(5)" )
			)
			( pin "U2D1.U12"
				( objectStatus "@baseboard_fab2_lib.baseboard_fab2(sch_1):page68_i125:upi1_rx_dn(6)" )
			)
			( pin "U2D1.L12"
				( objectStatus "@baseboard_fab2_lib.baseboard_fab2(sch_1):page68_i125:upi1_rx_dn(7)" )
			)
			( pin "U2D1.N14"
				( objectStatus "@baseboard_fab2_lib.baseboard_fab2(sch_1):page68_i125:upi1_rx_dn(8)" )
			)
			( pin "U2D1.R12"
				( objectStatus "@baseboard_fab2_lib.baseboard_fab2(sch_1):page68_i125:upi1_rx_dn(9)" )
			)
			( pin "U2D1.R16"
				( objectStatus "@baseboard_fab2_lib.baseboard_fab2(sch_1):page68_i125:upi1_rx_dn(10)" )
			)
			( pin "U2D1.P17"
				( objectStatus "@baseboard_fab2_lib.baseboard_fab2(sch_1):page68_i125:upi1_rx_dn(11)" )
			)
			( pin "U2D1.U16"
				( objectStatus "@baseboard_fab2_lib.baseboard_fab2(sch_1):page68_i125:upi1_rx_dn(12)" )
			)
			( pin "U2D1.W18"
				( objectStatus "@baseboard_fab2_lib.baseboard_fab2(sch_1):page68_i125:upi1_rx_dn(13)" )
			)
			( pin "U2D1.R20"
				( objectStatus "@baseboard_fab2_lib.baseboard_fab2(sch_1):page68_i125:upi1_rx_dn(14)" )
			)
			( pin "U2D1.U18"
				( objectStatus "@baseboard_fab2_lib.baseboard_fab2(sch_1):page68_i125:upi1_rx_dn(15)" )
			)
			( pin "U2D1.P21"
				( objectStatus "@baseboard_fab2_lib.baseboard_fab2(sch_1):page68_i125:upi1_rx_dn(16)" )
			)
			( pin "U2D1.V19"
				( objectStatus "@baseboard_fab2_lib.baseboard_fab2(sch_1):page68_i125:upi1_rx_dn(17)" )
			)
			( pin "U2D1.Y21"
				( objectStatus "@baseboard_fab2_lib.baseboard_fab2(sch_1):page68_i125:upi1_rx_dn(18)" )
			)
			( pin "U2D1.AB19"
				( objectStatus "@baseboard_fab2_lib.baseboard_fab2(sch_1):page68_i125:upi1_rx_dn(19)" )
			)
			( pin "U2D1.R6"
				( objectStatus "@baseboard_fab2_lib.baseboard_fab2(sch_1):page68_i125:upi1_rx_dp(0)" )
			)
			( pin "U2D1.T7"
				( objectStatus "@baseboard_fab2_lib.baseboard_fab2(sch_1):page68_i125:upi1_rx_dp(1)" )
			)
			( pin "U2D1.U8"
				( objectStatus "@baseboard_fab2_lib.baseboard_fab2(sch_1):page68_i125:upi1_rx_dp(2)" )
			)
			( pin "U2D1.R8"
				( objectStatus "@baseboard_fab2_lib.baseboard_fab2(sch_1):page68_i125:upi1_rx_dp(3)" )
			)
			( pin "U2D1.N10"
				( objectStatus "@baseboard_fab2_lib.baseboard_fab2(sch_1):page68_i125:upi1_rx_dp(4)" )
			)
			( pin "U2D1.U10"
				( objectStatus "@baseboard_fab2_lib.baseboard_fab2(sch_1):page68_i125:upi1_rx_dp(5)" )
			)
			( pin "U2D1.T11"
				( objectStatus "@baseboard_fab2_lib.baseboard_fab2(sch_1):page68_i125:upi1_rx_dp(6)" )
			)
			( pin "U2D1.N12"
				( objectStatus "@baseboard_fab2_lib.baseboard_fab2(sch_1):page68_i125:upi1_rx_dp(7)" )
			)
			( pin "U2D1.M13"
				( objectStatus "@baseboard_fab2_lib.baseboard_fab2(sch_1):page68_i125:upi1_rx_dp(8)" )
			)
			( pin "U2D1.P13"
				( objectStatus "@baseboard_fab2_lib.baseboard_fab2(sch_1):page68_i125:upi1_rx_dp(9)" )
			)
			( pin "U2D1.T15"
				( objectStatus "@baseboard_fab2_lib.baseboard_fab2(sch_1):page68_i125:upi1_rx_dp(10)" )
			)
			( pin "U2D1.N16"
				( objectStatus "@baseboard_fab2_lib.baseboard_fab2(sch_1):page68_i125:upi1_rx_dp(11)" )
			)
			( pin "U2D1.W16"
				( objectStatus "@baseboard_fab2_lib.baseboard_fab2(sch_1):page68_i125:upi1_rx_dp(12)" )
			)
			( pin "U2D1.V17"
				( objectStatus "@baseboard_fab2_lib.baseboard_fab2(sch_1):page68_i125:upi1_rx_dp(13)" )
			)
			( pin "U2D1.P19"
				( objectStatus "@baseboard_fab2_lib.baseboard_fab2(sch_1):page68_i125:upi1_rx_dp(14)" )
			)
			( pin "U2D1.T19"
				( objectStatus "@baseboard_fab2_lib.baseboard_fab2(sch_1):page68_i125:upi1_rx_dp(15)" )
			)
			( pin "U2D1.T21"
				( objectStatus "@baseboard_fab2_lib.baseboard_fab2(sch_1):page68_i125:upi1_rx_dp(16)" )
			)
			( pin "U2D1.Y19"
				( objectStatus "@baseboard_fab2_lib.baseboard_fab2(sch_1):page68_i125:upi1_rx_dp(17)" )
			)
			( pin "U2D1.W20"
				( objectStatus "@baseboard_fab2_lib.baseboard_fab2(sch_1):page68_i125:upi1_rx_dp(18)" )
			)
			( pin "U2D1.AA20"
				( objectStatus "@baseboard_fab2_lib.baseboard_fab2(sch_1):page68_i125:upi1_rx_dp(19)" )
			)
			( pin "U2D1.M3"
				( objectStatus "@baseboard_fab2_lib.baseboard_fab2(sch_1):page68_i125:upi1_tx_dn(0)" )
			)
			( pin "U2D1.L4"
				( objectStatus "@baseboard_fab2_lib.baseboard_fab2(sch_1):page68_i125:upi1_tx_dn(1)" )
			)
			( pin "U2D1.K5"
				( objectStatus "@baseboard_fab2_lib.baseboard_fab2(sch_1):page68_i125:upi1_tx_dn(2)" )
			)
			( pin "U2D1.J6"
				( objectStatus "@baseboard_fab2_lib.baseboard_fab2(sch_1):page68_i125:upi1_tx_dn(3)" )
			)
			( pin "U2D1.G6"
				( objectStatus "@baseboard_fab2_lib.baseboard_fab2(sch_1):page68_i125:upi1_tx_dn(4)" )
			)
			( pin "U2D1.H7"
				( objectStatus "@baseboard_fab2_lib.baseboard_fab2(sch_1):page68_i125:upi1_tx_dn(5)" )
			)
			( pin "U2D1.K9"
				( objectStatus "@baseboard_fab2_lib.baseboard_fab2(sch_1):page68_i125:upi1_tx_dn(6)" )
			)
			( pin "U2D1.D9"
				( objectStatus "@baseboard_fab2_lib.baseboard_fab2(sch_1):page68_i125:upi1_tx_dn(7)" )
			)
			( pin "U2D1.F11"
				( objectStatus "@baseboard_fab2_lib.baseboard_fab2(sch_1):page68_i125:upi1_tx_dn(8)" )
			)
			( pin "U2D1.G10"
				( objectStatus "@baseboard_fab2_lib.baseboard_fab2(sch_1):page68_i125:upi1_tx_dn(9)" )
			)
			( pin "U2D1.E12"
				( objectStatus "@baseboard_fab2_lib.baseboard_fab2(sch_1):page68_i125:upi1_tx_dn(10)" )
			)
			( pin "U2D1.G14"
				( objectStatus "@baseboard_fab2_lib.baseboard_fab2(sch_1):page68_i125:upi1_tx_dn(11)" )
			)
			( pin "U2D1.D15"
				( objectStatus "@baseboard_fab2_lib.baseboard_fab2(sch_1):page68_i125:upi1_tx_dn(12)" )
			)
			( pin "U2D1.F15"
				( objectStatus "@baseboard_fab2_lib.baseboard_fab2(sch_1):page68_i125:upi1_tx_dn(13)" )
			)
			( pin "U2D1.H17"
				( objectStatus "@baseboard_fab2_lib.baseboard_fab2(sch_1):page68_i125:upi1_tx_dn(14)" )
			)
			( pin "U2D1.K19"
				( objectStatus "@baseboard_fab2_lib.baseboard_fab2(sch_1):page68_i125:upi1_tx_dn(15)" )
			)
			( pin "U2D1.G18"
				( objectStatus "@baseboard_fab2_lib.baseboard_fab2(sch_1):page68_i125:upi1_tx_dn(16)" )
			)
			( pin "U2D1.J20"
				( objectStatus "@baseboard_fab2_lib.baseboard_fab2(sch_1):page68_i125:upi1_tx_dn(17)" )
			)
			( pin "U2D1.F21"
				( objectStatus "@baseboard_fab2_lib.baseboard_fab2(sch_1):page68_i125:upi1_tx_dn(18)" )
			)
			( pin "U2D1.H21"
				( objectStatus "@baseboard_fab2_lib.baseboard_fab2(sch_1):page68_i125:upi1_tx_dn(19)" )
			)
			( pin "U2D1.P3"
				( objectStatus "@baseboard_fab2_lib.baseboard_fab2(sch_1):page68_i125:upi1_tx_dp(0)" )
			)
			( pin "U2D1.K3"
				( objectStatus "@baseboard_fab2_lib.baseboard_fab2(sch_1):page68_i125:upi1_tx_dp(1)" )
			)
			( pin "U2D1.M5"
				( objectStatus "@baseboard_fab2_lib.baseboard_fab2(sch_1):page68_i125:upi1_tx_dp(2)" )
			)
			( pin "U2D1.H5"
				( objectStatus "@baseboard_fab2_lib.baseboard_fab2(sch_1):page68_i125:upi1_tx_dp(3)" )
			)
			( pin "U2D1.F7"
				( objectStatus "@baseboard_fab2_lib.baseboard_fab2(sch_1):page68_i125:upi1_tx_dp(4)" )
			)
			( pin "U2D1.K7"
				( objectStatus "@baseboard_fab2_lib.baseboard_fab2(sch_1):page68_i125:upi1_tx_dp(5)" )
			)
			( pin "U2D1.J8"
				( objectStatus "@baseboard_fab2_lib.baseboard_fab2(sch_1):page68_i125:upi1_tx_dp(6)" )
			)
			( pin "U2D1.F9"
				( objectStatus "@baseboard_fab2_lib.baseboard_fab2(sch_1):page68_i125:upi1_tx_dp(7)" )
			)
			( pin "U2D1.E10"
				( objectStatus "@baseboard_fab2_lib.baseboard_fab2(sch_1):page68_i125:upi1_tx_dp(8)" )
			)
			( pin "U2D1.H9"
				( objectStatus "@baseboard_fab2_lib.baseboard_fab2(sch_1):page68_i125:upi1_tx_dp(9)" )
			)
			( pin "U2D1.G12"
				( objectStatus "@baseboard_fab2_lib.baseboard_fab2(sch_1):page68_i125:upi1_tx_dp(10)" )
			)
			( pin "U2D1.F13"
				( objectStatus "@baseboard_fab2_lib.baseboard_fab2(sch_1):page68_i125:upi1_tx_dp(11)" )
			)
			( pin "U2D1.E14"
				( objectStatus "@baseboard_fab2_lib.baseboard_fab2(sch_1):page68_i125:upi1_tx_dp(12)" )
			)
			( pin "U2D1.H15"
				( objectStatus "@baseboard_fab2_lib.baseboard_fab2(sch_1):page68_i125:upi1_tx_dp(13)" )
			)
			( pin "U2D1.G16"
				( objectStatus "@baseboard_fab2_lib.baseboard_fab2(sch_1):page68_i125:upi1_tx_dp(14)" )
			)
			( pin "U2D1.L18"
				( objectStatus "@baseboard_fab2_lib.baseboard_fab2(sch_1):page68_i125:upi1_tx_dp(15)" )
			)
			( pin "U2D1.J18"
				( objectStatus "@baseboard_fab2_lib.baseboard_fab2(sch_1):page68_i125:upi1_tx_dp(16)" )
			)
			( pin "U2D1.H19"
				( objectStatus "@baseboard_fab2_lib.baseboard_fab2(sch_1):page68_i125:upi1_tx_dp(17)" )
			)
			( pin "U2D1.G20"
				( objectStatus "@baseboard_fab2_lib.baseboard_fab2(sch_1):page68_i125:upi1_tx_dp(18)" )
			)
			( pin "U2D1.K21"
				( objectStatus "@baseboard_fab2_lib.baseboard_fab2(sch_1):page68_i125:upi1_tx_dp(19)" )
			)
			( pin "U2D1.DF23"
				( objectStatus "@baseboard_fab2_lib.baseboard_fab2(sch_1):page69_i1:upi2_rx_dn(0)" )
			)
			( pin "U2D1.DE22"
				( objectStatus "@baseboard_fab2_lib.baseboard_fab2(sch_1):page69_i1:upi2_rx_dn(1)" )
			)
			( pin "U2D1.DC22"
				( objectStatus "@baseboard_fab2_lib.baseboard_fab2(sch_1):page69_i1:upi2_rx_dn(2)" )
			)
			( pin "U2D1.DB21"
				( objectStatus "@baseboard_fab2_lib.baseboard_fab2(sch_1):page69_i1:upi2_rx_dn(3)" )
			)
			( pin "U2D1.DD19"
				( objectStatus "@baseboard_fab2_lib.baseboard_fab2(sch_1):page69_i1:upi2_rx_dn(4)" )
			)
			( pin "U2D1.DA20"
				( objectStatus "@baseboard_fab2_lib.baseboard_fab2(sch_1):page69_i1:upi2_rx_dn(5)" )
			)
			( pin "U2D1.CW20"
				( objectStatus "@baseboard_fab2_lib.baseboard_fab2(sch_1):page69_i1:upi2_rx_dn(6)" )
			)
			( pin "U2D1.CV19"
				( objectStatus "@baseboard_fab2_lib.baseboard_fab2(sch_1):page69_i1:upi2_rx_dn(7)" )
			)
			( pin "U2D1.CT21"
				( objectStatus "@baseboard_fab2_lib.baseboard_fab2(sch_1):page69_i1:upi2_rx_dn(8)" )
			)
			( pin "U2D1.CR18"
				( objectStatus "@baseboard_fab2_lib.baseboard_fab2(sch_1):page69_i1:upi2_rx_dn(9)" )
			)
			( pin "U2D1.CN20"
				( objectStatus "@baseboard_fab2_lib.baseboard_fab2(sch_1):page69_i1:upi2_rx_dn(10)" )
			)
			( pin "U2D1.CP21"
				( objectStatus "@baseboard_fab2_lib.baseboard_fab2(sch_1):page69_i1:upi2_rx_dn(11)" )
			)
			( pin "U2D1.CL16"
				( objectStatus "@baseboard_fab2_lib.baseboard_fab2(sch_1):page69_i1:upi2_rx_dn(12)" )
			)
			( pin "U2D1.CJ18"
				( objectStatus "@baseboard_fab2_lib.baseboard_fab2(sch_1):page69_i1:upi2_rx_dn(13)" )
			)
			( pin "U2D1.CH17"
				( objectStatus "@baseboard_fab2_lib.baseboard_fab2(sch_1):page69_i1:upi2_rx_dn(14)" )
			)
			( pin "U2D1.CE16"
				( objectStatus "@baseboard_fab2_lib.baseboard_fab2(sch_1):page69_i1:upi2_rx_dn(15)" )
			)
			( pin "U2D1.CD15"
				( objectStatus "@baseboard_fab2_lib.baseboard_fab2(sch_1):page69_i1:upi2_rx_dn(16)" )
			)
			( pin "U2D1.CF17"
				( objectStatus "@baseboard_fab2_lib.baseboard_fab2(sch_1):page69_i1:upi2_rx_dn(17)" )
			)
			( pin "U2D1.CB15"
				( objectStatus "@baseboard_fab2_lib.baseboard_fab2(sch_1):page69_i1:upi2_rx_dn(18)" )
			)
			( pin "U2D1.BY17"
				( objectStatus "@baseboard_fab2_lib.baseboard_fab2(sch_1):page69_i1:upi2_rx_dn(19)" )
			)
			( pin "U2D1.DG22"
				( objectStatus "@baseboard_fab2_lib.baseboard_fab2(sch_1):page69_i1:upi2_rx_dp(0)" )
			)
			( pin "U2D1.DD21"
				( objectStatus "@baseboard_fab2_lib.baseboard_fab2(sch_1):page69_i1:upi2_rx_dp(1)" )
			)
			( pin "U2D1.DA22"
				( objectStatus "@baseboard_fab2_lib.baseboard_fab2(sch_1):page69_i1:upi2_rx_dp(2)" )
			)
			( pin "U2D1.DC20"
				( objectStatus "@baseboard_fab2_lib.baseboard_fab2(sch_1):page69_i1:upi2_rx_dp(3)" )
			)
			( pin "U2D1.DB19"
				( objectStatus "@baseboard_fab2_lib.baseboard_fab2(sch_1):page69_i1:upi2_rx_dp(4)" )
			)
			( pin "U2D1.CY19"
				( objectStatus "@baseboard_fab2_lib.baseboard_fab2(sch_1):page69_i1:upi2_rx_dp(5)" )
			)
			( pin "U2D1.CU20"
				( objectStatus "@baseboard_fab2_lib.baseboard_fab2(sch_1):page69_i1:upi2_rx_dp(6)" )
			)
			( pin "U2D1.CW18"
				( objectStatus "@baseboard_fab2_lib.baseboard_fab2(sch_1):page69_i1:upi2_rx_dp(7)" )
			)
			( pin "U2D1.CR20"
				( objectStatus "@baseboard_fab2_lib.baseboard_fab2(sch_1):page69_i1:upi2_rx_dp(8)" )
			)
			( pin "U2D1.CN18"
				( objectStatus "@baseboard_fab2_lib.baseboard_fab2(sch_1):page69_i1:upi2_rx_dp(9)" )
			)
			( pin "U2D1.CP19"
				( objectStatus "@baseboard_fab2_lib.baseboard_fab2(sch_1):page69_i1:upi2_rx_dp(10)" )
			)
			( pin "U2D1.CM21"
				( objectStatus "@baseboard_fab2_lib.baseboard_fab2(sch_1):page69_i1:upi2_rx_dp(11)" )
			)
			( pin "U2D1.CJ16"
				( objectStatus "@baseboard_fab2_lib.baseboard_fab2(sch_1):page69_i1:upi2_rx_dp(12)" )
			)
			( pin "U2D1.CK17"
				( objectStatus "@baseboard_fab2_lib.baseboard_fab2(sch_1):page69_i1:upi2_rx_dp(13)" )
			)
			( pin "U2D1.CG16"
				( objectStatus "@baseboard_fab2_lib.baseboard_fab2(sch_1):page69_i1:upi2_rx_dp(14)" )
			)
			( pin "U2D1.CF15"
				( objectStatus "@baseboard_fab2_lib.baseboard_fab2(sch_1):page69_i1:upi2_rx_dp(15)" )
			)
			( pin "U2D1.CC14"
				( objectStatus "@baseboard_fab2_lib.baseboard_fab2(sch_1):page69_i1:upi2_rx_dp(16)" )
			)
			( pin "U2D1.CD17"
				( objectStatus "@baseboard_fab2_lib.baseboard_fab2(sch_1):page69_i1:upi2_rx_dp(17)" )
			)
			( pin "U2D1.BY15"
				( objectStatus "@baseboard_fab2_lib.baseboard_fab2(sch_1):page69_i1:upi2_rx_dp(18)" )
			)
			( pin "U2D1.CA16"
				( objectStatus "@baseboard_fab2_lib.baseboard_fab2(sch_1):page69_i1:upi2_rx_dp(19)" )
			)
			( pin "U2D1.DT21"
				( objectStatus "@baseboard_fab2_lib.baseboard_fab2(sch_1):page69_i1:upi2_tx_dn(0)" )
			)
			( pin "U2D1.DM21"
				( objectStatus "@baseboard_fab2_lib.baseboard_fab2(sch_1):page69_i1:upi2_tx_dn(1)" )
			)
			( pin "U2D1.DL20"
				( objectStatus "@baseboard_fab2_lib.baseboard_fab2(sch_1):page69_i1:upi2_tx_dn(2)" )
			)
			( pin "U2D1.DG20"
				( objectStatus "@baseboard_fab2_lib.baseboard_fab2(sch_1):page69_i1:upi2_tx_dn(3)" )
			)
			( pin "U2D1.DH19"
				( objectStatus "@baseboard_fab2_lib.baseboard_fab2(sch_1):page69_i1:upi2_tx_dn(4)" )
			)
			( pin "U2D1.DK17"
				( objectStatus "@baseboard_fab2_lib.baseboard_fab2(sch_1):page69_i1:upi2_tx_dn(5)" )
			)
			( pin "U2D1.DG18"
				( objectStatus "@baseboard_fab2_lib.baseboard_fab2(sch_1):page69_i1:upi2_tx_dn(6)" )
			)
			( pin "U2D1.DD17"
				( objectStatus "@baseboard_fab2_lib.baseboard_fab2(sch_1):page69_i1:upi2_tx_dn(7)" )
			)
			( pin "U2D1.DF15"
				( objectStatus "@baseboard_fab2_lib.baseboard_fab2(sch_1):page69_i1:upi2_tx_dn(8)" )
			)
			( pin "U2D1.DC16"
				( objectStatus "@baseboard_fab2_lib.baseboard_fab2(sch_1):page69_i1:upi2_tx_dn(9)" )
			)
			( pin "U2D1.DA16"
				( objectStatus "@baseboard_fab2_lib.baseboard_fab2(sch_1):page69_i1:upi2_tx_dn(10)" )
			)
			( pin "U2D1.CW14"
				( objectStatus "@baseboard_fab2_lib.baseboard_fab2(sch_1):page69_i1:upi2_tx_dn(11)" )
			)
			( pin "U2D1.CU14"
				( objectStatus "@baseboard_fab2_lib.baseboard_fab2(sch_1):page69_i1:upi2_tx_dn(12)" )
			)
			( pin "U2D1.CM13"
				( objectStatus "@baseboard_fab2_lib.baseboard_fab2(sch_1):page69_i1:upi2_tx_dn(13)" )
			)
			( pin "U2D1.CJ14"
				( objectStatus "@baseboard_fab2_lib.baseboard_fab2(sch_1):page69_i1:upi2_tx_dn(14)" )
			)
			( pin "U2D1.CF13"
				( objectStatus "@baseboard_fab2_lib.baseboard_fab2(sch_1):page69_i1:upi2_tx_dn(15)" )
			)
			( pin "U2D1.CH11"
				( objectStatus "@baseboard_fab2_lib.baseboard_fab2(sch_1):page69_i1:upi2_tx_dn(16)" )
			)
			( pin "U2D1.CE12"
				( objectStatus "@baseboard_fab2_lib.baseboard_fab2(sch_1):page69_i1:upi2_tx_dn(17)" )
			)
			( pin "U2D1.CC10"
				( objectStatus "@baseboard_fab2_lib.baseboard_fab2(sch_1):page69_i1:upi2_tx_dn(18)" )
			)
			( pin "U2D1.CC12"
				( objectStatus "@baseboard_fab2_lib.baseboard_fab2(sch_1):page69_i1:upi2_tx_dn(19)" )
			)
			( pin "U2D1.DP21"
				( objectStatus "@baseboard_fab2_lib.baseboard_fab2(sch_1):page69_i1:upi2_tx_dp(0)" )
			)
			( pin "U2D1.DN20"
				( objectStatus "@baseboard_fab2_lib.baseboard_fab2(sch_1):page69_i1:upi2_tx_dp(1)" )
			)
			( pin "U2D1.DK19"
				( objectStatus "@baseboard_fab2_lib.baseboard_fab2(sch_1):page69_i1:upi2_tx_dp(2)" )
			)
			( pin "U2D1.DJ20"
				( objectStatus "@baseboard_fab2_lib.baseboard_fab2(sch_1):page69_i1:upi2_tx_dp(3)" )
			)
			( pin "U2D1.DJ18"
				( objectStatus "@baseboard_fab2_lib.baseboard_fab2(sch_1):page69_i1:upi2_tx_dp(4)" )
			)
			( pin "U2D1.DH17"
				( objectStatus "@baseboard_fab2_lib.baseboard_fab2(sch_1):page69_i1:upi2_tx_dp(5)" )
			)
			( pin "U2D1.DF17"
				( objectStatus "@baseboard_fab2_lib.baseboard_fab2(sch_1):page69_i1:upi2_tx_dp(6)" )
			)
			( pin "U2D1.DE16"
				( objectStatus "@baseboard_fab2_lib.baseboard_fab2(sch_1):page69_i1:upi2_tx_dp(7)" )
			)
			( pin "U2D1.DD15"
				( objectStatus "@baseboard_fab2_lib.baseboard_fab2(sch_1):page69_i1:upi2_tx_dp(8)" )
			)
			( pin "U2D1.DB15"
				( objectStatus "@baseboard_fab2_lib.baseboard_fab2(sch_1):page69_i1:upi2_tx_dp(9)" )
			)
			( pin "U2D1.CW16"
				( objectStatus "@baseboard_fab2_lib.baseboard_fab2(sch_1):page69_i1:upi2_tx_dp(10)" )
			)
			( pin "U2D1.CV13"
				( objectStatus "@baseboard_fab2_lib.baseboard_fab2(sch_1):page69_i1:upi2_tx_dp(11)" )
			)
			( pin "U2D1.CR14"
				( objectStatus "@baseboard_fab2_lib.baseboard_fab2(sch_1):page69_i1:upi2_tx_dp(12)" )
			)
			( pin "U2D1.CK13"
				( objectStatus "@baseboard_fab2_lib.baseboard_fab2(sch_1):page69_i1:upi2_tx_dp(13)" )
			)
			( pin "U2D1.CH13"
				( objectStatus "@baseboard_fab2_lib.baseboard_fab2(sch_1):page69_i1:upi2_tx_dp(14)" )
			)
			( pin "U2D1.CG12"
				( objectStatus "@baseboard_fab2_lib.baseboard_fab2(sch_1):page69_i1:upi2_tx_dp(15)" )
			)
			( pin "U2D1.CF11"
				( objectStatus "@baseboard_fab2_lib.baseboard_fab2(sch_1):page69_i1:upi2_tx_dp(16)" )
			)
			( pin "U2D1.CD11"
				( objectStatus "@baseboard_fab2_lib.baseboard_fab2(sch_1):page69_i1:upi2_tx_dp(17)" )
			)
			( pin "U2D1.CB11"
				( objectStatus "@baseboard_fab2_lib.baseboard_fab2(sch_1):page69_i1:upi2_tx_dp(18)" )
			)
			( pin "U2D1.CA12"
				( objectStatus "@baseboard_fab2_lib.baseboard_fab2(sch_1):page69_i1:upi2_tx_dp(19)" )
			)
			( pin "U2D1.CH23"
				( objectStatus "@baseboard_fab2_lib.baseboard_fab2(sch_1):page70_i9:rsvd(92)" )
			)
			( pin "U2D1.CH21"
				( objectStatus "@baseboard_fab2_lib.baseboard_fab2(sch_1):page70_i9:rsvd(93)" )
			)
			( pin "U2D1.CG82"
				( objectStatus "@baseboard_fab2_lib.baseboard_fab2(sch_1):page70_i9:rsvd(94)" )
			)
			( pin "U2D1.CG78"
				( objectStatus "@baseboard_fab2_lib.baseboard_fab2(sch_1):page70_i9:rsvd(95)" )
			)
			( pin "U2D1.CG26"
				( objectStatus "@baseboard_fab2_lib.baseboard_fab2(sch_1):page70_i9:rsvd(96)" )
			)
			( pin "U2D1.CG24"
				( objectStatus "@baseboard_fab2_lib.baseboard_fab2(sch_1):page70_i9:rsvd(97)" )
			)
			( pin "U2D1.CG20"
				( objectStatus "@baseboard_fab2_lib.baseboard_fab2(sch_1):page70_i9:rsvd(98)" )
			)
			( pin "U2D1.CG10"
				( objectStatus "@baseboard_fab2_lib.baseboard_fab2(sch_1):page70_i9:rsvd(99)" )
			)
			( pin "U2D1.CF81"
				( objectStatus "@baseboard_fab2_lib.baseboard_fab2(sch_1):page70_i9:rsvd(100)" )
			)
			( pin "U2D1.CF79"
				( objectStatus "@baseboard_fab2_lib.baseboard_fab2(sch_1):page70_i9:rsvd(101)" )
			)
			( pin "U2D1.CF23"
				( objectStatus "@baseboard_fab2_lib.baseboard_fab2(sch_1):page70_i9:rsvd(102)" )
			)
			( pin "U2D1.CF21"
				( objectStatus "@baseboard_fab2_lib.baseboard_fab2(sch_1):page70_i9:rsvd(103)" )
			)
			( pin "U2D1.CF19"
				( objectStatus "@baseboard_fab2_lib.baseboard_fab2(sch_1):page70_i9:rsvd(104)" )
			)
			( pin "U2D1.CE80"
				( objectStatus "@baseboard_fab2_lib.baseboard_fab2(sch_1):page70_i9:rsvd(105)" )
			)
			( pin "U2D1.CE78"
				( objectStatus "@baseboard_fab2_lib.baseboard_fab2(sch_1):page70_i9:rsvd(106)" )
			)
			( pin "U2D1.CE22"
				( objectStatus "@baseboard_fab2_lib.baseboard_fab2(sch_1):page70_i9:rsvd(107)" )
			)
			( pin "U2D1.CD25"
				( objectStatus "@baseboard_fab2_lib.baseboard_fab2(sch_1):page70_i9:rsvd(108)" )
			)
			( pin "U2D1.CD21"
				( objectStatus "@baseboard_fab2_lib.baseboard_fab2(sch_1):page70_i9:rsvd(109)" )
			)
			( pin "U2D1.CD19"
				( objectStatus "@baseboard_fab2_lib.baseboard_fab2(sch_1):page70_i9:rsvd(110)" )
			)
			( pin "U2D1.CC6"
				( objectStatus "@baseboard_fab2_lib.baseboard_fab2(sch_1):page70_i9:rsvd(111)" )
			)
			( pin "U2D1.CC20"
				( objectStatus "@baseboard_fab2_lib.baseboard_fab2(sch_1):page70_i9:rsvd(112)" )
			)
			( pin "U2D1.CB5"
				( objectStatus "@baseboard_fab2_lib.baseboard_fab2(sch_1):page70_i9:rsvd(113)" )
			)
			( pin "U2D1.CB25"
				( objectStatus "@baseboard_fab2_lib.baseboard_fab2(sch_1):page70_i9:rsvd(114)" )
			)
			( pin "U2D1.CB21"
				( objectStatus "@baseboard_fab2_lib.baseboard_fab2(sch_1):page70_i9:rsvd(115)" )
			)
			( pin "U2D1.CB19"
				( objectStatus "@baseboard_fab2_lib.baseboard_fab2(sch_1):page70_i9:rsvd(116)" )
			)
			( pin "U2D1.CA24"
				( objectStatus "@baseboard_fab2_lib.baseboard_fab2(sch_1):page70_i9:rsvd(117)" )
			)
			( pin "U2D1.CA22"
				( objectStatus "@baseboard_fab2_lib.baseboard_fab2(sch_1):page70_i9:rsvd(118)" )
			)
			( pin "U2D1.BY25"
				( objectStatus "@baseboard_fab2_lib.baseboard_fab2(sch_1):page70_i9:rsvd(119)" )
			)
			( pin "U2D1.BY19"
				( objectStatus "@baseboard_fab2_lib.baseboard_fab2(sch_1):page70_i9:rsvd(120)" )
			)
			( pin "U2D1.BW22"
				( objectStatus "@baseboard_fab2_lib.baseboard_fab2(sch_1):page70_i9:rsvd(121)" )
			)
			( pin "U2D1.BW20"
				( objectStatus "@baseboard_fab2_lib.baseboard_fab2(sch_1):page70_i9:rsvd(122)" )
			)
			( pin "U2D1.BW10"
				( objectStatus "@baseboard_fab2_lib.baseboard_fab2(sch_1):page70_i9:rsvd(123)" )
			)
			( pin "U2D1.BV23"
				( objectStatus "@baseboard_fab2_lib.baseboard_fab2(sch_1):page70_i9:rsvd(124)" )
			)
			( pin "U2D1.BV21"
				( objectStatus "@baseboard_fab2_lib.baseboard_fab2(sch_1):page70_i9:rsvd(125)" )
			)
			( pin "U2D1.BV19"
				( objectStatus "@baseboard_fab2_lib.baseboard_fab2(sch_1):page70_i9:rsvd(126)" )
			)
			( pin "U2D1.BU22"
				( objectStatus "@baseboard_fab2_lib.baseboard_fab2(sch_1):page70_i9:rsvd(127)" )
			)
			( pin "U2D1.BU20"
				( objectStatus "@baseboard_fab2_lib.baseboard_fab2(sch_1):page70_i9:rsvd(128)" )
			)
			( pin "U2D1.BU18"
				( objectStatus "@baseboard_fab2_lib.baseboard_fab2(sch_1):page70_i9:rsvd(129)" )
			)
			( pin "U2D1.BR24"
				( objectStatus "@baseboard_fab2_lib.baseboard_fab2(sch_1):page70_i9:rsvd(130)" )
			)
			( pin "U2D1.BR22"
				( objectStatus "@baseboard_fab2_lib.baseboard_fab2(sch_1):page70_i9:rsvd(131)" )
			)
			( pin "U2D1.BP21"
				( objectStatus "@baseboard_fab2_lib.baseboard_fab2(sch_1):page70_i9:rsvd(132)" )
			)
			( pin "U2D1.BP17"
				( objectStatus "@baseboard_fab2_lib.baseboard_fab2(sch_1):page70_i9:rsvd(133)" )
			)
			( pin "U2D1.BN18"
				( objectStatus "@baseboard_fab2_lib.baseboard_fab2(sch_1):page70_i9:rsvd(134)" )
			)
			( pin "U2D1.BM19"
				( objectStatus "@baseboard_fab2_lib.baseboard_fab2(sch_1):page70_i9:rsvd(135)" )
			)
			( pin "U2D1.BM17"
				( objectStatus "@baseboard_fab2_lib.baseboard_fab2(sch_1):page70_i9:rsvd(136)" )
			)
			( pin "U2D1.BL20"
				( objectStatus "@baseboard_fab2_lib.baseboard_fab2(sch_1):page70_i9:rsvd(137)" )
			)
			( pin "U2D1.BL18"
				( objectStatus "@baseboard_fab2_lib.baseboard_fab2(sch_1):page70_i9:rsvd(138)" )
			)
			( pin "U2D1.BK17"
				( objectStatus "@baseboard_fab2_lib.baseboard_fab2(sch_1):page70_i9:rsvd(139)" )
			)
			( pin "U2D1.BJ20"
				( objectStatus "@baseboard_fab2_lib.baseboard_fab2(sch_1):page70_i9:rsvd(140)" )
			)
			( pin "U2D1.BJ18"
				( objectStatus "@baseboard_fab2_lib.baseboard_fab2(sch_1):page70_i9:rsvd(141)" )
			)
			( pin "U2D1.BJ16"
				( objectStatus "@baseboard_fab2_lib.baseboard_fab2(sch_1):page70_i9:rsvd(142)" )
			)
			( pin "U2D1.BH19"
				( objectStatus "@baseboard_fab2_lib.baseboard_fab2(sch_1):page70_i9:rsvd(143)" )
			)
			( pin "U2D1.BG20"
				( objectStatus "@baseboard_fab2_lib.baseboard_fab2(sch_1):page70_i9:rsvd(144)" )
			)
			( pin "U2D1.BG18"
				( objectStatus "@baseboard_fab2_lib.baseboard_fab2(sch_1):page70_i9:rsvd(145)" )
			)
			( pin "U2D1.BF21"
				( objectStatus "@baseboard_fab2_lib.baseboard_fab2(sch_1):page70_i9:rsvd(146)" )
			)
			( pin "U2D1.BE22"
				( objectStatus "@baseboard_fab2_lib.baseboard_fab2(sch_1):page70_i9:rsvd(147)" )
			)
			( pin "U2D1.BE20"
				( objectStatus "@baseboard_fab2_lib.baseboard_fab2(sch_1):page70_i9:rsvd(148)" )
			)
			( pin "U2D1.BE18"
				( objectStatus "@baseboard_fab2_lib.baseboard_fab2(sch_1):page70_i9:rsvd(149)" )
			)
			( pin "U2D1.BD69"
				( objectStatus "@baseboard_fab2_lib.baseboard_fab2(sch_1):page70_i9:rsvd(150)" )
			)
			( pin "U2D1.BD67"
				( objectStatus "@baseboard_fab2_lib.baseboard_fab2(sch_1):page70_i9:rsvd(151)" )
			)
			( pin "U2D1.BD65"
				( objectStatus "@baseboard_fab2_lib.baseboard_fab2(sch_1):page70_i9:rsvd(152)" )
			)
			( pin "U2D1.BD25"
				( objectStatus "@baseboard_fab2_lib.baseboard_fab2(sch_1):page70_i9:rsvd(153)" )
			)
			( pin "U2D1.BD19"
				( objectStatus "@baseboard_fab2_lib.baseboard_fab2(sch_1):page70_i9:rsvd(154)" )
			)
			( pin "U2D1.BD17"
				( objectStatus "@baseboard_fab2_lib.baseboard_fab2(sch_1):page70_i9:rsvd(155)" )
			)
			( pin "U2D1.BC68"
				( objectStatus "@baseboard_fab2_lib.baseboard_fab2(sch_1):page70_i9:rsvd(156)" )
			)
			( pin "U2D1.BC66"
				( objectStatus "@baseboard_fab2_lib.baseboard_fab2(sch_1):page70_i9:rsvd(157)" )
			)
			( pin "U2D1.BC64"
				( objectStatus "@baseboard_fab2_lib.baseboard_fab2(sch_1):page70_i9:rsvd(158)" )
			)
			( pin "U2D1.BC22"
				( objectStatus "@baseboard_fab2_lib.baseboard_fab2(sch_1):page70_i9:rsvd(159)" )
			)
			( pin "U2D1.BC20"
				( objectStatus "@baseboard_fab2_lib.baseboard_fab2(sch_1):page70_i9:rsvd(160)" )
			)
			( pin "U2D1.BC18"
				( objectStatus "@baseboard_fab2_lib.baseboard_fab2(sch_1):page70_i9:rsvd(161)" )
			)
			( pin "U2D1.BC14"
				( objectStatus "@baseboard_fab2_lib.baseboard_fab2(sch_1):page70_i9:rsvd(162)" )
			)
			( pin "U2D1.BB67"
				( objectStatus "@baseboard_fab2_lib.baseboard_fab2(sch_1):page70_i9:rsvd(163)" )
			)
			( pin "U2D1.BB65"
				( objectStatus "@baseboard_fab2_lib.baseboard_fab2(sch_1):page70_i9:rsvd(164)" )
			)
			( pin "U2D1.BB25"
				( objectStatus "@baseboard_fab2_lib.baseboard_fab2(sch_1):page70_i9:rsvd(165)" )
			)
			( pin "U2D1.BB21"
				( objectStatus "@baseboard_fab2_lib.baseboard_fab2(sch_1):page70_i9:rsvd(166)" )
			)
			( pin "U2D1.BB17"
				( objectStatus "@baseboard_fab2_lib.baseboard_fab2(sch_1):page70_i9:rsvd(167)" )
			)
			( pin "U2D1.BB15"
				( objectStatus "@baseboard_fab2_lib.baseboard_fab2(sch_1):page70_i9:rsvd(168)" )
			)
			( pin "U2D1.BB13"
				( objectStatus "@baseboard_fab2_lib.baseboard_fab2(sch_1):page70_i9:rsvd(169)" )
			)
			( pin "U2D1.BA82"
				( objectStatus "@baseboard_fab2_lib.baseboard_fab2(sch_1):page70_i9:rsvd(170)" )
			)
			( pin "U2D1.BA78"
				( objectStatus "@baseboard_fab2_lib.baseboard_fab2(sch_1):page70_i9:rsvd(171)" )
			)
			( pin "U2D1.AY83"
				( objectStatus "@baseboard_fab2_lib.baseboard_fab2(sch_1):page70_i9:rsvd(255)" )
			)
			( pin "U2D1.CL24"
				( objectStatus "@baseboard_fab2_lib.baseboard_fab2(sch_1):page70_i10:rsvd(81)" )
			)
			( pin "U2D1.CK77"
				( objectStatus "@baseboard_fab2_lib.baseboard_fab2(sch_1):page70_i10:rsvd(82)" )
			)
			( pin "U2D1.CK25"
				( objectStatus "@baseboard_fab2_lib.baseboard_fab2(sch_1):page70_i10:rsvd(83)" )
			)
			( pin "U2D1.CK23"
				( objectStatus "@baseboard_fab2_lib.baseboard_fab2(sch_1):page70_i10:rsvd(84)" )
			)
			( pin "U2D1.CK19"
				( objectStatus "@baseboard_fab2_lib.baseboard_fab2(sch_1):page70_i10:rsvd(85)" )
			)
			( pin "U2D1.CJ26"
				( objectStatus "@baseboard_fab2_lib.baseboard_fab2(sch_1):page70_i10:rsvd(86)" )
			)
			( pin "U2D1.CJ24"
				( objectStatus "@baseboard_fab2_lib.baseboard_fab2(sch_1):page70_i10:rsvd(87)" )
			)
			( pin "U2D1.CJ22"
				( objectStatus "@baseboard_fab2_lib.baseboard_fab2(sch_1):page70_i10:rsvd(88)" )
			)
			( pin "U2D1.CJ20"
				( objectStatus "@baseboard_fab2_lib.baseboard_fab2(sch_1):page70_i10:rsvd(89)" )
			)
			( pin "U2D1.CH77"
				( objectStatus "@baseboard_fab2_lib.baseboard_fab2(sch_1):page70_i10:rsvd(90)" )
			)
			( pin "U2D1.CH25"
				( objectStatus "@baseboard_fab2_lib.baseboard_fab2(sch_1):page70_i10:rsvd(91)" )
			)
			( pin "U2D1.AR16"
				( objectStatus "@baseboard_fab2_lib.baseboard_fab2(sch_1):page70_i10:test_6" )
			)
			( pin "U2D1.AU18"
				( objectStatus "@baseboard_fab2_lib.baseboard_fab2(sch_1):page70_i10:test_7" )
			)
			( pin "U2D1.AW16"
				( objectStatus "@baseboard_fab2_lib.baseboard_fab2(sch_1):page70_i10:test_8" )
			)
			( pin "U2D1.AW20"
				( objectStatus "@baseboard_fab2_lib.baseboard_fab2(sch_1):page70_i10:test_9" )
			)
			( pin "U2D1.AW22"
				( objectStatus "@baseboard_fab2_lib.baseboard_fab2(sch_1):page70_i10:test_10" )
			)
			( pin "R3D27.1"
				( objectStatus "@baseboard_fab2_lib.baseboard_fab2(sch_1):page71_i43:a" )
			)
			( pin "R3D27.2"
				( objectStatus "@baseboard_fab2_lib.baseboard_fab2(sch_1):page71_i43:b" )
			)
			( pin "RT8P1.1"
				( objectStatus "@baseboard_fab2_lib.baseboard_fab2(sch_1):page71_i49:a" )
			)
			( pin "RT8P1.2"
				( objectStatus "@baseboard_fab2_lib.baseboard_fab2(sch_1):page71_i49:b" )
			)
			( pin "U2D1.BN78"
				( objectStatus "@baseboard_fab2_lib.baseboard_fab2(sch_1):page71_i50:vccin(130)" )
			)
			( pin "U2D1.BN76"
				( objectStatus "@baseboard_fab2_lib.baseboard_fab2(sch_1):page71_i50:vccin(131)" )
			)
			( pin "U2D1.BN74"
				( objectStatus "@baseboard_fab2_lib.baseboard_fab2(sch_1):page71_i50:vccin(132)" )
			)
			( pin "U2D1.BN72"
				( objectStatus "@baseboard_fab2_lib.baseboard_fab2(sch_1):page71_i50:vccin(133)" )
			)
			( pin "U2D1.BN70"
				( objectStatus "@baseboard_fab2_lib.baseboard_fab2(sch_1):page71_i50:vccin(134)" )
			)
			( pin "U2D1.BN68"
				( objectStatus "@baseboard_fab2_lib.baseboard_fab2(sch_1):page71_i50:vccin(135)" )
			)
			( pin "U2D1.BN66"
				( objectStatus "@baseboard_fab2_lib.baseboard_fab2(sch_1):page71_i50:vccin(136)" )
			)
			( pin "U2D1.BN64"
				( objectStatus "@baseboard_fab2_lib.baseboard_fab2(sch_1):page71_i50:vccin(137)" )
			)
			( pin "U2D1.BN62"
				( objectStatus "@baseboard_fab2_lib.baseboard_fab2(sch_1):page71_i50:vccin(138)" )
			)
			( pin "U2D1.BN60"
				( objectStatus "@baseboard_fab2_lib.baseboard_fab2(sch_1):page71_i50:vccin(139)" )
			)
			( pin "U2D1.BM83"
				( objectStatus "@baseboard_fab2_lib.baseboard_fab2(sch_1):page71_i50:vccin(140)" )
			)
			( pin "U2D1.BM81"
				( objectStatus "@baseboard_fab2_lib.baseboard_fab2(sch_1):page71_i50:vccin(141)" )
			)
			( pin "U2D1.BM79"
				( objectStatus "@baseboard_fab2_lib.baseboard_fab2(sch_1):page71_i50:vccin(142)" )
			)
			( pin "U2D1.BM77"
				( objectStatus "@baseboard_fab2_lib.baseboard_fab2(sch_1):page71_i50:vccin(143)" )
			)
			( pin "U2D1.BM75"
				( objectStatus "@baseboard_fab2_lib.baseboard_fab2(sch_1):page71_i50:vccin(144)" )
			)
			( pin "U2D1.BM73"
				( objectStatus "@baseboard_fab2_lib.baseboard_fab2(sch_1):page71_i50:vccin(145)" )
			)
			( pin "U2D1.BM71"
				( objectStatus "@baseboard_fab2_lib.baseboard_fab2(sch_1):page71_i50:vccin(146)" )
			)
			( pin "U2D1.BM69"
				( objectStatus "@baseboard_fab2_lib.baseboard_fab2(sch_1):page71_i50:vccin(147)" )
			)
			( pin "U2D1.BM67"
				( objectStatus "@baseboard_fab2_lib.baseboard_fab2(sch_1):page71_i50:vccin(148)" )
			)
			( pin "U2D1.BM65"
				( objectStatus "@baseboard_fab2_lib.baseboard_fab2(sch_1):page71_i50:vccin(149)" )
			)
			( pin "U2D1.BM63"
				( objectStatus "@baseboard_fab2_lib.baseboard_fab2(sch_1):page71_i50:vccin(150)" )
			)
			( pin "U2D1.BM61"
				( objectStatus "@baseboard_fab2_lib.baseboard_fab2(sch_1):page71_i50:vccin(151)" )
			)
			( pin "U2D1.BL84"
				( objectStatus "@baseboard_fab2_lib.baseboard_fab2(sch_1):page71_i50:vccin(152)" )
			)
			( pin "U2D1.BL62"
				( objectStatus "@baseboard_fab2_lib.baseboard_fab2(sch_1):page71_i50:vccin(153)" )
			)
			( pin "U2D1.BL60"
				( objectStatus "@baseboard_fab2_lib.baseboard_fab2(sch_1):page71_i50:vccin(154)" )
			)
			( pin "U2D1.BK83"
				( objectStatus "@baseboard_fab2_lib.baseboard_fab2(sch_1):page71_i50:vccin(155)" )
			)
			( pin "U2D1.BK81"
				( objectStatus "@baseboard_fab2_lib.baseboard_fab2(sch_1):page71_i50:vccin(156)" )
			)
			( pin "U2D1.BK79"
				( objectStatus "@baseboard_fab2_lib.baseboard_fab2(sch_1):page71_i50:vccin(157)" )
			)
			( pin "U2D1.BK77"
				( objectStatus "@baseboard_fab2_lib.baseboard_fab2(sch_1):page71_i50:vccin(158)" )
			)
			( pin "U2D1.BK75"
				( objectStatus "@baseboard_fab2_lib.baseboard_fab2(sch_1):page71_i50:vccin(159)" )
			)
			( pin "U2D1.BK73"
				( objectStatus "@baseboard_fab2_lib.baseboard_fab2(sch_1):page71_i50:vccin(160)" )
			)
			( pin "U2D1.BK71"
				( objectStatus "@baseboard_fab2_lib.baseboard_fab2(sch_1):page71_i50:vccin(161)" )
			)
			( pin "U2D1.BK69"
				( objectStatus "@baseboard_fab2_lib.baseboard_fab2(sch_1):page71_i50:vccin(162)" )
			)
			( pin "U2D1.BK67"
				( objectStatus "@baseboard_fab2_lib.baseboard_fab2(sch_1):page71_i50:vccin(163)" )
			)
			( pin "U2D1.BK65"
				( objectStatus "@baseboard_fab2_lib.baseboard_fab2(sch_1):page71_i50:vccin(164)" )
			)
			( pin "U2D1.BK63"
				( objectStatus "@baseboard_fab2_lib.baseboard_fab2(sch_1):page71_i50:vccin(165)" )
			)
			( pin "U2D1.BK61"
				( objectStatus "@baseboard_fab2_lib.baseboard_fab2(sch_1):page71_i50:vccin(166)" )
			)
			( pin "U2D1.BJ84"
				( objectStatus "@baseboard_fab2_lib.baseboard_fab2(sch_1):page71_i50:vccin(167)" )
			)
			( pin "U2D1.BJ82"
				( objectStatus "@baseboard_fab2_lib.baseboard_fab2(sch_1):page71_i50:vccin(168)" )
			)
			( pin "U2D1.BJ80"
				( objectStatus "@baseboard_fab2_lib.baseboard_fab2(sch_1):page71_i50:vccin(169)" )
			)
			( pin "U2D1.BJ78"
				( objectStatus "@baseboard_fab2_lib.baseboard_fab2(sch_1):page71_i50:vccin(170)" )
			)
			( pin "U2D1.BJ76"
				( objectStatus "@baseboard_fab2_lib.baseboard_fab2(sch_1):page71_i50:vccin(171)" )
			)
			( pin "U2D1.BJ74"
				( objectStatus "@baseboard_fab2_lib.baseboard_fab2(sch_1):page71_i50:vccin(172)" )
			)
			( pin "U2D1.BJ72"
				( objectStatus "@baseboard_fab2_lib.baseboard_fab2(sch_1):page71_i50:vccin(173)" )
			)
			( pin "U2D1.BJ70"
				( objectStatus "@baseboard_fab2_lib.baseboard_fab2(sch_1):page71_i50:vccin(174)" )
			)
			( pin "U2D1.BJ68"
				( objectStatus "@baseboard_fab2_lib.baseboard_fab2(sch_1):page71_i50:vccin(175)" )
			)
			( pin "U2D1.BJ66"
				( objectStatus "@baseboard_fab2_lib.baseboard_fab2(sch_1):page71_i50:vccin(176)" )
			)
			( pin "U2D1.BJ64"
				( objectStatus "@baseboard_fab2_lib.baseboard_fab2(sch_1):page71_i50:vccin(177)" )
			)
			( pin "U2D1.BJ62"
				( objectStatus "@baseboard_fab2_lib.baseboard_fab2(sch_1):page71_i50:vccin(178)" )
			)
			( pin "U2D1.BJ60"
				( objectStatus "@baseboard_fab2_lib.baseboard_fab2(sch_1):page71_i50:vccin(179)" )
			)
			( pin "U2D1.BH83"
				( objectStatus "@baseboard_fab2_lib.baseboard_fab2(sch_1):page71_i50:vccin(180)" )
			)
			( pin "U2D1.BH81"
				( objectStatus "@baseboard_fab2_lib.baseboard_fab2(sch_1):page71_i50:vccin(181)" )
			)
			( pin "U2D1.BH79"
				( objectStatus "@baseboard_fab2_lib.baseboard_fab2(sch_1):page71_i50:vccin(182)" )
			)
			( pin "U2D1.BH77"
				( objectStatus "@baseboard_fab2_lib.baseboard_fab2(sch_1):page71_i50:vccin(183)" )
			)
			( pin "U2D1.BH75"
				( objectStatus "@baseboard_fab2_lib.baseboard_fab2(sch_1):page71_i50:vccin(184)" )
			)
			( pin "U2D1.BH73"
				( objectStatus "@baseboard_fab2_lib.baseboard_fab2(sch_1):page71_i50:vccin(185)" )
			)
			( pin "U2D1.BH71"
				( objectStatus "@baseboard_fab2_lib.baseboard_fab2(sch_1):page71_i50:vccin(186)" )
			)
			( pin "U2D1.BH69"
				( objectStatus "@baseboard_fab2_lib.baseboard_fab2(sch_1):page71_i50:vccin(187)" )
			)
			( pin "U2D1.BH67"
				( objectStatus "@baseboard_fab2_lib.baseboard_fab2(sch_1):page71_i50:vccin(188)" )
			)
			( pin "U2D1.BH65"
				( objectStatus "@baseboard_fab2_lib.baseboard_fab2(sch_1):page71_i50:vccin(189)" )
			)
			( pin "U2D1.BH63"
				( objectStatus "@baseboard_fab2_lib.baseboard_fab2(sch_1):page71_i50:vccin(190)" )
			)
			( pin "U2D1.BH61"
				( objectStatus "@baseboard_fab2_lib.baseboard_fab2(sch_1):page71_i50:vccin(191)" )
			)
			( pin "U2D1.BG84"
				( objectStatus "@baseboard_fab2_lib.baseboard_fab2(sch_1):page71_i50:vccin(192)" )
			)
			( pin "U2D1.BG70"
				( objectStatus "@baseboard_fab2_lib.baseboard_fab2(sch_1):page71_i50:vccin(193)" )
			)
			( pin "U2D1.BG68"
				( objectStatus "@baseboard_fab2_lib.baseboard_fab2(sch_1):page71_i50:vccin(194)" )
			)
			( pin "U2D1.BG66"
				( objectStatus "@baseboard_fab2_lib.baseboard_fab2(sch_1):page71_i50:vccin(195)" )
			)
			( pin "U2D1.BG64"
				( objectStatus "@baseboard_fab2_lib.baseboard_fab2(sch_1):page71_i50:vccin(196)" )
			)
			( pin "U2D1.BG62"
				( objectStatus "@baseboard_fab2_lib.baseboard_fab2(sch_1):page71_i50:vccin(197)" )
			)
			( pin "U2D1.BG60"
				( objectStatus "@baseboard_fab2_lib.baseboard_fab2(sch_1):page71_i50:vccin(198)" )
			)
			( pin "U2D1.BF85"
				( objectStatus "@baseboard_fab2_lib.baseboard_fab2(sch_1):page71_i50:vccin(199)" )
			)
			( pin "U2D1.BF83"
				( objectStatus "@baseboard_fab2_lib.baseboard_fab2(sch_1):page71_i50:vccin(200)" )
			)
			( pin "U2D1.BF81"
				( objectStatus "@baseboard_fab2_lib.baseboard_fab2(sch_1):page71_i50:vccin(201)" )
			)
			( pin "U2D1.BF79"
				( objectStatus "@baseboard_fab2_lib.baseboard_fab2(sch_1):page71_i50:vccin(202)" )
			)
			( pin "U2D1.BF77"
				( objectStatus "@baseboard_fab2_lib.baseboard_fab2(sch_1):page71_i50:vccin(203)" )
			)
			( pin "U2D1.BF75"
				( objectStatus "@baseboard_fab2_lib.baseboard_fab2(sch_1):page71_i50:vccin(204)" )
			)
			( pin "U2D1.BF73"
				( objectStatus "@baseboard_fab2_lib.baseboard_fab2(sch_1):page71_i50:vccin(205)" )
			)
			( pin "U2D1.BF61"
				( objectStatus "@baseboard_fab2_lib.baseboard_fab2(sch_1):page71_i50:vccin(206)" )
			)
			( pin "U2D1.BE84"
				( objectStatus "@baseboard_fab2_lib.baseboard_fab2(sch_1):page71_i50:vccin(207)" )
			)
			( pin "U2D1.BE82"
				( objectStatus "@baseboard_fab2_lib.baseboard_fab2(sch_1):page71_i50:vccin(208)" )
			)
			( pin "U2D1.BE80"
				( objectStatus "@baseboard_fab2_lib.baseboard_fab2(sch_1):page71_i50:vccin(209)" )
			)
			( pin "U2D1.BE78"
				( objectStatus "@baseboard_fab2_lib.baseboard_fab2(sch_1):page71_i50:vccin(210)" )
			)
			( pin "U2D1.BE76"
				( objectStatus "@baseboard_fab2_lib.baseboard_fab2(sch_1):page71_i50:vccin(211)" )
			)
			( pin "U2D1.BE74"
				( objectStatus "@baseboard_fab2_lib.baseboard_fab2(sch_1):page71_i50:vccin(212)" )
			)
			( pin "U2D1.BE72"
				( objectStatus "@baseboard_fab2_lib.baseboard_fab2(sch_1):page71_i50:vccin(213)" )
			)
			( pin "U2D1.BE62"
				( objectStatus "@baseboard_fab2_lib.baseboard_fab2(sch_1):page71_i50:vccin(214)" )
			)
			( pin "U2D1.BE60"
				( objectStatus "@baseboard_fab2_lib.baseboard_fab2(sch_1):page71_i50:vccin(215)" )
			)
			( pin "U2D1.BD85"
				( objectStatus "@baseboard_fab2_lib.baseboard_fab2(sch_1):page71_i50:vccin(216)" )
			)
			( pin "U2D1.BD83"
				( objectStatus "@baseboard_fab2_lib.baseboard_fab2(sch_1):page71_i50:vccin(217)" )
			)
			( pin "U2D1.BD81"
				( objectStatus "@baseboard_fab2_lib.baseboard_fab2(sch_1):page71_i50:vccin(218)" )
			)
			( pin "U2D1.BD79"
				( objectStatus "@baseboard_fab2_lib.baseboard_fab2(sch_1):page71_i50:vccin(219)" )
			)
			( pin "U2D1.BD77"
				( objectStatus "@baseboard_fab2_lib.baseboard_fab2(sch_1):page71_i50:vccin(220)" )
			)
			( pin "U2D1.BD75"
				( objectStatus "@baseboard_fab2_lib.baseboard_fab2(sch_1):page71_i50:vccin(221)" )
			)
			( pin "U2D1.BD73"
				( objectStatus "@baseboard_fab2_lib.baseboard_fab2(sch_1):page71_i50:vccin(222)" )
			)
			( pin "U2D1.BD61"
				( objectStatus "@baseboard_fab2_lib.baseboard_fab2(sch_1):page71_i50:vccin(223)" )
			)
			( pin "U2D1.BC84"
				( objectStatus "@baseboard_fab2_lib.baseboard_fab2(sch_1):page71_i50:vccin(224)" )
			)
			( pin "U2D1.BC62"
				( objectStatus "@baseboard_fab2_lib.baseboard_fab2(sch_1):page71_i50:vccin(225)" )
			)
			( pin "U2D1.BC60"
				( objectStatus "@baseboard_fab2_lib.baseboard_fab2(sch_1):page71_i50:vccin(226)" )
			)
			( pin "U2D1.BB85"
				( objectStatus "@baseboard_fab2_lib.baseboard_fab2(sch_1):page71_i50:vccin(227)" )
			)
			( pin "U2D1.BB61"
				( objectStatus "@baseboard_fab2_lib.baseboard_fab2(sch_1):page71_i50:vccin(228)" )
			)
			( pin "U2D1.BA60"
				( objectStatus "@baseboard_fab2_lib.baseboard_fab2(sch_1):page71_i50:vccin(229)" )
			)
			( pin "U2D1.AY61"
				( objectStatus "@baseboard_fab2_lib.baseboard_fab2(sch_1):page71_i50:vccin(230)" )
			)
			( pin "U2D1.AW60"
				( objectStatus "@baseboard_fab2_lib.baseboard_fab2(sch_1):page71_i50:vccin(231)" )
			)
			( pin "U2D1.AV61"
				( objectStatus "@baseboard_fab2_lib.baseboard_fab2(sch_1):page71_i50:vccin(232)" )
			)
			( pin "U2D1.AV59"
				( objectStatus "@baseboard_fab2_lib.baseboard_fab2(sch_1):page71_i50:vccin(233)" )
			)
			( pin "U2D1.AU60"
				( objectStatus "@baseboard_fab2_lib.baseboard_fab2(sch_1):page71_i50:vccin(234)" )
			)
			( pin "U2D1.AU58"
				( objectStatus "@baseboard_fab2_lib.baseboard_fab2(sch_1):page71_i50:vccin(235)" )
			)
			( pin "U2D1.AT59"
				( objectStatus "@baseboard_fab2_lib.baseboard_fab2(sch_1):page71_i50:vccin(236)" )
			)
			( pin "U2D1.AT57"
				( objectStatus "@baseboard_fab2_lib.baseboard_fab2(sch_1):page71_i50:vccin(237)" )
			)
			( pin "U2D1.AR58"
				( objectStatus "@baseboard_fab2_lib.baseboard_fab2(sch_1):page71_i50:vccin(238)" )
			)
			( pin "U2D1.AR56"
				( objectStatus "@baseboard_fab2_lib.baseboard_fab2(sch_1):page71_i50:vccin(239)" )
			)
			( pin "U2D1.AP57"
				( objectStatus "@baseboard_fab2_lib.baseboard_fab2(sch_1):page71_i50:vccin(240)" )
			)
			( pin "U2D1.AP55"
				( objectStatus "@baseboard_fab2_lib.baseboard_fab2(sch_1):page71_i50:vccin(241)" )
			)
			( pin "U2D1.AN56"
				( objectStatus "@baseboard_fab2_lib.baseboard_fab2(sch_1):page71_i50:vccin(242)" )
			)
			( pin "U2D1.AN54"
				( objectStatus "@baseboard_fab2_lib.baseboard_fab2(sch_1):page71_i50:vccin(243)" )
			)
			( pin "U2D1.AN32"
				( objectStatus "@baseboard_fab2_lib.baseboard_fab2(sch_1):page71_i50:vccin(244)" )
			)
			( pin "U2D1.AM55"
				( objectStatus "@baseboard_fab2_lib.baseboard_fab2(sch_1):page71_i50:vccin(245)" )
			)
			( pin "U2D1.AM53"
				( objectStatus "@baseboard_fab2_lib.baseboard_fab2(sch_1):page71_i50:vccin(246)" )
			)
			( pin "U2D1.AM33"
				( objectStatus "@baseboard_fab2_lib.baseboard_fab2(sch_1):page71_i50:vccin(247)" )
			)
			( pin "U2D1.AL54"
				( objectStatus "@baseboard_fab2_lib.baseboard_fab2(sch_1):page71_i50:vccin(248)" )
			)
			( pin "U2D1.AL52"
				( objectStatus "@baseboard_fab2_lib.baseboard_fab2(sch_1):page71_i50:vccin(249)" )
			)
			( pin "U2D1.AL50"
				( objectStatus "@baseboard_fab2_lib.baseboard_fab2(sch_1):page71_i50:vccin(250)" )
			)
			( pin "U2D1.AL48"
				( objectStatus "@baseboard_fab2_lib.baseboard_fab2(sch_1):page71_i50:vccin(251)" )
			)
			( pin "U2D1.AL46"
				( objectStatus "@baseboard_fab2_lib.baseboard_fab2(sch_1):page71_i50:vccin(252)" )
			)
			( pin "U2D1.AL34"
				( objectStatus "@baseboard_fab2_lib.baseboard_fab2(sch_1):page71_i50:vccin(253)" )
			)
			( pin "U2D1.AK53"
				( objectStatus "@baseboard_fab2_lib.baseboard_fab2(sch_1):page71_i50:vccin(254)" )
			)
			( pin "U2D1.AK51"
				( objectStatus "@baseboard_fab2_lib.baseboard_fab2(sch_1):page71_i50:vccin(255)" )
			)
			( pin "U2D1.AK49"
				( objectStatus "@baseboard_fab2_lib.baseboard_fab2(sch_1):page71_i50:vccin(256)" )
			)
			( pin "U2D1.AK47"
				( objectStatus "@baseboard_fab2_lib.baseboard_fab2(sch_1):page71_i50:vccin(257)" )
			)
			( pin "U2D1.AK45"
				( objectStatus "@baseboard_fab2_lib.baseboard_fab2(sch_1):page71_i50:vccin(258)" )
			)
			( pin "U2D1.AK35"
				( objectStatus "@baseboard_fab2_lib.baseboard_fab2(sch_1):page71_i50:vccin(259)" )
			)
			( pin "U2D1.AJ36"
				( objectStatus "@baseboard_fab2_lib.baseboard_fab2(sch_1):page71_i50:vccin(260)" )
			)
			( pin "U2D1.AH41"
				( objectStatus "@baseboard_fab2_lib.baseboard_fab2(sch_1):page71_i50:vccin(261)" )
			)
			( pin "U2D1.AH39"
				( objectStatus "@baseboard_fab2_lib.baseboard_fab2(sch_1):page71_i50:vccin(262)" )
			)
			( pin "U2D1.AH37"
				( objectStatus "@baseboard_fab2_lib.baseboard_fab2(sch_1):page71_i50:vccin(263)" )
			)
			( pin "U2D1.AG42"
				( objectStatus "@baseboard_fab2_lib.baseboard_fab2(sch_1):page71_i50:vccin(264)" )
			)
			( pin "U2D1.AG40"
				( objectStatus "@baseboard_fab2_lib.baseboard_fab2(sch_1):page71_i50:vccin(265)" )
			)
			( pin "U2D1.AG38"
				( objectStatus "@baseboard_fab2_lib.baseboard_fab2(sch_1):page71_i50:vccin(266)" )
			)
			( pin "U2D1.AF43"
				( objectStatus "@baseboard_fab2_lib.baseboard_fab2(sch_1):page71_i50:vccin(267)" )
			)
			( pin "U2D1.CY49"
				( objectStatus "@baseboard_fab2_lib.baseboard_fab2(sch_1):page71_i51:vccin(0)" )
			)
			( pin "U2D1.CY47"
				( objectStatus "@baseboard_fab2_lib.baseboard_fab2(sch_1):page71_i51:vccin(1)" )
			)
			( pin "U2D1.CW50"
				( objectStatus "@baseboard_fab2_lib.baseboard_fab2(sch_1):page71_i51:vccin(2)" )
			)
			( pin "U2D1.CW48"
				( objectStatus "@baseboard_fab2_lib.baseboard_fab2(sch_1):page71_i51:vccin(3)" )
			)
			( pin "U2D1.CW46"
				( objectStatus "@baseboard_fab2_lib.baseboard_fab2(sch_1):page71_i51:vccin(4)" )
			)
			( pin "U2D1.CV51"
				( objectStatus "@baseboard_fab2_lib.baseboard_fab2(sch_1):page71_i51:vccin(5)" )
			)
			( pin "U2D1.CU54"
				( objectStatus "@baseboard_fab2_lib.baseboard_fab2(sch_1):page71_i51:vccin(6)" )
			)
			( pin "U2D1.CU52"
				( objectStatus "@baseboard_fab2_lib.baseboard_fab2(sch_1):page71_i51:vccin(7)" )
			)
			( pin "U2D1.CU42"
				( objectStatus "@baseboard_fab2_lib.baseboard_fab2(sch_1):page71_i51:vccin(8)" )
			)
			( pin "U2D1.CU40"
				( objectStatus "@baseboard_fab2_lib.baseboard_fab2(sch_1):page71_i51:vccin(9)" )
			)
			( pin "U2D1.CU38"
				( objectStatus "@baseboard_fab2_lib.baseboard_fab2(sch_1):page71_i51:vccin(10)" )
			)
			( pin "U2D1.CT55"
				( objectStatus "@baseboard_fab2_lib.baseboard_fab2(sch_1):page71_i51:vccin(11)" )
			)
			( pin "U2D1.CT53"
				( objectStatus "@baseboard_fab2_lib.baseboard_fab2(sch_1):page71_i51:vccin(12)" )
			)
			( pin "U2D1.CT41"
				( objectStatus "@baseboard_fab2_lib.baseboard_fab2(sch_1):page71_i51:vccin(13)" )
			)
			( pin "U2D1.CT39"
				( objectStatus "@baseboard_fab2_lib.baseboard_fab2(sch_1):page71_i51:vccin(14)" )
			)
			( pin "U2D1.CT37"
				( objectStatus "@baseboard_fab2_lib.baseboard_fab2(sch_1):page71_i51:vccin(15)" )
			)
			( pin "U2D1.CR56"
				( objectStatus "@baseboard_fab2_lib.baseboard_fab2(sch_1):page71_i51:vccin(16)" )
			)
			( pin "U2D1.CR54"
				( objectStatus "@baseboard_fab2_lib.baseboard_fab2(sch_1):page71_i51:vccin(17)" )
			)
			( pin "U2D1.CR34"
				( objectStatus "@baseboard_fab2_lib.baseboard_fab2(sch_1):page71_i51:vccin(18)" )
			)
			( pin "U2D1.CP57"
				( objectStatus "@baseboard_fab2_lib.baseboard_fab2(sch_1):page71_i51:vccin(19)" )
			)
			( pin "U2D1.CP55"
				( objectStatus "@baseboard_fab2_lib.baseboard_fab2(sch_1):page71_i51:vccin(20)" )
			)
			( pin "U2D1.CP33"
				( objectStatus "@baseboard_fab2_lib.baseboard_fab2(sch_1):page71_i51:vccin(21)" )
			)
			( pin "U2D1.CN58"
				( objectStatus "@baseboard_fab2_lib.baseboard_fab2(sch_1):page71_i51:vccin(22)" )
			)
			( pin "U2D1.CN56"
				( objectStatus "@baseboard_fab2_lib.baseboard_fab2(sch_1):page71_i51:vccin(23)" )
			)
			( pin "U2D1.CM59"
				( objectStatus "@baseboard_fab2_lib.baseboard_fab2(sch_1):page71_i51:vccin(24)" )
			)
			( pin "U2D1.CM57"
				( objectStatus "@baseboard_fab2_lib.baseboard_fab2(sch_1):page71_i51:vccin(25)" )
			)
			( pin "U2D1.CL60"
				( objectStatus "@baseboard_fab2_lib.baseboard_fab2(sch_1):page71_i51:vccin(26)" )
			)
			( pin "U2D1.CL58"
				( objectStatus "@baseboard_fab2_lib.baseboard_fab2(sch_1):page71_i51:vccin(27)" )
			)
			( pin "U2D1.CK61"
				( objectStatus "@baseboard_fab2_lib.baseboard_fab2(sch_1):page71_i51:vccin(28)" )
			)
			( pin "U2D1.CK59"
				( objectStatus "@baseboard_fab2_lib.baseboard_fab2(sch_1):page71_i51:vccin(29)" )
			)
			( pin "U2D1.CJ60"
				( objectStatus "@baseboard_fab2_lib.baseboard_fab2(sch_1):page71_i51:vccin(30)" )
			)
			( pin "U2D1.CH85"
				( objectStatus "@baseboard_fab2_lib.baseboard_fab2(sch_1):page71_i51:vccin(31)" )
			)
			( pin "U2D1.CH61"
				( objectStatus "@baseboard_fab2_lib.baseboard_fab2(sch_1):page71_i51:vccin(32)" )
			)
			( pin "U2D1.CG84"
				( objectStatus "@baseboard_fab2_lib.baseboard_fab2(sch_1):page71_i51:vccin(33)" )
			)
			( pin "U2D1.CG60"
				( objectStatus "@baseboard_fab2_lib.baseboard_fab2(sch_1):page71_i51:vccin(34)" )
			)
			( pin "U2D1.CF85"
				( objectStatus "@baseboard_fab2_lib.baseboard_fab2(sch_1):page71_i51:vccin(35)" )
			)
			( pin "U2D1.CF61"
				( objectStatus "@baseboard_fab2_lib.baseboard_fab2(sch_1):page71_i51:vccin(36)" )
			)
			( pin "U2D1.CE84"
				( objectStatus "@baseboard_fab2_lib.baseboard_fab2(sch_1):page71_i51:vccin(37)" )
			)
			( pin "U2D1.CE60"
				( objectStatus "@baseboard_fab2_lib.baseboard_fab2(sch_1):page71_i51:vccin(38)" )
			)
			( pin "U2D1.CD85"
				( objectStatus "@baseboard_fab2_lib.baseboard_fab2(sch_1):page71_i51:vccin(39)" )
			)
			( pin "U2D1.CD83"
				( objectStatus "@baseboard_fab2_lib.baseboard_fab2(sch_1):page71_i51:vccin(40)" )
			)
			( pin "U2D1.CD61"
				( objectStatus "@baseboard_fab2_lib.baseboard_fab2(sch_1):page71_i51:vccin(41)" )
			)
			( pin "U2D1.CC84"
				( objectStatus "@baseboard_fab2_lib.baseboard_fab2(sch_1):page71_i51:vccin(42)" )
			)
			( pin "U2D1.CC62"
				( objectStatus "@baseboard_fab2_lib.baseboard_fab2(sch_1):page71_i51:vccin(43)" )
			)
			( pin "U2D1.CC60"
				( objectStatus "@baseboard_fab2_lib.baseboard_fab2(sch_1):page71_i51:vccin(44)" )
			)
			( pin "U2D1.CB83"
				( objectStatus "@baseboard_fab2_lib.baseboard_fab2(sch_1):page71_i51:vccin(45)" )
			)
			( pin "U2D1.CB81"
				( objectStatus "@baseboard_fab2_lib.baseboard_fab2(sch_1):page71_i51:vccin(46)" )
			)
			( pin "U2D1.CB79"
				( objectStatus "@baseboard_fab2_lib.baseboard_fab2(sch_1):page71_i51:vccin(47)" )
			)
			( pin "U2D1.CB77"
				( objectStatus "@baseboard_fab2_lib.baseboard_fab2(sch_1):page71_i51:vccin(48)" )
			)
			( pin "U2D1.CB75"
				( objectStatus "@baseboard_fab2_lib.baseboard_fab2(sch_1):page71_i51:vccin(49)" )
			)
			( pin "U2D1.CB73"
				( objectStatus "@baseboard_fab2_lib.baseboard_fab2(sch_1):page71_i51:vccin(50)" )
			)
			( pin "U2D1.CB61"
				( objectStatus "@baseboard_fab2_lib.baseboard_fab2(sch_1):page71_i51:vccin(51)" )
			)
			( pin "U2D1.CA84"
				( objectStatus "@baseboard_fab2_lib.baseboard_fab2(sch_1):page71_i51:vccin(52)" )
			)
			( pin "U2D1.CA82"
				( objectStatus "@baseboard_fab2_lib.baseboard_fab2(sch_1):page71_i51:vccin(53)" )
			)
			( pin "U2D1.CA80"
				( objectStatus "@baseboard_fab2_lib.baseboard_fab2(sch_1):page71_i51:vccin(54)" )
			)
			( pin "U2D1.CA78"
				( objectStatus "@baseboard_fab2_lib.baseboard_fab2(sch_1):page71_i51:vccin(55)" )
			)
			( pin "U2D1.CA76"
				( objectStatus "@baseboard_fab2_lib.baseboard_fab2(sch_1):page71_i51:vccin(56)" )
			)
			( pin "U2D1.CA74"
				( objectStatus "@baseboard_fab2_lib.baseboard_fab2(sch_1):page71_i51:vccin(57)" )
			)
			( pin "U2D1.CA72"
				( objectStatus "@baseboard_fab2_lib.baseboard_fab2(sch_1):page71_i51:vccin(58)" )
			)
			( pin "U2D1.CA62"
				( objectStatus "@baseboard_fab2_lib.baseboard_fab2(sch_1):page71_i51:vccin(59)" )
			)
			( pin "U2D1.CA60"
				( objectStatus "@baseboard_fab2_lib.baseboard_fab2(sch_1):page71_i51:vccin(60)" )
			)
			( pin "U2D1.BY83"
				( objectStatus "@baseboard_fab2_lib.baseboard_fab2(sch_1):page71_i51:vccin(61)" )
			)
			( pin "U2D1.BY81"
				( objectStatus "@baseboard_fab2_lib.baseboard_fab2(sch_1):page71_i51:vccin(62)" )
			)
			( pin "U2D1.BY79"
				( objectStatus "@baseboard_fab2_lib.baseboard_fab2(sch_1):page71_i51:vccin(63)" )
			)
			( pin "U2D1.BY77"
				( objectStatus "@baseboard_fab2_lib.baseboard_fab2(sch_1):page71_i51:vccin(64)" )
			)
			( pin "U2D1.BY75"
				( objectStatus "@baseboard_fab2_lib.baseboard_fab2(sch_1):page71_i51:vccin(65)" )
			)
			( pin "U2D1.BY73"
				( objectStatus "@baseboard_fab2_lib.baseboard_fab2(sch_1):page71_i51:vccin(66)" )
			)
			( pin "U2D1.BY61"
				( objectStatus "@baseboard_fab2_lib.baseboard_fab2(sch_1):page71_i51:vccin(67)" )
			)
			( pin "U2D1.BW84"
				( objectStatus "@baseboard_fab2_lib.baseboard_fab2(sch_1):page71_i51:vccin(68)" )
			)
			( pin "U2D1.BW70"
				( objectStatus "@baseboard_fab2_lib.baseboard_fab2(sch_1):page71_i51:vccin(69)" )
			)
			( pin "U2D1.BW68"
				( objectStatus "@baseboard_fab2_lib.baseboard_fab2(sch_1):page71_i51:vccin(70)" )
			)
			( pin "U2D1.BW66"
				( objectStatus "@baseboard_fab2_lib.baseboard_fab2(sch_1):page71_i51:vccin(71)" )
			)
			( pin "U2D1.BW64"
				( objectStatus "@baseboard_fab2_lib.baseboard_fab2(sch_1):page71_i51:vccin(72)" )
			)
			( pin "U2D1.BW62"
				( objectStatus "@baseboard_fab2_lib.baseboard_fab2(sch_1):page71_i51:vccin(73)" )
			)
			( pin "U2D1.BW60"
				( objectStatus "@baseboard_fab2_lib.baseboard_fab2(sch_1):page71_i51:vccin(74)" )
			)
			( pin "U2D1.BV83"
				( objectStatus "@baseboard_fab2_lib.baseboard_fab2(sch_1):page71_i51:vccin(75)" )
			)
			( pin "U2D1.BV81"
				( objectStatus "@baseboard_fab2_lib.baseboard_fab2(sch_1):page71_i51:vccin(76)" )
			)
			( pin "U2D1.BV79"
				( objectStatus "@baseboard_fab2_lib.baseboard_fab2(sch_1):page71_i51:vccin(77)" )
			)
			( pin "U2D1.BV77"
				( objectStatus "@baseboard_fab2_lib.baseboard_fab2(sch_1):page71_i51:vccin(78)" )
			)
			( pin "U2D1.BV75"
				( objectStatus "@baseboard_fab2_lib.baseboard_fab2(sch_1):page71_i51:vccin(79)" )
			)
			( pin "U2D1.BV73"
				( objectStatus "@baseboard_fab2_lib.baseboard_fab2(sch_1):page71_i51:vccin(80)" )
			)
			( pin "U2D1.BV71"
				( objectStatus "@baseboard_fab2_lib.baseboard_fab2(sch_1):page71_i51:vccin(81)" )
			)
			( pin "U2D1.BV69"
				( objectStatus "@baseboard_fab2_lib.baseboard_fab2(sch_1):page71_i51:vccin(82)" )
			)
			( pin "U2D1.BV67"
				( objectStatus "@baseboard_fab2_lib.baseboard_fab2(sch_1):page71_i51:vccin(83)" )
			)
			( pin "U2D1.BV65"
				( objectStatus "@baseboard_fab2_lib.baseboard_fab2(sch_1):page71_i51:vccin(84)" )
			)
			( pin "U2D1.BV63"
				( objectStatus "@baseboard_fab2_lib.baseboard_fab2(sch_1):page71_i51:vccin(85)" )
			)
			( pin "U2D1.BV61"
				( objectStatus "@baseboard_fab2_lib.baseboard_fab2(sch_1):page71_i51:vccin(86)" )
			)
			( pin "U2D1.BU84"
				( objectStatus "@baseboard_fab2_lib.baseboard_fab2(sch_1):page71_i51:vccin(87)" )
			)
			( pin "U2D1.BU82"
				( objectStatus "@baseboard_fab2_lib.baseboard_fab2(sch_1):page71_i51:vccin(88)" )
			)
			( pin "U2D1.BU80"
				( objectStatus "@baseboard_fab2_lib.baseboard_fab2(sch_1):page71_i51:vccin(89)" )
			)
			( pin "U2D1.BU78"
				( objectStatus "@baseboard_fab2_lib.baseboard_fab2(sch_1):page71_i51:vccin(90)" )
			)
			( pin "U2D1.BU76"
				( objectStatus "@baseboard_fab2_lib.baseboard_fab2(sch_1):page71_i51:vccin(91)" )
			)
			( pin "U2D1.BU74"
				( objectStatus "@baseboard_fab2_lib.baseboard_fab2(sch_1):page71_i51:vccin(92)" )
			)
			( pin "U2D1.BU72"
				( objectStatus "@baseboard_fab2_lib.baseboard_fab2(sch_1):page71_i51:vccin(93)" )
			)
			( pin "U2D1.BU70"
				( objectStatus "@baseboard_fab2_lib.baseboard_fab2(sch_1):page71_i51:vccin(94)" )
			)
			( pin "U2D1.BU68"
				( objectStatus "@baseboard_fab2_lib.baseboard_fab2(sch_1):page71_i51:vccin(95)" )
			)
			( pin "U2D1.BU66"
				( objectStatus "@baseboard_fab2_lib.baseboard_fab2(sch_1):page71_i51:vccin(96)" )
			)
			( pin "U2D1.BU64"
				( objectStatus "@baseboard_fab2_lib.baseboard_fab2(sch_1):page71_i51:vccin(97)" )
			)
			( pin "U2D1.BU62"
				( objectStatus "@baseboard_fab2_lib.baseboard_fab2(sch_1):page71_i51:vccin(98)" )
			)
			( pin "U2D1.BU60"
				( objectStatus "@baseboard_fab2_lib.baseboard_fab2(sch_1):page71_i51:vccin(99)" )
			)
			( pin "U2D1.BT83"
				( objectStatus "@baseboard_fab2_lib.baseboard_fab2(sch_1):page71_i51:vccin(100)" )
			)
			( pin "U2D1.BT81"
				( objectStatus "@baseboard_fab2_lib.baseboard_fab2(sch_1):page71_i51:vccin(101)" )
			)
			( pin "U2D1.BT79"
				( objectStatus "@baseboard_fab2_lib.baseboard_fab2(sch_1):page71_i51:vccin(102)" )
			)
			( pin "U2D1.BT77"
				( objectStatus "@baseboard_fab2_lib.baseboard_fab2(sch_1):page71_i51:vccin(103)" )
			)
			( pin "U2D1.BT75"
				( objectStatus "@baseboard_fab2_lib.baseboard_fab2(sch_1):page71_i51:vccin(104)" )
			)
			( pin "U2D1.BT73"
				( objectStatus "@baseboard_fab2_lib.baseboard_fab2(sch_1):page71_i51:vccin(105)" )
			)
			( pin "U2D1.BT71"
				( objectStatus "@baseboard_fab2_lib.baseboard_fab2(sch_1):page71_i51:vccin(106)" )
			)
			( pin "U2D1.BT69"
				( objectStatus "@baseboard_fab2_lib.baseboard_fab2(sch_1):page71_i51:vccin(107)" )
			)
			( pin "U2D1.BT67"
				( objectStatus "@baseboard_fab2_lib.baseboard_fab2(sch_1):page71_i51:vccin(108)" )
			)
			( pin "U2D1.BT65"
				( objectStatus "@baseboard_fab2_lib.baseboard_fab2(sch_1):page71_i51:vccin(109)" )
			)
			( pin "U2D1.BT63"
				( objectStatus "@baseboard_fab2_lib.baseboard_fab2(sch_1):page71_i51:vccin(110)" )
			)
			( pin "U2D1.BT61"
				( objectStatus "@baseboard_fab2_lib.baseboard_fab2(sch_1):page71_i51:vccin(111)" )
			)
			( pin "U2D1.BR84"
				( objectStatus "@baseboard_fab2_lib.baseboard_fab2(sch_1):page71_i51:vccin(112)" )
			)
			( pin "U2D1.BR62"
				( objectStatus "@baseboard_fab2_lib.baseboard_fab2(sch_1):page71_i51:vccin(113)" )
			)
			( pin "U2D1.BR60"
				( objectStatus "@baseboard_fab2_lib.baseboard_fab2(sch_1):page71_i51:vccin(114)" )
			)
			( pin "U2D1.BP83"
				( objectStatus "@baseboard_fab2_lib.baseboard_fab2(sch_1):page71_i51:vccin(115)" )
			)
			( pin "U2D1.BP81"
				( objectStatus "@baseboard_fab2_lib.baseboard_fab2(sch_1):page71_i51:vccin(116)" )
			)
			( pin "U2D1.BP79"
				( objectStatus "@baseboard_fab2_lib.baseboard_fab2(sch_1):page71_i51:vccin(117)" )
			)
			( pin "U2D1.BP77"
				( objectStatus "@baseboard_fab2_lib.baseboard_fab2(sch_1):page71_i51:vccin(118)" )
			)
			( pin "U2D1.BP75"
				( objectStatus "@baseboard_fab2_lib.baseboard_fab2(sch_1):page71_i51:vccin(119)" )
			)
			( pin "U2D1.BP73"
				( objectStatus "@baseboard_fab2_lib.baseboard_fab2(sch_1):page71_i51:vccin(120)" )
			)
			( pin "U2D1.BP71"
				( objectStatus "@baseboard_fab2_lib.baseboard_fab2(sch_1):page71_i51:vccin(121)" )
			)
			( pin "U2D1.BP69"
				( objectStatus "@baseboard_fab2_lib.baseboard_fab2(sch_1):page71_i51:vccin(122)" )
			)
			( pin "U2D1.BP67"
				( objectStatus "@baseboard_fab2_lib.baseboard_fab2(sch_1):page71_i51:vccin(123)" )
			)
			( pin "U2D1.BP65"
				( objectStatus "@baseboard_fab2_lib.baseboard_fab2(sch_1):page71_i51:vccin(124)" )
			)
			( pin "U2D1.BP63"
				( objectStatus "@baseboard_fab2_lib.baseboard_fab2(sch_1):page71_i51:vccin(125)" )
			)
			( pin "U2D1.BP61"
				( objectStatus "@baseboard_fab2_lib.baseboard_fab2(sch_1):page71_i51:vccin(126)" )
			)
			( pin "U2D1.BN84"
				( objectStatus "@baseboard_fab2_lib.baseboard_fab2(sch_1):page71_i51:vccin(127)" )
			)
			( pin "U2D1.BN82"
				( objectStatus "@baseboard_fab2_lib.baseboard_fab2(sch_1):page71_i51:vccin(128)" )
			)
			( pin "U2D1.BN80"
				( objectStatus "@baseboard_fab2_lib.baseboard_fab2(sch_1):page71_i51:vccin(129)" )
			)
			( pin "U2D1.BA86"
				( objectStatus "@baseboard_fab2_lib.baseboard_fab2(sch_1):page71_i51:vccin_sense" )
			)
			( pin "U2D1.AW86"
				( objectStatus "@baseboard_fab2_lib.baseboard_fab2(sch_1):page71_i51:vccinpmax(0)" )
			)
			( pin "U2D1.AV85"
				( objectStatus "@baseboard_fab2_lib.baseboard_fab2(sch_1):page71_i51:vccinpmax(1)" )
			)
			( pin "U2D1.AD41"
				( objectStatus "@baseboard_fab2_lib.baseboard_fab2(sch_1):page71_i51:vsensepmax" )
			)
			( pin "U2D1.AY85"
				( objectStatus "@baseboard_fab2_lib.baseboard_fab2(sch_1):page71_i51:vss_vccin_sense" )
			)
			( pin "R3D32.1"
				( objectStatus "@baseboard_fab2_lib.baseboard_fab2(sch_1):page71_i53:a" )
			)
			( pin "R3D32.2"
				( objectStatus "@baseboard_fab2_lib.baseboard_fab2(sch_1):page71_i53:b" )
			)
			( pin "C3D3.1"
				( objectStatus "@baseboard_fab2_lib.baseboard_fab2(sch_1):page72_i25:a" )
			)
			( pin "C3D3.2"
				( objectStatus "@baseboard_fab2_lib.baseboard_fab2(sch_1):page72_i25:b" )
			)
			( pin "U2D1.B49"
				( objectStatus "@baseboard_fab2_lib.baseboard_fab2(sch_1):page72_i32:vccd012(0)" )
			)
			( pin "U2D1.B53"
				( objectStatus "@baseboard_fab2_lib.baseboard_fab2(sch_1):page72_i32:vccd012(1)" )
			)
			( pin "U2D1.B59"
				( objectStatus "@baseboard_fab2_lib.baseboard_fab2(sch_1):page72_i32:vccd012(2)" )
			)
			( pin "U2D1.E46"
				( objectStatus "@baseboard_fab2_lib.baseboard_fab2(sch_1):page72_i32:vccd012(3)" )
			)
			( pin "U2D1.E48"
				( objectStatus "@baseboard_fab2_lib.baseboard_fab2(sch_1):page72_i32:vccd012(4)" )
			)
			( pin "U2D1.E50"
				( objectStatus "@baseboard_fab2_lib.baseboard_fab2(sch_1):page72_i32:vccd012(5)" )
			)
			( pin "U2D1.E52"
				( objectStatus "@baseboard_fab2_lib.baseboard_fab2(sch_1):page72_i32:vccd012(6)" )
			)
			( pin "U2D1.E54"
				( objectStatus "@baseboard_fab2_lib.baseboard_fab2(sch_1):page72_i32:vccd012(7)" )
			)
			( pin "U2D1.E56"
				( objectStatus "@baseboard_fab2_lib.baseboard_fab2(sch_1):page72_i32:vccd012(8)" )
			)
			( pin "U2D1.E58"
				( objectStatus "@baseboard_fab2_lib.baseboard_fab2(sch_1):page72_i32:vccd012(9)" )
			)
			( pin "U2D1.E60"
				( objectStatus "@baseboard_fab2_lib.baseboard_fab2(sch_1):page72_i32:vccd012(10)" )
			)
			( pin "U2D1.E62"
				( objectStatus "@baseboard_fab2_lib.baseboard_fab2(sch_1):page72_i32:vccd012(11)" )
			)
			( pin "U2D1.E64"
				( objectStatus "@baseboard_fab2_lib.baseboard_fab2(sch_1):page72_i32:vccd012(12)" )
			)
			( pin "U2D1.L46"
				( objectStatus "@baseboard_fab2_lib.baseboard_fab2(sch_1):page72_i32:vccd012(13)" )
			)
			( pin "U2D1.L48"
				( objectStatus "@baseboard_fab2_lib.baseboard_fab2(sch_1):page72_i32:vccd012(14)" )
			)
			( pin "U2D1.L50"
				( objectStatus "@baseboard_fab2_lib.baseboard_fab2(sch_1):page72_i32:vccd012(15)" )
			)
			( pin "U2D1.L52"
				( objectStatus "@baseboard_fab2_lib.baseboard_fab2(sch_1):page72_i32:vccd012(16)" )
			)
			( pin "U2D1.L54"
				( objectStatus "@baseboard_fab2_lib.baseboard_fab2(sch_1):page72_i32:vccd012(17)" )
			)
			( pin "U2D1.L56"
				( objectStatus "@baseboard_fab2_lib.baseboard_fab2(sch_1):page72_i32:vccd012(18)" )
			)
			( pin "U2D1.L58"
				( objectStatus "@baseboard_fab2_lib.baseboard_fab2(sch_1):page72_i32:vccd012(19)" )
			)
			( pin "U2D1.L60"
				( objectStatus "@baseboard_fab2_lib.baseboard_fab2(sch_1):page72_i32:vccd012(20)" )
			)
			( pin "U2D1.L62"
				( objectStatus "@baseboard_fab2_lib.baseboard_fab2(sch_1):page72_i32:vccd012(21)" )
			)
			( pin "U2D1.N64"
				( objectStatus "@baseboard_fab2_lib.baseboard_fab2(sch_1):page72_i32:vccd012(22)" )
			)
			( pin "U2D1.U46"
				( objectStatus "@baseboard_fab2_lib.baseboard_fab2(sch_1):page72_i32:vccd012(23)" )
			)
			( pin "U2D1.U48"
				( objectStatus "@baseboard_fab2_lib.baseboard_fab2(sch_1):page72_i32:vccd012(24)" )
			)
			( pin "U2D1.U50"
				( objectStatus "@baseboard_fab2_lib.baseboard_fab2(sch_1):page72_i32:vccd012(25)" )
			)
			( pin "U2D1.U52"
				( objectStatus "@baseboard_fab2_lib.baseboard_fab2(sch_1):page72_i32:vccd012(26)" )
			)
			( pin "U2D1.U54"
				( objectStatus "@baseboard_fab2_lib.baseboard_fab2(sch_1):page72_i32:vccd012(27)" )
			)
			( pin "U2D1.U56"
				( objectStatus "@baseboard_fab2_lib.baseboard_fab2(sch_1):page72_i32:vccd012(28)" )
			)
			( pin "U2D1.U58"
				( objectStatus "@baseboard_fab2_lib.baseboard_fab2(sch_1):page72_i32:vccd012(29)" )
			)
			( pin "U2D1.U60"
				( objectStatus "@baseboard_fab2_lib.baseboard_fab2(sch_1):page72_i32:vccd012(30)" )
			)
			( pin "U2D1.U62"
				( objectStatus "@baseboard_fab2_lib.baseboard_fab2(sch_1):page72_i32:vccd012(31)" )
			)
			( pin "U2D1.W64"
				( objectStatus "@baseboard_fab2_lib.baseboard_fab2(sch_1):page72_i32:vccd012(32)" )
			)
			( pin "U2D1.Y45"
				( objectStatus "@baseboard_fab2_lib.baseboard_fab2(sch_1):page72_i32:vccd012(33)" )
			)
			( pin "U2D1.Y47"
				( objectStatus "@baseboard_fab2_lib.baseboard_fab2(sch_1):page72_i32:vccd012(34)" )
			)
			( pin "U2D1.Y49"
				( objectStatus "@baseboard_fab2_lib.baseboard_fab2(sch_1):page72_i32:vccd012(35)" )
			)
			( pin "U2D1.Y51"
				( objectStatus "@baseboard_fab2_lib.baseboard_fab2(sch_1):page72_i32:vccd012(36)" )
			)
			( pin "U2D1.Y53"
				( objectStatus "@baseboard_fab2_lib.baseboard_fab2(sch_1):page72_i32:vccd012(37)" )
			)
			( pin "U2D1.Y55"
				( objectStatus "@baseboard_fab2_lib.baseboard_fab2(sch_1):page72_i32:vccd012(38)" )
			)
			( pin "U2D1.Y57"
				( objectStatus "@baseboard_fab2_lib.baseboard_fab2(sch_1):page72_i32:vccd012(39)" )
			)
			( pin "U2D1.Y59"
				( objectStatus "@baseboard_fab2_lib.baseboard_fab2(sch_1):page72_i32:vccd012(40)" )
			)
			( pin "U2D1.Y61"
				( objectStatus "@baseboard_fab2_lib.baseboard_fab2(sch_1):page72_i32:vccd012(41)" )
			)
			( pin "U2D1.Y63"
				( objectStatus "@baseboard_fab2_lib.baseboard_fab2(sch_1):page72_i32:vccd012(42)" )
			)
			( pin "U2D1.AD45"
				( objectStatus "@baseboard_fab2_lib.baseboard_fab2(sch_1):page72_i32:vccd012(43)" )
			)
			( pin "U2D1.AF55"
				( objectStatus "@baseboard_fab2_lib.baseboard_fab2(sch_1):page72_i32:vccd012(44)" )
			)
			( pin "U2D1.AF57"
				( objectStatus "@baseboard_fab2_lib.baseboard_fab2(sch_1):page72_i32:vccd012(45)" )
			)
			( pin "U2D1.AF59"
				( objectStatus "@baseboard_fab2_lib.baseboard_fab2(sch_1):page72_i32:vccd012(46)" )
			)
			( pin "U2D1.AF61"
				( objectStatus "@baseboard_fab2_lib.baseboard_fab2(sch_1):page72_i32:vccd012(47)" )
			)
			( pin "U2D1.AF63"
				( objectStatus "@baseboard_fab2_lib.baseboard_fab2(sch_1):page72_i32:vccd012(48)" )
			)
			( pin "U2D1.D45"
				( objectStatus "@baseboard_fab2_lib.baseboard_fab2(sch_1):page72_i32:vccd012(49)" )
			)
			( pin "U2D1.C46"
				( objectStatus "@baseboard_fab2_lib.baseboard_fab2(sch_1):page72_i32:vccd012(50)" )
			)
			( pin "U2D1.B47"
				( objectStatus "@baseboard_fab2_lib.baseboard_fab2(sch_1):page72_i32:vccd012(51)" )
			)
			( pin "U2D1.EF59"
				( objectStatus "@baseboard_fab2_lib.baseboard_fab2(sch_1):page72_i32:vccd345(0)" )
			)
			( pin "U2D1.EF53"
				( objectStatus "@baseboard_fab2_lib.baseboard_fab2(sch_1):page72_i32:vccd345(1)" )
			)
			( pin "U2D1.EF49"
				( objectStatus "@baseboard_fab2_lib.baseboard_fab2(sch_1):page72_i32:vccd345(2)" )
			)
			( pin "U2D1.EC62"
				( objectStatus "@baseboard_fab2_lib.baseboard_fab2(sch_1):page72_i32:vccd345(3)" )
			)
			( pin "U2D1.EC60"
				( objectStatus "@baseboard_fab2_lib.baseboard_fab2(sch_1):page72_i32:vccd345(4)" )
			)
			( pin "U2D1.EC58"
				( objectStatus "@baseboard_fab2_lib.baseboard_fab2(sch_1):page72_i32:vccd345(5)" )
			)
			( pin "U2D1.EC56"
				( objectStatus "@baseboard_fab2_lib.baseboard_fab2(sch_1):page72_i32:vccd345(6)" )
			)
			( pin "U2D1.EC54"
				( objectStatus "@baseboard_fab2_lib.baseboard_fab2(sch_1):page72_i32:vccd345(7)" )
			)
			( pin "U2D1.EC52"
				( objectStatus "@baseboard_fab2_lib.baseboard_fab2(sch_1):page72_i32:vccd345(8)" )
			)
			( pin "U2D1.EC50"
				( objectStatus "@baseboard_fab2_lib.baseboard_fab2(sch_1):page72_i32:vccd345(9)" )
			)
			( pin "U2D1.EC48"
				( objectStatus "@baseboard_fab2_lib.baseboard_fab2(sch_1):page72_i32:vccd345(10)" )
			)
			( pin "U2D1.EC46"
				( objectStatus "@baseboard_fab2_lib.baseboard_fab2(sch_1):page72_i32:vccd345(11)" )
			)
			( pin "U2D1.DU64"
				( objectStatus "@baseboard_fab2_lib.baseboard_fab2(sch_1):page72_i32:vccd345(12)" )
			)
			( pin "U2D1.DU62"
				( objectStatus "@baseboard_fab2_lib.baseboard_fab2(sch_1):page72_i32:vccd345(13)" )
			)
			( pin "U2D1.DU60"
				( objectStatus "@baseboard_fab2_lib.baseboard_fab2(sch_1):page72_i32:vccd345(14)" )
			)
			( pin "U2D1.DU58"
				( objectStatus "@baseboard_fab2_lib.baseboard_fab2(sch_1):page72_i32:vccd345(15)" )
			)
			( pin "U2D1.DU56"
				( objectStatus "@baseboard_fab2_lib.baseboard_fab2(sch_1):page72_i32:vccd345(16)" )
			)
			( pin "U2D1.DU54"
				( objectStatus "@baseboard_fab2_lib.baseboard_fab2(sch_1):page72_i32:vccd345(17)" )
			)
			( pin "U2D1.DU52"
				( objectStatus "@baseboard_fab2_lib.baseboard_fab2(sch_1):page72_i32:vccd345(18)" )
			)
			( pin "U2D1.DU50"
				( objectStatus "@baseboard_fab2_lib.baseboard_fab2(sch_1):page72_i32:vccd345(19)" )
			)
			( pin "U2D1.DU48"
				( objectStatus "@baseboard_fab2_lib.baseboard_fab2(sch_1):page72_i32:vccd345(20)" )
			)
			( pin "U2D1.DU46"
				( objectStatus "@baseboard_fab2_lib.baseboard_fab2(sch_1):page72_i32:vccd345(21)" )
			)
			( pin "U2D1.DL62"
				( objectStatus "@baseboard_fab2_lib.baseboard_fab2(sch_1):page72_i32:vccd345(22)" )
			)
			( pin "U2D1.DL60"
				( objectStatus "@baseboard_fab2_lib.baseboard_fab2(sch_1):page72_i32:vccd345(23)" )
			)
			( pin "U2D1.DL58"
				( objectStatus "@baseboard_fab2_lib.baseboard_fab2(sch_1):page72_i32:vccd345(24)" )
			)
			( pin "U2D1.DL56"
				( objectStatus "@baseboard_fab2_lib.baseboard_fab2(sch_1):page72_i32:vccd345(25)" )
			)
			( pin "U2D1.DL54"
				( objectStatus "@baseboard_fab2_lib.baseboard_fab2(sch_1):page72_i32:vccd345(26)" )
			)
			( pin "U2D1.DL52"
				( objectStatus "@baseboard_fab2_lib.baseboard_fab2(sch_1):page72_i32:vccd345(27)" )
			)
			( pin "U2D1.DL50"
				( objectStatus "@baseboard_fab2_lib.baseboard_fab2(sch_1):page72_i32:vccd345(28)" )
			)
			( pin "U2D1.DL48"
				( objectStatus "@baseboard_fab2_lib.baseboard_fab2(sch_1):page72_i32:vccd345(29)" )
			)
			( pin "U2D1.DL46"
				( objectStatus "@baseboard_fab2_lib.baseboard_fab2(sch_1):page72_i32:vccd345(30)" )
			)
			( pin "U2D1.DJ64"
				( objectStatus "@baseboard_fab2_lib.baseboard_fab2(sch_1):page72_i32:vccd345(31)" )
			)
			( pin "U2D1.DH63"
				( objectStatus "@baseboard_fab2_lib.baseboard_fab2(sch_1):page72_i32:vccd345(32)" )
			)
			( pin "U2D1.DH61"
				( objectStatus "@baseboard_fab2_lib.baseboard_fab2(sch_1):page72_i32:vccd345(33)" )
			)
			( pin "U2D1.DH59"
				( objectStatus "@baseboard_fab2_lib.baseboard_fab2(sch_1):page72_i32:vccd345(34)" )
			)
			( pin "U2D1.DH57"
				( objectStatus "@baseboard_fab2_lib.baseboard_fab2(sch_1):page72_i32:vccd345(35)" )
			)
			( pin "U2D1.DH55"
				( objectStatus "@baseboard_fab2_lib.baseboard_fab2(sch_1):page72_i32:vccd345(36)" )
			)
			( pin "U2D1.DH53"
				( objectStatus "@baseboard_fab2_lib.baseboard_fab2(sch_1):page72_i32:vccd345(37)" )
			)
			( pin "U2D1.DH51"
				( objectStatus "@baseboard_fab2_lib.baseboard_fab2(sch_1):page72_i32:vccd345(38)" )
			)
			( pin "U2D1.DH49"
				( objectStatus "@baseboard_fab2_lib.baseboard_fab2(sch_1):page72_i32:vccd345(39)" )
			)
			( pin "U2D1.DH47"
				( objectStatus "@baseboard_fab2_lib.baseboard_fab2(sch_1):page72_i32:vccd345(40)" )
			)
			( pin "U2D1.DH45"
				( objectStatus "@baseboard_fab2_lib.baseboard_fab2(sch_1):page72_i32:vccd345(41)" )
			)
			( pin "U2D1.DD45"
				( objectStatus "@baseboard_fab2_lib.baseboard_fab2(sch_1):page72_i32:vccd345(42)" )
			)
			( pin "U2D1.DB63"
				( objectStatus "@baseboard_fab2_lib.baseboard_fab2(sch_1):page72_i32:vccd345(43)" )
			)
			( pin "U2D1.DB61"
				( objectStatus "@baseboard_fab2_lib.baseboard_fab2(sch_1):page72_i32:vccd345(44)" )
			)
			( pin "U2D1.DB59"
				( objectStatus "@baseboard_fab2_lib.baseboard_fab2(sch_1):page72_i32:vccd345(45)" )
			)
			( pin "U2D1.DB57"
				( objectStatus "@baseboard_fab2_lib.baseboard_fab2(sch_1):page72_i32:vccd345(46)" )
			)
			( pin "U2D1.DB55"
				( objectStatus "@baseboard_fab2_lib.baseboard_fab2(sch_1):page72_i32:vccd345(47)" )
			)
			( pin "U2D1.DB53"
				( objectStatus "@baseboard_fab2_lib.baseboard_fab2(sch_1):page72_i32:vccd345(48)" )
			)
			( pin "U2D1.EF45"
				( objectStatus "@baseboard_fab2_lib.baseboard_fab2(sch_1):page72_i32:vccd345(49)" )
			)
			( pin "U2D1.EE44"
				( objectStatus "@baseboard_fab2_lib.baseboard_fab2(sch_1):page72_i32:vccd345(50)" )
			)
			( pin "U2D1.BL14"
				( objectStatus "@baseboard_fab2_lib.baseboard_fab2(sch_1):page72_i33:cd_vcc_core(0)" )
			)
			( pin "U2D1.BK15"
				( objectStatus "@baseboard_fab2_lib.baseboard_fab2(sch_1):page72_i33:cd_vcc_core(1)" )
			)
			( pin "U2D1.BK13"
				( objectStatus "@baseboard_fab2_lib.baseboard_fab2(sch_1):page72_i33:cd_vcc_core(2)" )
			)
			( pin "U2D1.BJ14"
				( objectStatus "@baseboard_fab2_lib.baseboard_fab2(sch_1):page72_i33:cd_vcc_core(3)" )
			)
			( pin "U2D1.BJ12"
				( objectStatus "@baseboard_fab2_lib.baseboard_fab2(sch_1):page72_i33:cd_vcc_core(4)" )
			)
			( pin "U2D1.BH13"
				( objectStatus "@baseboard_fab2_lib.baseboard_fab2(sch_1):page72_i33:cd_vcc_core(5)" )
			)
			( pin "U2D1.BG14"
				( objectStatus "@baseboard_fab2_lib.baseboard_fab2(sch_1):page72_i33:cd_vcc_core(6)" )
			)
			( pin "U2D1.BG12"
				( objectStatus "@baseboard_fab2_lib.baseboard_fab2(sch_1):page72_i33:cd_vcc_core(7)" )
			)
			( pin "U2D1.BF13"
				( objectStatus "@baseboard_fab2_lib.baseboard_fab2(sch_1):page72_i33:cd_vcc_core(8)" )
			)
			( pin "U2D1.BF11"
				( objectStatus "@baseboard_fab2_lib.baseboard_fab2(sch_1):page72_i33:cd_vcc_core(9)" )
			)
			( pin "U2D1.BE14"
				( objectStatus "@baseboard_fab2_lib.baseboard_fab2(sch_1):page72_i33:cd_vcc_core(10)" )
			)
			( pin "U2D1.BE12"
				( objectStatus "@baseboard_fab2_lib.baseboard_fab2(sch_1):page72_i33:cd_vcc_core(11)" )
			)
			( pin "U2D1.BD13"
				( objectStatus "@baseboard_fab2_lib.baseboard_fab2(sch_1):page72_i33:cd_vcc_core(12)" )
			)
			( pin "U2D1.BT27"
				( objectStatus "@baseboard_fab2_lib.baseboard_fab2(sch_1):page72_i33:cd_vccin(0)" )
			)
			( pin "U2D1.BU26"
				( objectStatus "@baseboard_fab2_lib.baseboard_fab2(sch_1):page72_i33:cd_vccin(1)" )
			)
			( pin "U2D1.BV27"
				( objectStatus "@baseboard_fab2_lib.baseboard_fab2(sch_1):page72_i33:cd_vccin(2)" )
			)
			( pin "U2D1.BY27"
				( objectStatus "@baseboard_fab2_lib.baseboard_fab2(sch_1):page72_i33:cd_vccin(3)" )
			)
			( pin "U2D1.BV15"
				( objectStatus "@baseboard_fab2_lib.baseboard_fab2(sch_1):page72_i33:cd_vccp(0)" )
			)
			( pin "U2D1.BV13"
				( objectStatus "@baseboard_fab2_lib.baseboard_fab2(sch_1):page72_i33:cd_vccp(1)" )
			)
			( pin "U2D1.BV11"
				( objectStatus "@baseboard_fab2_lib.baseboard_fab2(sch_1):page72_i33:cd_vccp(2)" )
			)
			( pin "U2D1.BU14"
				( objectStatus "@baseboard_fab2_lib.baseboard_fab2(sch_1):page72_i33:cd_vccp(3)" )
			)
			( pin "U2D1.BU12"
				( objectStatus "@baseboard_fab2_lib.baseboard_fab2(sch_1):page72_i33:cd_vccp(4)" )
			)
			( pin "U2D1.BT15"
				( objectStatus "@baseboard_fab2_lib.baseboard_fab2(sch_1):page72_i33:cd_vccp(5)" )
			)
			( pin "U2D1.BT13"
				( objectStatus "@baseboard_fab2_lib.baseboard_fab2(sch_1):page72_i33:cd_vccp(6)" )
			)
			( pin "U2D1.BT11"
				( objectStatus "@baseboard_fab2_lib.baseboard_fab2(sch_1):page72_i33:cd_vccp(7)" )
			)
			( pin "U2D1.BR14"
				( objectStatus "@baseboard_fab2_lib.baseboard_fab2(sch_1):page72_i33:cd_vccp(8)" )
			)
			( pin "U2D1.BR12"
				( objectStatus "@baseboard_fab2_lib.baseboard_fab2(sch_1):page72_i33:cd_vccp(9)" )
			)
			( pin "U2D1.BP15"
				( objectStatus "@baseboard_fab2_lib.baseboard_fab2(sch_1):page72_i33:cd_vccp(10)" )
			)
			( pin "U2D1.BP13"
				( objectStatus "@baseboard_fab2_lib.baseboard_fab2(sch_1):page72_i33:cd_vccp(11)" )
			)
			( pin "U2D1.BP11"
				( objectStatus "@baseboard_fab2_lib.baseboard_fab2(sch_1):page72_i33:cd_vccp(12)" )
			)
			( pin "U2D1.BN14"
				( objectStatus "@baseboard_fab2_lib.baseboard_fab2(sch_1):page72_i33:cd_vccp(13)" )
			)
			( pin "U2D1.BN12"
				( objectStatus "@baseboard_fab2_lib.baseboard_fab2(sch_1):page72_i33:cd_vccp(14)" )
			)
			( pin "U2D1.BM11"
				( objectStatus "@baseboard_fab2_lib.baseboard_fab2(sch_1):page72_i33:cd_vccp(15)" )
			)
			( pin "U2D1.B11"
				( objectStatus "@baseboard_fab2_lib.baseboard_fab2(sch_1):page72_i33:cd_vpp(0)" )
			)
			( pin "U2D1.A12"
				( objectStatus "@baseboard_fab2_lib.baseboard_fab2(sch_1):page72_i33:cd_vpp(1)" )
			)
			( pin "U2D1.A10"
				( objectStatus "@baseboard_fab2_lib.baseboard_fab2(sch_1):page72_i33:cd_vpp(2)" )
			)
			( pin "U2D1.A8"
				( objectStatus "@baseboard_fab2_lib.baseboard_fab2(sch_1):page72_i33:cd_vpp(3)" )
			)
			( pin "U2D1.CY55"
				( objectStatus "@baseboard_fab2_lib.baseboard_fab2(sch_1):page72_i33:vcc33" )
			)
			( pin "U2D1.CM15"
				( objectStatus "@baseboard_fab2_lib.baseboard_fab2(sch_1):page72_i33:vccio(20)" )
			)
			( pin "U2D1.CL12"
				( objectStatus "@baseboard_fab2_lib.baseboard_fab2(sch_1):page72_i33:vccio(21)" )
			)
			( pin "U2D1.CK5"
				( objectStatus "@baseboard_fab2_lib.baseboard_fab2(sch_1):page72_i33:vccio(22)" )
			)
			( pin "U2D1.CV7"
				( objectStatus "@baseboard_fab2_lib.baseboard_fab2(sch_1):page72_i33:vccio(23)" )
			)
			( pin "U2D1.CH9"
				( objectStatus "@baseboard_fab2_lib.baseboard_fab2(sch_1):page72_i33:vccio(24)" )
			)
			( pin "U2D1.D7"
				( objectStatus "@baseboard_fab2_lib.baseboard_fab2(sch_1):page72_i33:vccio(25)" )
			)
			( pin "U2D1.CE18"
				( objectStatus "@baseboard_fab2_lib.baseboard_fab2(sch_1):page72_i33:vccio(26)" )
			)
			( pin "U2D1.CD9"
				( objectStatus "@baseboard_fab2_lib.baseboard_fab2(sch_1):page72_i33:vccio(27)" )
			)
			( pin "U2D1.CB17"
				( objectStatus "@baseboard_fab2_lib.baseboard_fab2(sch_1):page72_i33:vccio(28)" )
			)
			( pin "U2D1.CB13"
				( objectStatus "@baseboard_fab2_lib.baseboard_fab2(sch_1):page72_i33:vccio(29)" )
			)
			( pin "U2D1.BP25"
				( objectStatus "@baseboard_fab2_lib.baseboard_fab2(sch_1):page72_i33:vccio(30)" )
			)
			( pin "U2D1.BJ24"
				( objectStatus "@baseboard_fab2_lib.baseboard_fab2(sch_1):page72_i33:vccio(31)" )
			)
			( pin "U2D1.BF23"
				( objectStatus "@baseboard_fab2_lib.baseboard_fab2(sch_1):page72_i33:vccio(32)" )
			)
			( pin "U2D1.DA14"
				( objectStatus "@baseboard_fab2_lib.baseboard_fab2(sch_1):page72_i33:vccio(33)" )
			)
			( pin "U2D1.BB5"
				( objectStatus "@baseboard_fab2_lib.baseboard_fab2(sch_1):page72_i33:vccio(34)" )
			)
			( pin "U2D1.BA24"
				( objectStatus "@baseboard_fab2_lib.baseboard_fab2(sch_1):page72_i33:vccio(35)" )
			)
			( pin "U2D1.AY11"
				( objectStatus "@baseboard_fab2_lib.baseboard_fab2(sch_1):page72_i33:vccio(36)" )
			)
			( pin "U2D1.AW6"
				( objectStatus "@baseboard_fab2_lib.baseboard_fab2(sch_1):page72_i33:vccio(37)" )
			)
			( pin "U2D1.AT11"
				( objectStatus "@baseboard_fab2_lib.baseboard_fab2(sch_1):page72_i33:vccio(38)" )
			)
			( pin "U2D1.DD7"
				( objectStatus "@baseboard_fab2_lib.baseboard_fab2(sch_1):page72_i33:vccio(39)" )
			)
			( pin "U2D1.AN10"
				( objectStatus "@baseboard_fab2_lib.baseboard_fab2(sch_1):page72_i33:vccio(40)" )
			)
			( pin "U2D1.DF13"
				( objectStatus "@baseboard_fab2_lib.baseboard_fab2(sch_1):page72_i33:vccio(41)" )
			)
			( pin "U2D1.AH9"
				( objectStatus "@baseboard_fab2_lib.baseboard_fab2(sch_1):page72_i33:vccio(42)" )
			)
			( pin "U2D1.AC4"
				( objectStatus "@baseboard_fab2_lib.baseboard_fab2(sch_1):page72_i33:vccio(43)" )
			)
			( pin "U2D1.AC20"
				( objectStatus "@baseboard_fab2_lib.baseboard_fab2(sch_1):page72_i33:vccio(44)" )
			)
			( pin "U2D1.AA10"
				( objectStatus "@baseboard_fab2_lib.baseboard_fab2(sch_1):page72_i33:vccio(45)" )
			)
			( pin "U2D1.W6"
				( objectStatus "@baseboard_fab2_lib.baseboard_fab2(sch_1):page72_i33:vccio(46)" )
			)
			( pin "U2D1.W4"
				( objectStatus "@baseboard_fab2_lib.baseboard_fab2(sch_1):page72_i33:vccio(47)" )
			)
			( pin "U2D1.DF21"
				( objectStatus "@baseboard_fab2_lib.baseboard_fab2(sch_1):page72_i33:vccio(48)" )
			)
			( pin "U2D1.U14"
				( objectStatus "@baseboard_fab2_lib.baseboard_fab2(sch_1):page72_i33:vccio(49)" )
			)
			( pin "U2D1.T3"
				( objectStatus "@baseboard_fab2_lib.baseboard_fab2(sch_1):page72_i33:vccio(50)" )
			)
			( pin "U2D1.P5"
				( objectStatus "@baseboard_fab2_lib.baseboard_fab2(sch_1):page72_i33:vccio(51)" )
			)
			( pin "U2D1.M21"
				( objectStatus "@baseboard_fab2_lib.baseboard_fab2(sch_1):page72_i33:vccio(52)" )
			)
			( pin "U2D1.M11"
				( objectStatus "@baseboard_fab2_lib.baseboard_fab2(sch_1):page72_i33:vccio(53)" )
			)
			( pin "U2D1.DG8"
				( objectStatus "@baseboard_fab2_lib.baseboard_fab2(sch_1):page72_i33:vccio(54)" )
			)
			( pin "U2D1.DH7"
				( objectStatus "@baseboard_fab2_lib.baseboard_fab2(sch_1):page72_i33:vccio(55)" )
			)
			( pin "U2D1.L16"
				( objectStatus "@baseboard_fab2_lib.baseboard_fab2(sch_1):page72_i33:vccio(56)" )
			)
			( pin "U2D1.L14"
				( objectStatus "@baseboard_fab2_lib.baseboard_fab2(sch_1):page72_i33:vccio(57)" )
			)
			( pin "U2D1.J10"
				( objectStatus "@baseboard_fab2_lib.baseboard_fab2(sch_1):page72_i33:vccio(58)" )
			)
			( pin "U2D1.H13"
				( objectStatus "@baseboard_fab2_lib.baseboard_fab2(sch_1):page72_i33:vccio(59)" )
			)
			( pin "U2D1.DJ16"
				( objectStatus "@baseboard_fab2_lib.baseboard_fab2(sch_1):page72_i33:vccio(60)" )
			)
			( pin "U2D1.DM17"
				( objectStatus "@baseboard_fab2_lib.baseboard_fab2(sch_1):page72_i33:vccio(61)" )
			)
			( pin "U2D1.DN8"
				( objectStatus "@baseboard_fab2_lib.baseboard_fab2(sch_1):page72_i33:vccio(62)" )
			)
			( pin "U2D1.DP19"
				( objectStatus "@baseboard_fab2_lib.baseboard_fab2(sch_1):page72_i33:vccio(63)" )
			)
			( pin "U2D1.DR10"
				( objectStatus "@baseboard_fab2_lib.baseboard_fab2(sch_1):page72_i33:vccio(64)" )
			)
			( pin "U2D1.DR2"
				( objectStatus "@baseboard_fab2_lib.baseboard_fab2(sch_1):page72_i33:vccio(65)" )
			)
			( pin "U2D1.DU20"
				( objectStatus "@baseboard_fab2_lib.baseboard_fab2(sch_1):page72_i33:vccio(66)" )
			)
			( pin "U2D1.EA12"
				( objectStatus "@baseboard_fab2_lib.baseboard_fab2(sch_1):page72_i33:vccio(67)" )
			)
			( pin "U2D1.EB15"
				( objectStatus "@baseboard_fab2_lib.baseboard_fab2(sch_1):page72_i33:vccio(68)" )
			)
			( pin "U2D1.J2"
				( objectStatus "@baseboard_fab2_lib.baseboard_fab2(sch_1):page72_i33:vccio(69)" )
			)
			( pin "U2D1.K15"
				( objectStatus "@baseboard_fab2_lib.baseboard_fab2(sch_1):page72_i33:vccio(70)" )
			)
			( pin "U2D1.M7"
				( objectStatus "@baseboard_fab2_lib.baseboard_fab2(sch_1):page72_i33:vccio(71)" )
			)
			( pin "U2D1.M9"
				( objectStatus "@baseboard_fab2_lib.baseboard_fab2(sch_1):page72_i33:vccio(72)" )
			)
			( pin "U2D1.N18"
				( objectStatus "@baseboard_fab2_lib.baseboard_fab2(sch_1):page72_i33:vccio(73)" )
			)
			( pin "U2D1.W10"
				( objectStatus "@baseboard_fab2_lib.baseboard_fab2(sch_1):page72_i33:vccio(74)" )
			)
			( pin "U2D1.BC26"
				( objectStatus "@baseboard_fab2_lib.baseboard_fab2(sch_1):page72_i33:vccio(75)" )
			)
			( pin "U2D1.BB27"
				( objectStatus "@baseboard_fab2_lib.baseboard_fab2(sch_1):page72_i33:vccio(76)" )
			)
			( pin "U2D1.BA26"
				( objectStatus "@baseboard_fab2_lib.baseboard_fab2(sch_1):page72_i33:vccio(77)" )
			)
			( pin "U2D1.AY27"
				( objectStatus "@baseboard_fab2_lib.baseboard_fab2(sch_1):page72_i33:vccio(78)" )
			)
			( pin "U2D1.AW26"
				( objectStatus "@baseboard_fab2_lib.baseboard_fab2(sch_1):page72_i33:vccio(79)" )
			)
			( pin "U2D1.AV27"
				( objectStatus "@baseboard_fab2_lib.baseboard_fab2(sch_1):page72_i33:vccio(80)" )
			)
			( pin "U2D1.CF27"
				( objectStatus "@baseboard_fab2_lib.baseboard_fab2(sch_1):page72_i33:vccio(81)" )
			)
			( pin "U2D1.CD27"
				( objectStatus "@baseboard_fab2_lib.baseboard_fab2(sch_1):page72_i33:vccio(82)" )
			)
			( pin "U2D1.CC26"
				( objectStatus "@baseboard_fab2_lib.baseboard_fab2(sch_1):page72_i33:vccio(83)" )
			)
			( pin "U2D1.CJ28"
				( objectStatus "@baseboard_fab2_lib.baseboard_fab2(sch_1):page72_i33:vccio(84)" )
			)
			( pin "U2D1.CH27"
				( objectStatus "@baseboard_fab2_lib.baseboard_fab2(sch_1):page72_i33:vccio(85)" )
			)
			( pin "U2D1.BM27"
				( objectStatus "@baseboard_fab2_lib.baseboard_fab2(sch_1):page72_i33:vccio(86)" )
			)
			( pin "U2D1.BL26"
				( objectStatus "@baseboard_fab2_lib.baseboard_fab2(sch_1):page72_i33:vccio(87)" )
			)
			( pin "U2D1.BK27"
				( objectStatus "@baseboard_fab2_lib.baseboard_fab2(sch_1):page72_i33:vccio(88)" )
			)
			( pin "U2D1.BK25"
				( objectStatus "@baseboard_fab2_lib.baseboard_fab2(sch_1):page72_i33:vccio(89)" )
			)
			( pin "U2D1.BJ26"
				( objectStatus "@baseboard_fab2_lib.baseboard_fab2(sch_1):page72_i33:vccio(90)" )
			)
			( pin "U2D1.BH27"
				( objectStatus "@baseboard_fab2_lib.baseboard_fab2(sch_1):page72_i33:vccio(91)" )
			)
			( pin "U2D1.BH25"
				( objectStatus "@baseboard_fab2_lib.baseboard_fab2(sch_1):page72_i33:vccio(92)" )
			)
			( pin "U2D1.BG26"
				( objectStatus "@baseboard_fab2_lib.baseboard_fab2(sch_1):page72_i33:vccio(93)" )
			)
			( pin "U2D1.BF27"
				( objectStatus "@baseboard_fab2_lib.baseboard_fab2(sch_1):page72_i33:vccio(94)" )
			)
			( pin "U2D1.AE36"
				( objectStatus "@baseboard_fab2_lib.baseboard_fab2(sch_1):page72_i33:vccio(95)" )
			)
			( pin "U2D1.AD37"
				( objectStatus "@baseboard_fab2_lib.baseboard_fab2(sch_1):page72_i33:vccio(96)" )
			)
			( pin "U2D1.AC36"
				( objectStatus "@baseboard_fab2_lib.baseboard_fab2(sch_1):page72_i33:vccio(97)" )
			)
			( pin "U2D1.AF35"
				( objectStatus "@baseboard_fab2_lib.baseboard_fab2(sch_1):page72_i33:vccio(98)" )
			)
			( pin "U2D1.AD35"
				( objectStatus "@baseboard_fab2_lib.baseboard_fab2(sch_1):page72_i33:vccio(99)" )
			)
			( pin "U2D1.AE34"
				( objectStatus "@baseboard_fab2_lib.baseboard_fab2(sch_1):page72_i33:vccio(100)" )
			)
			( pin "U2D1.AG34"
				( objectStatus "@baseboard_fab2_lib.baseboard_fab2(sch_1):page72_i33:vccio(101)" )
			)
			( pin "U2D1.AM29"
				( objectStatus "@baseboard_fab2_lib.baseboard_fab2(sch_1):page72_i33:vccio(102)" )
			)
			( pin "U2D1.AL28"
				( objectStatus "@baseboard_fab2_lib.baseboard_fab2(sch_1):page72_i33:vccio(103)" )
			)
			( pin "U2D1.AR28"
				( objectStatus "@baseboard_fab2_lib.baseboard_fab2(sch_1):page72_i33:vccio(104)" )
			)
			( pin "U2D1.CJ66"
				( objectStatus "@baseboard_fab2_lib.baseboard_fab2(sch_1):page72_i33:vccsa(0)" )
			)
			( pin "U2D1.CJ64"
				( objectStatus "@baseboard_fab2_lib.baseboard_fab2(sch_1):page72_i33:vccsa(1)" )
			)
			( pin "U2D1.CH75"
				( objectStatus "@baseboard_fab2_lib.baseboard_fab2(sch_1):page72_i33:vccsa(2)" )
			)
			( pin "U2D1.CH65"
				( objectStatus "@baseboard_fab2_lib.baseboard_fab2(sch_1):page72_i33:vccsa(3)" )
			)
			( pin "U2D1.CG74"
				( objectStatus "@baseboard_fab2_lib.baseboard_fab2(sch_1):page72_i33:vccsa(4)" )
			)
			( pin "U2D1.CG66"
				( objectStatus "@baseboard_fab2_lib.baseboard_fab2(sch_1):page72_i33:vccsa(5)" )
			)
			( pin "U2D1.CG64"
				( objectStatus "@baseboard_fab2_lib.baseboard_fab2(sch_1):page72_i33:vccsa(6)" )
			)
			( pin "U2D1.CF75"
				( objectStatus "@baseboard_fab2_lib.baseboard_fab2(sch_1):page72_i33:vccsa(7)" )
			)
			( pin "U2D1.CF73"
				( objectStatus "@baseboard_fab2_lib.baseboard_fab2(sch_1):page72_i33:vccsa(8)" )
			)
			( pin "U2D1.CF67"
				( objectStatus "@baseboard_fab2_lib.baseboard_fab2(sch_1):page72_i33:vccsa(9)" )
			)
			( pin "U2D1.CF65"
				( objectStatus "@baseboard_fab2_lib.baseboard_fab2(sch_1):page72_i33:vccsa(10)" )
			)
			( pin "U2D1.CE74"
				( objectStatus "@baseboard_fab2_lib.baseboard_fab2(sch_1):page72_i33:vccsa(11)" )
			)
			( pin "U2D1.CE72"
				( objectStatus "@baseboard_fab2_lib.baseboard_fab2(sch_1):page72_i33:vccsa(12)" )
			)
			( pin "U2D1.CE68"
				( objectStatus "@baseboard_fab2_lib.baseboard_fab2(sch_1):page72_i33:vccsa(13)" )
			)
			( pin "U2D1.CE66"
				( objectStatus "@baseboard_fab2_lib.baseboard_fab2(sch_1):page72_i33:vccsa(14)" )
			)
			( pin "U2D1.CE64"
				( objectStatus "@baseboard_fab2_lib.baseboard_fab2(sch_1):page72_i33:vccsa(15)" )
			)
			( pin "U2D1.CD71"
				( objectStatus "@baseboard_fab2_lib.baseboard_fab2(sch_1):page72_i33:vccsa(16)" )
			)
			( pin "U2D1.CD69"
				( objectStatus "@baseboard_fab2_lib.baseboard_fab2(sch_1):page72_i33:vccsa(17)" )
			)
			( pin "U2D1.CD67"
				( objectStatus "@baseboard_fab2_lib.baseboard_fab2(sch_1):page72_i33:vccsa(18)" )
			)
			( pin "U2D1.CD65"
				( objectStatus "@baseboard_fab2_lib.baseboard_fab2(sch_1):page72_i33:vccsa(19)" )
			)
			( pin "U2D1.CC70"
				( objectStatus "@baseboard_fab2_lib.baseboard_fab2(sch_1):page72_i33:vccsa(20)" )
			)
			( pin "U2D1.CC68"
				( objectStatus "@baseboard_fab2_lib.baseboard_fab2(sch_1):page72_i33:vccsa(21)" )
			)
			( pin "U2D1.CC66"
				( objectStatus "@baseboard_fab2_lib.baseboard_fab2(sch_1):page72_i33:vccsa(22)" )
			)
			( pin "U2D1.CB69"
				( objectStatus "@baseboard_fab2_lib.baseboard_fab2(sch_1):page72_i33:vccsa(23)" )
			)
			( pin "U2D1.CB67"
				( objectStatus "@baseboard_fab2_lib.baseboard_fab2(sch_1):page72_i33:vccsa(24)" )
			)
			( pin "U2D1.CB65"
				( objectStatus "@baseboard_fab2_lib.baseboard_fab2(sch_1):page72_i33:vccsa(25)" )
			)
			( pin "U2D1.BN16"
				( objectStatus "@baseboard_fab2_lib.baseboard_fab2(sch_1):page73_i107:cd_vcc_core_sense" )
			)
			( pin "U2D1.BU16"
				( objectStatus "@baseboard_fab2_lib.baseboard_fab2(sch_1):page73_i107:cd_vccp_sense(0)" )
			)
			( pin "U2D1.BT17"
				( objectStatus "@baseboard_fab2_lib.baseboard_fab2(sch_1):page73_i107:cd_vccp_sense(1)" )
			)
			( pin "U2D1.BL16"
				( objectStatus "@baseboard_fab2_lib.baseboard_fab2(sch_1):page73_i107:cd_vss_vcc_core_sense" )
			)
			( pin "U2D1.EF83"
				( objectStatus "@baseboard_fab2_lib.baseboard_fab2(sch_1):page73_i107:rsvd(0)" )
			)
			( pin "U2D1.EF81"
				( objectStatus "@baseboard_fab2_lib.baseboard_fab2(sch_1):page73_i107:rsvd(1)" )
			)
			( pin "U2D1.EF77"
				( objectStatus "@baseboard_fab2_lib.baseboard_fab2(sch_1):page73_i107:rsvd(2)" )
			)
			( pin "U2D1.EF47"
				( objectStatus "@baseboard_fab2_lib.baseboard_fab2(sch_1):page73_i107:rsvd(3)" )
			)
			( pin "U2D1.EE84"
				( objectStatus "@baseboard_fab2_lib.baseboard_fab2(sch_1):page73_i107:rsvd(4)" )
			)
			( pin "U2D1.EE82"
				( objectStatus "@baseboard_fab2_lib.baseboard_fab2(sch_1):page73_i107:rsvd(5)" )
			)
			( pin "U2D1.EE6"
				( objectStatus "@baseboard_fab2_lib.baseboard_fab2(sch_1):page73_i107:rsvd(6)" )
			)
			( pin "U2D1.EE46"
				( objectStatus "@baseboard_fab2_lib.baseboard_fab2(sch_1):page73_i107:rsvd(7)" )
			)
			( pin "U2D1.EE16"
				( objectStatus "@baseboard_fab2_lib.baseboard_fab2(sch_1):page73_i107:rsvd(8)" )
			)
			( pin "U2D1.ED83"
				( objectStatus "@baseboard_fab2_lib.baseboard_fab2(sch_1):page73_i107:rsvd(9)" )
			)
			( pin "U2D1.ED5"
				( objectStatus "@baseboard_fab2_lib.baseboard_fab2(sch_1):page73_i107:rsvd(10)" )
			)
			( pin "U2D1.ED45"
				( objectStatus "@baseboard_fab2_lib.baseboard_fab2(sch_1):page73_i107:rsvd(11)" )
			)
			( pin "U2D1.EC84"
				( objectStatus "@baseboard_fab2_lib.baseboard_fab2(sch_1):page73_i107:rsvd(12)" )
			)
			( pin "U2D1.EC44"
				( objectStatus "@baseboard_fab2_lib.baseboard_fab2(sch_1):page73_i107:rsvd(13)" )
			)
			( pin "U2D1.EC4"
				( objectStatus "@baseboard_fab2_lib.baseboard_fab2(sch_1):page73_i107:rsvd(14)" )
			)
			( pin "U2D1.EC16"
				( objectStatus "@baseboard_fab2_lib.baseboard_fab2(sch_1):page73_i107:rsvd(15)" )
			)
			( pin "U2D1.EB85"
				( objectStatus "@baseboard_fab2_lib.baseboard_fab2(sch_1):page73_i107:rsvd(16)" )
			)
			( pin "U2D1.EB5"
				( objectStatus "@baseboard_fab2_lib.baseboard_fab2(sch_1):page73_i107:rsvd(17)" )
			)
			( pin "U2D1.EB3"
				( objectStatus "@baseboard_fab2_lib.baseboard_fab2(sch_1):page73_i107:rsvd(18)" )
			)
			( pin "U2D1.EA44"
				( objectStatus "@baseboard_fab2_lib.baseboard_fab2(sch_1):page73_i107:rsvd(19)" )
			)
			( pin "U2D1.EA4"
				( objectStatus "@baseboard_fab2_lib.baseboard_fab2(sch_1):page73_i107:rsvd(20)" )
			)
			( pin "U2D1.DY3"
				( objectStatus "@baseboard_fab2_lib.baseboard_fab2(sch_1):page73_i107:rsvd(21)" )
			)
			( pin "U2D1.DW46"
				( objectStatus "@baseboard_fab2_lib.baseboard_fab2(sch_1):page73_i107:rsvd(22)" )
			)
			( pin "U2D1.DW44"
				( objectStatus "@baseboard_fab2_lib.baseboard_fab2(sch_1):page73_i107:rsvd(23)" )
			)
			( pin "U2D1.DV71"
				( objectStatus "@baseboard_fab2_lib.baseboard_fab2(sch_1):page73_i107:rsvd(24)" )
			)
			( pin "U2D1.DV61"
				( objectStatus "@baseboard_fab2_lib.baseboard_fab2(sch_1):page73_i107:rsvd(25)" )
			)
			( pin "U2D1.DU44"
				( objectStatus "@baseboard_fab2_lib.baseboard_fab2(sch_1):page73_i107:rsvd(26)" )
			)
			( pin "U2D1.DT71"
				( objectStatus "@baseboard_fab2_lib.baseboard_fab2(sch_1):page73_i107:rsvd(27)" )
			)
			( pin "U2D1.DR44"
				( objectStatus "@baseboard_fab2_lib.baseboard_fab2(sch_1):page73_i107:rsvd(28)" )
			)
			( pin "U2D1.DP65"
				( objectStatus "@baseboard_fab2_lib.baseboard_fab2(sch_1):page73_i107:rsvd(29)" )
			)
			( pin "U2D1.DP17"
				( objectStatus "@baseboard_fab2_lib.baseboard_fab2(sch_1):page73_i107:rsvd(30)" )
			)
			( pin "U2D1.DN66"
				( objectStatus "@baseboard_fab2_lib.baseboard_fab2(sch_1):page73_i107:rsvd(31)" )
			)
			( pin "U2D1.DN62"
				( objectStatus "@baseboard_fab2_lib.baseboard_fab2(sch_1):page73_i107:rsvd(32)" )
			)
			( pin "U2D1.DM67"
				( objectStatus "@baseboard_fab2_lib.baseboard_fab2(sch_1):page73_i107:rsvd(33)" )
			)
			( pin "U2D1.DL66"
				( objectStatus "@baseboard_fab2_lib.baseboard_fab2(sch_1):page73_i107:rsvd(34)" )
			)
			( pin "U2D1.DL38"
				( objectStatus "@baseboard_fab2_lib.baseboard_fab2(sch_1):page73_i107:rsvd(35)" )
			)
			( pin "U2D1.DK67"
				( objectStatus "@baseboard_fab2_lib.baseboard_fab2(sch_1):page73_i107:rsvd(36)" )
			)
			( pin "U2D1.DK65"
				( objectStatus "@baseboard_fab2_lib.baseboard_fab2(sch_1):page73_i107:rsvd(37)" )
			)
			( pin "U2D1.DK37"
				( objectStatus "@baseboard_fab2_lib.baseboard_fab2(sch_1):page73_i107:rsvd(38)" )
			)
			( pin "U2D1.DK15"
				( objectStatus "@baseboard_fab2_lib.baseboard_fab2(sch_1):page73_i107:rsvd(39)" )
			)
			( pin "U2D1.DJ66"
				( objectStatus "@baseboard_fab2_lib.baseboard_fab2(sch_1):page73_i107:rsvd(40)" )
			)
			( pin "U2D1.DJ36"
				( objectStatus "@baseboard_fab2_lib.baseboard_fab2(sch_1):page73_i107:rsvd(41)" )
			)
			( pin "U2D1.DH65"
				( objectStatus "@baseboard_fab2_lib.baseboard_fab2(sch_1):page73_i107:rsvd(42)" )
			)
			( pin "U2D1.DG64"
				( objectStatus "@baseboard_fab2_lib.baseboard_fab2(sch_1):page73_i107:rsvd(43)" )
			)
			( pin "U2D1.DG36"
				( objectStatus "@baseboard_fab2_lib.baseboard_fab2(sch_1):page73_i107:rsvd(44)" )
			)
			( pin "U2D1.DD51"
				( objectStatus "@baseboard_fab2_lib.baseboard_fab2(sch_1):page73_i107:rsvd(45)" )
			)
			( pin "U2D1.DC52"
				( objectStatus "@baseboard_fab2_lib.baseboard_fab2(sch_1):page73_i107:rsvd(46)" )
			)
			( pin "U2D1.DC46"
				( objectStatus "@baseboard_fab2_lib.baseboard_fab2(sch_1):page73_i107:rsvd(47)" )
			)
			( pin "U2D1.DA56"
				( objectStatus "@baseboard_fab2_lib.baseboard_fab2(sch_1):page73_i107:rsvd(48)" )
			)
			( pin "U2D1.DA54"
				( objectStatus "@baseboard_fab2_lib.baseboard_fab2(sch_1):page73_i107:rsvd(49)" )
			)
			( pin "U2D1.DA52"
				( objectStatus "@baseboard_fab2_lib.baseboard_fab2(sch_1):page73_i107:rsvd(50)" )
			)
			( pin "U2D1.DA40"
				( objectStatus "@baseboard_fab2_lib.baseboard_fab2(sch_1):page73_i107:rsvd(51)" )
			)
			( pin "U2D1.DA24"
				( objectStatus "@baseboard_fab2_lib.baseboard_fab2(sch_1):page73_i107:rsvd(52)" )
			)
			( pin "U2D1.CY73"
				( objectStatus "@baseboard_fab2_lib.baseboard_fab2(sch_1):page73_i107:rsvd(53)" )
			)
			( pin "U2D1.CY63"
				( objectStatus "@baseboard_fab2_lib.baseboard_fab2(sch_1):page73_i107:rsvd(54)" )
			)
			( pin "U2D1.CY57"
				( objectStatus "@baseboard_fab2_lib.baseboard_fab2(sch_1):page73_i107:rsvd(55)" )
			)
			( pin "U2D1.CY53"
				( objectStatus "@baseboard_fab2_lib.baseboard_fab2(sch_1):page73_i107:rsvd(56)" )
			)
			( pin "U2D1.CY39"
				( objectStatus "@baseboard_fab2_lib.baseboard_fab2(sch_1):page73_i107:rsvd(57)" )
			)
			( pin "U2D1.CY25"
				( objectStatus "@baseboard_fab2_lib.baseboard_fab2(sch_1):page73_i107:rsvd(58)" )
			)
			( pin "U2D1.CY23"
				( objectStatus "@baseboard_fab2_lib.baseboard_fab2(sch_1):page73_i107:rsvd(59)" )
			)
			( pin "U2D1.CW62"
				( objectStatus "@baseboard_fab2_lib.baseboard_fab2(sch_1):page73_i107:rsvd(60)" )
			)
			( pin "U2D1.CW60"
				( objectStatus "@baseboard_fab2_lib.baseboard_fab2(sch_1):page73_i107:rsvd(61)" )
			)
			( pin "U2D1.CW24"
				( objectStatus "@baseboard_fab2_lib.baseboard_fab2(sch_1):page73_i107:rsvd(62)" )
			)
			( pin "U2D1.CW22"
				( objectStatus "@baseboard_fab2_lib.baseboard_fab2(sch_1):page73_i107:rsvd(63)" )
			)
			( pin "U2D1.CV69"
				( objectStatus "@baseboard_fab2_lib.baseboard_fab2(sch_1):page73_i107:rsvd(64)" )
			)
			( pin "U2D1.CV23"
				( objectStatus "@baseboard_fab2_lib.baseboard_fab2(sch_1):page73_i107:rsvd(65)" )
			)
			( pin "U2D1.CU60"
				( objectStatus "@baseboard_fab2_lib.baseboard_fab2(sch_1):page73_i107:rsvd(66)" )
			)
			( pin "U2D1.CU6"
				( objectStatus "@baseboard_fab2_lib.baseboard_fab2(sch_1):page73_i107:rsvd(67)" )
			)
			( pin "U2D1.CU24"
				( objectStatus "@baseboard_fab2_lib.baseboard_fab2(sch_1):page73_i107:rsvd(68)" )
			)
			( pin "U2D1.CT69"
				( objectStatus "@baseboard_fab2_lib.baseboard_fab2(sch_1):page73_i107:rsvd(69)" )
			)
			( pin "U2D1.CT5"
				( objectStatus "@baseboard_fab2_lib.baseboard_fab2(sch_1):page73_i107:rsvd(70)" )
			)
			( pin "U2D1.CT23"
				( objectStatus "@baseboard_fab2_lib.baseboard_fab2(sch_1):page73_i107:rsvd(71)" )
			)
			( pin "U2D1.CR60"
				( objectStatus "@baseboard_fab2_lib.baseboard_fab2(sch_1):page73_i107:rsvd(72)" )
			)
			( pin "U2D1.CP31"
				( objectStatus "@baseboard_fab2_lib.baseboard_fab2(sch_1):page73_i107:rsvd(73)" )
			)
			( pin "U2D1.CP23"
				( objectStatus "@baseboard_fab2_lib.baseboard_fab2(sch_1):page73_i107:rsvd(74)" )
			)
			( pin "U2D1.CN28"
				( objectStatus "@baseboard_fab2_lib.baseboard_fab2(sch_1):page73_i107:rsvd(75)" )
			)
			( pin "U2D1.CN24"
				( objectStatus "@baseboard_fab2_lib.baseboard_fab2(sch_1):page73_i107:rsvd(76)" )
			)
			( pin "U2D1.CN22"
				( objectStatus "@baseboard_fab2_lib.baseboard_fab2(sch_1):page73_i107:rsvd(77)" )
			)
			( pin "U2D1.CM25"
				( objectStatus "@baseboard_fab2_lib.baseboard_fab2(sch_1):page73_i107:rsvd(78)" )
			)
			( pin "U2D1.CM23"
				( objectStatus "@baseboard_fab2_lib.baseboard_fab2(sch_1):page73_i107:rsvd(79)" )
			)
			( pin "U2D1.CL26"
				( objectStatus "@baseboard_fab2_lib.baseboard_fab2(sch_1):page73_i107:rsvd(80)" )
			)
			( pin "U2D1.EE10"
				( objectStatus "@baseboard_fab2_lib.baseboard_fab2(sch_1):page73_i107:vccio(0)" )
			)
			( pin "U2D1.AE10"
				( objectStatus "@baseboard_fab2_lib.baseboard_fab2(sch_1):page73_i107:vccio(1)" )
			)
			( pin "U2D1.AF5"
				( objectStatus "@baseboard_fab2_lib.baseboard_fab2(sch_1):page73_i107:vccio(2)" )
			)
			( pin "U2D1.DV11"
				( objectStatus "@baseboard_fab2_lib.baseboard_fab2(sch_1):page73_i107:vccio(3)" )
			)
			( pin "U2D1.AM5"
				( objectStatus "@baseboard_fab2_lib.baseboard_fab2(sch_1):page73_i107:vccio(4)" )
			)
			( pin "U2D1.AT5"
				( objectStatus "@baseboard_fab2_lib.baseboard_fab2(sch_1):page73_i107:vccio(5)" )
			)
			( pin "U2D1.AT7"
				( objectStatus "@baseboard_fab2_lib.baseboard_fab2(sch_1):page73_i107:vccio(6)" )
			)
			( pin "U2D1.BE24"
				( objectStatus "@baseboard_fab2_lib.baseboard_fab2(sch_1):page73_i107:vccio(7)" )
			)
			( pin "U2D1.DK21"
				( objectStatus "@baseboard_fab2_lib.baseboard_fab2(sch_1):page73_i107:vccio(8)" )
			)
			( pin "U2D1.CF5"
				( objectStatus "@baseboard_fab2_lib.baseboard_fab2(sch_1):page73_i107:vccio(9)" )
			)
			( pin "U2D1.CG14"
				( objectStatus "@baseboard_fab2_lib.baseboard_fab2(sch_1):page73_i107:vccio(10)" )
			)
			( pin "U2D1.CL20"
				( objectStatus "@baseboard_fab2_lib.baseboard_fab2(sch_1):page73_i107:vccio(11)" )
			)
			( pin "U2D1.CP13"
				( objectStatus "@baseboard_fab2_lib.baseboard_fab2(sch_1):page73_i107:vccio(12)" )
			)
			( pin "U2D1.DE14"
				( objectStatus "@baseboard_fab2_lib.baseboard_fab2(sch_1):page73_i107:vccio(13)" )
			)
			( pin "U2D1.DC18"
				( objectStatus "@baseboard_fab2_lib.baseboard_fab2(sch_1):page73_i107:vccio(14)" )
			)
			( pin "U2D1.CY17"
				( objectStatus "@baseboard_fab2_lib.baseboard_fab2(sch_1):page73_i107:vccio(15)" )
			)
			( pin "U2D1.CU18"
				( objectStatus "@baseboard_fab2_lib.baseboard_fab2(sch_1):page73_i107:vccio(16)" )
			)
			( pin "U2D1.CV21"
				( objectStatus "@baseboard_fab2_lib.baseboard_fab2(sch_1):page73_i107:vccio(17)" )
			)
			( pin "U2D1.CU12"
				( objectStatus "@baseboard_fab2_lib.baseboard_fab2(sch_1):page73_i107:vccio(18)" )
			)
			( pin "U2D1.CN6"
				( objectStatus "@baseboard_fab2_lib.baseboard_fab2(sch_1):page73_i107:vccio(19)" )
			)
			( pin "U2D1.BH5"
				( objectStatus "@baseboard_fab2_lib.baseboard_fab2(sch_1):page73_i107:vccio_sense" )
			)
			( pin "U2D1.CE76"
				( objectStatus "@baseboard_fab2_lib.baseboard_fab2(sch_1):page73_i107:vccsa_sense" )
			)
			( pin "U2D1.BF5"
				( objectStatus "@baseboard_fab2_lib.baseboard_fab2(sch_1):page73_i107:vss_vccio_sense" )
			)
			( pin "U2D1.CG76"
				( objectStatus "@baseboard_fab2_lib.baseboard_fab2(sch_1):page73_i107:vss_vccsa_sense" )
			)
			( pin "U2D1.J74"
				( objectStatus "@baseboard_fab2_lib.baseboard_fab2(sch_1):page74_i20:vss(1094)" )
			)
			( pin "U2D1.J72"
				( objectStatus "@baseboard_fab2_lib.baseboard_fab2(sch_1):page74_i20:vss(1095)" )
			)
			( pin "U2D1.J40"
				( objectStatus "@baseboard_fab2_lib.baseboard_fab2(sch_1):page74_i20:vss(1096)" )
			)
			( pin "U2D1.J38"
				( objectStatus "@baseboard_fab2_lib.baseboard_fab2(sch_1):page74_i20:vss(1097)" )
			)
			( pin "U2D1.J34"
				( objectStatus "@baseboard_fab2_lib.baseboard_fab2(sch_1):page74_i20:vss(1098)" )
			)
			( pin "U2D1.J32"
				( objectStatus "@baseboard_fab2_lib.baseboard_fab2(sch_1):page74_i20:vss(1099)" )
			)
			( pin "U2D1.J28"
				( objectStatus "@baseboard_fab2_lib.baseboard_fab2(sch_1):page74_i20:vss(1100)" )
			)
			( pin "U2D1.J26"
				( objectStatus "@baseboard_fab2_lib.baseboard_fab2(sch_1):page74_i20:vss(1101)" )
			)
			( pin "U2D1.J22"
				( objectStatus "@baseboard_fab2_lib.baseboard_fab2(sch_1):page74_i20:vss(1102)" )
			)
			( pin "U2D1.J14"
				( objectStatus "@baseboard_fab2_lib.baseboard_fab2(sch_1):page74_i20:vss(1103)" )
			)
			( pin "U2D1.J12"
				( objectStatus "@baseboard_fab2_lib.baseboard_fab2(sch_1):page74_i20:vss(1104)" )
			)
			( pin "U2D1.J4"
				( objectStatus "@baseboard_fab2_lib.baseboard_fab2(sch_1):page74_i20:vss(1105)" )
			)
			( pin "U2D1.DN44"
				( objectStatus "@baseboard_fab2_lib.baseboard_fab2(sch_1):page74_i20:vss(1106)" )
			)
			( pin "U2D1.H75"
				( objectStatus "@baseboard_fab2_lib.baseboard_fab2(sch_1):page74_i20:vss(1107)" )
			)
			( pin "U2D1.H71"
				( objectStatus "@baseboard_fab2_lib.baseboard_fab2(sch_1):page74_i20:vss(1108)" )
			)
			( pin "U2D1.H65"
				( objectStatus "@baseboard_fab2_lib.baseboard_fab2(sch_1):page74_i20:vss(1109)" )
			)
			( pin "U2D1.H41"
				( objectStatus "@baseboard_fab2_lib.baseboard_fab2(sch_1):page74_i20:vss(1110)" )
			)
			( pin "U2D1.H39"
				( objectStatus "@baseboard_fab2_lib.baseboard_fab2(sch_1):page74_i20:vss(1111)" )
			)
			( pin "U2D1.H37"
				( objectStatus "@baseboard_fab2_lib.baseboard_fab2(sch_1):page74_i20:vss(1112)" )
			)
			( pin "U2D1.H35"
				( objectStatus "@baseboard_fab2_lib.baseboard_fab2(sch_1):page74_i20:vss(1113)" )
			)
			( pin "U2D1.H33"
				( objectStatus "@baseboard_fab2_lib.baseboard_fab2(sch_1):page74_i20:vss(1114)" )
			)
			( pin "U2D1.H31"
				( objectStatus "@baseboard_fab2_lib.baseboard_fab2(sch_1):page74_i20:vss(1115)" )
			)
			( pin "U2D1.H29"
				( objectStatus "@baseboard_fab2_lib.baseboard_fab2(sch_1):page74_i20:vss(1116)" )
			)
			( pin "U2D1.H27"
				( objectStatus "@baseboard_fab2_lib.baseboard_fab2(sch_1):page74_i20:vss(1117)" )
			)
			( pin "U2D1.H25"
				( objectStatus "@baseboard_fab2_lib.baseboard_fab2(sch_1):page74_i20:vss(1118)" )
			)
			( pin "U2D1.H11"
				( objectStatus "@baseboard_fab2_lib.baseboard_fab2(sch_1):page74_i20:vss(1119)" )
			)
			( pin "U2D1.H3"
				( objectStatus "@baseboard_fab2_lib.baseboard_fab2(sch_1):page74_i20:vss(1120)" )
			)
			( pin "U2D1.G82"
				( objectStatus "@baseboard_fab2_lib.baseboard_fab2(sch_1):page74_i20:vss(1121)" )
			)
			( pin "U2D1.G80"
				( objectStatus "@baseboard_fab2_lib.baseboard_fab2(sch_1):page74_i20:vss(1122)" )
			)
			( pin "U2D1.G78"
				( objectStatus "@baseboard_fab2_lib.baseboard_fab2(sch_1):page74_i20:vss(1123)" )
			)
			( pin "U2D1.G76"
				( objectStatus "@baseboard_fab2_lib.baseboard_fab2(sch_1):page74_i20:vss(1124)" )
			)
			( pin "U2D1.G70"
				( objectStatus "@baseboard_fab2_lib.baseboard_fab2(sch_1):page74_i20:vss(1125)" )
			)
			( pin "U2D1.G66"
				( objectStatus "@baseboard_fab2_lib.baseboard_fab2(sch_1):page74_i20:vss(1126)" )
			)
			( pin "U2D1.G42"
				( objectStatus "@baseboard_fab2_lib.baseboard_fab2(sch_1):page74_i20:vss(1127)" )
			)
			( pin "U2D1.G38"
				( objectStatus "@baseboard_fab2_lib.baseboard_fab2(sch_1):page74_i20:vss(1128)" )
			)
			( pin "U2D1.G36"
				( objectStatus "@baseboard_fab2_lib.baseboard_fab2(sch_1):page74_i20:vss(1129)" )
			)
			( pin "U2D1.G32"
				( objectStatus "@baseboard_fab2_lib.baseboard_fab2(sch_1):page74_i20:vss(1130)" )
			)
			( pin "U2D1.G30"
				( objectStatus "@baseboard_fab2_lib.baseboard_fab2(sch_1):page74_i20:vss(1131)" )
			)
			( pin "U2D1.G26"
				( objectStatus "@baseboard_fab2_lib.baseboard_fab2(sch_1):page74_i20:vss(1132)" )
			)
			( pin "U2D1.G24"
				( objectStatus "@baseboard_fab2_lib.baseboard_fab2(sch_1):page74_i20:vss(1133)" )
			)
			( pin "U2D1.G22"
				( objectStatus "@baseboard_fab2_lib.baseboard_fab2(sch_1):page74_i20:vss(1134)" )
			)
			( pin "U2D1.G8"
				( objectStatus "@baseboard_fab2_lib.baseboard_fab2(sch_1):page74_i20:vss(1135)" )
			)
			( pin "U2D1.G4"
				( objectStatus "@baseboard_fab2_lib.baseboard_fab2(sch_1):page74_i20:vss(1136)" )
			)
			( pin "U2D1.F69"
				( objectStatus "@baseboard_fab2_lib.baseboard_fab2(sch_1):page74_i20:vss(1137)" )
			)
			( pin "U2D1.F67"
				( objectStatus "@baseboard_fab2_lib.baseboard_fab2(sch_1):page74_i20:vss(1138)" )
			)
			( pin "U2D1.F43"
				( objectStatus "@baseboard_fab2_lib.baseboard_fab2(sch_1):page74_i20:vss(1139)" )
			)
			( pin "U2D1.F37"
				( objectStatus "@baseboard_fab2_lib.baseboard_fab2(sch_1):page74_i20:vss(1140)" )
			)
			( pin "U2D1.F31"
				( objectStatus "@baseboard_fab2_lib.baseboard_fab2(sch_1):page74_i20:vss(1141)" )
			)
			( pin "U2D1.F25"
				( objectStatus "@baseboard_fab2_lib.baseboard_fab2(sch_1):page74_i20:vss(1142)" )
			)
			( pin "U2D1.F19"
				( objectStatus "@baseboard_fab2_lib.baseboard_fab2(sch_1):page74_i20:vss(1143)" )
			)
			( pin "U2D1.F17"
				( objectStatus "@baseboard_fab2_lib.baseboard_fab2(sch_1):page74_i20:vss(1144)" )
			)
			( pin "U2D1.F5"
				( objectStatus "@baseboard_fab2_lib.baseboard_fab2(sch_1):page74_i20:vss(1145)" )
			)
			( pin "U2D1.E76"
				( objectStatus "@baseboard_fab2_lib.baseboard_fab2(sch_1):page74_i20:vss(1146)" )
			)
			( pin "U2D1.E74"
				( objectStatus "@baseboard_fab2_lib.baseboard_fab2(sch_1):page74_i20:vss(1147)" )
			)
			( pin "U2D1.E72"
				( objectStatus "@baseboard_fab2_lib.baseboard_fab2(sch_1):page74_i20:vss(1148)" )
			)
			( pin "U2D1.E22"
				( objectStatus "@baseboard_fab2_lib.baseboard_fab2(sch_1):page74_i20:vss(1149)" )
			)
			( pin "U2D1.E20"
				( objectStatus "@baseboard_fab2_lib.baseboard_fab2(sch_1):page74_i20:vss(1150)" )
			)
			( pin "U2D1.E18"
				( objectStatus "@baseboard_fab2_lib.baseboard_fab2(sch_1):page74_i20:vss(1151)" )
			)
			( pin "U2D1.E16"
				( objectStatus "@baseboard_fab2_lib.baseboard_fab2(sch_1):page74_i20:vss(1152)" )
			)
			( pin "U2D1.E8"
				( objectStatus "@baseboard_fab2_lib.baseboard_fab2(sch_1):page74_i20:vss(1153)" )
			)
			( pin "U2D1.E6"
				( objectStatus "@baseboard_fab2_lib.baseboard_fab2(sch_1):page74_i20:vss(1154)" )
			)
			( pin "U2D1.D77"
				( objectStatus "@baseboard_fab2_lib.baseboard_fab2(sch_1):page74_i20:vss(1155)" )
			)
			( pin "U2D1.D43"
				( objectStatus "@baseboard_fab2_lib.baseboard_fab2(sch_1):page74_i20:vss(1156)" )
			)
			( pin "U2D1.D41"
				( objectStatus "@baseboard_fab2_lib.baseboard_fab2(sch_1):page74_i20:vss(1157)" )
			)
			( pin "U2D1.D39"
				( objectStatus "@baseboard_fab2_lib.baseboard_fab2(sch_1):page74_i20:vss(1158)" )
			)
			( pin "U2D1.D37"
				( objectStatus "@baseboard_fab2_lib.baseboard_fab2(sch_1):page74_i20:vss(1159)" )
			)
			( pin "U2D1.D35"
				( objectStatus "@baseboard_fab2_lib.baseboard_fab2(sch_1):page74_i20:vss(1160)" )
			)
			( pin "U2D1.D33"
				( objectStatus "@baseboard_fab2_lib.baseboard_fab2(sch_1):page74_i20:vss(1161)" )
			)
			( pin "U2D1.D31"
				( objectStatus "@baseboard_fab2_lib.baseboard_fab2(sch_1):page74_i20:vss(1162)" )
			)
			( pin "U2D1.D29"
				( objectStatus "@baseboard_fab2_lib.baseboard_fab2(sch_1):page74_i20:vss(1163)" )
			)
			( pin "U2D1.D27"
				( objectStatus "@baseboard_fab2_lib.baseboard_fab2(sch_1):page74_i20:vss(1164)" )
			)
			( pin "U2D1.D25"
				( objectStatus "@baseboard_fab2_lib.baseboard_fab2(sch_1):page74_i20:vss(1165)" )
			)
			( pin "U2D1.D13"
				( objectStatus "@baseboard_fab2_lib.baseboard_fab2(sch_1):page74_i20:vss(1166)" )
			)
			( pin "U2D1.D11"
				( objectStatus "@baseboard_fab2_lib.baseboard_fab2(sch_1):page74_i20:vss(1167)" )
			)
			( pin "U2D1.CM27"
				( objectStatus "@baseboard_fab2_lib.baseboard_fab2(sch_1):page74_i20:vss(1168)" )
			)
			( pin "U2D1.C78"
				( objectStatus "@baseboard_fab2_lib.baseboard_fab2(sch_1):page74_i20:vss(1169)" )
			)
			( pin "U2D1.C76"
				( objectStatus "@baseboard_fab2_lib.baseboard_fab2(sch_1):page74_i20:vss(1170)" )
			)
			( pin "U2D1.C16"
				( objectStatus "@baseboard_fab2_lib.baseboard_fab2(sch_1):page74_i20:vss(1171)" )
			)
			( pin "U2D1.C14"
				( objectStatus "@baseboard_fab2_lib.baseboard_fab2(sch_1):page74_i20:vss(1172)" )
			)
			( pin "U2D1.C12"
				( objectStatus "@baseboard_fab2_lib.baseboard_fab2(sch_1):page74_i20:vss(1173)" )
			)
			( pin "U2D1.C10"
				( objectStatus "@baseboard_fab2_lib.baseboard_fab2(sch_1):page74_i20:vss(1174)" )
			)
			( pin "U2D1.C8"
				( objectStatus "@baseboard_fab2_lib.baseboard_fab2(sch_1):page74_i20:vss(1175)" )
			)
			( pin "U2D1.B75"
				( objectStatus "@baseboard_fab2_lib.baseboard_fab2(sch_1):page74_i20:vss(1176)" )
			)
			( pin "U2D1.B71"
				( objectStatus "@baseboard_fab2_lib.baseboard_fab2(sch_1):page74_i20:vss(1177)" )
			)
			( pin "U2D1.B37"
				( objectStatus "@baseboard_fab2_lib.baseboard_fab2(sch_1):page74_i20:vss(1178)" )
			)
			( pin "U2D1.B31"
				( objectStatus "@baseboard_fab2_lib.baseboard_fab2(sch_1):page74_i20:vss(1179)" )
			)
			( pin "U2D1.B25"
				( objectStatus "@baseboard_fab2_lib.baseboard_fab2(sch_1):page74_i20:vss(1180)" )
			)
			( pin "U2D1.A38"
				( objectStatus "@baseboard_fab2_lib.baseboard_fab2(sch_1):page74_i20:vss(1181)" )
			)
			( pin "U2D1.A36"
				( objectStatus "@baseboard_fab2_lib.baseboard_fab2(sch_1):page74_i20:vss(1182)" )
			)
			( pin "U2D1.A32"
				( objectStatus "@baseboard_fab2_lib.baseboard_fab2(sch_1):page74_i20:vss(1183)" )
			)
			( pin "U2D1.A30"
				( objectStatus "@baseboard_fab2_lib.baseboard_fab2(sch_1):page74_i20:vss(1184)" )
			)
			( pin "U2D1.A26"
				( objectStatus "@baseboard_fab2_lib.baseboard_fab2(sch_1):page74_i20:vss(1185)" )
			)
			( pin "U2D1.AC58"
				( objectStatus "@baseboard_fab2_lib.baseboard_fab2(sch_1):page74_i20:vss(1186)" )
			)
			( pin "U2D1.AC60"
				( objectStatus "@baseboard_fab2_lib.baseboard_fab2(sch_1):page74_i20:vss(1187)" )
			)
			( pin "U2D1.AC62"
				( objectStatus "@baseboard_fab2_lib.baseboard_fab2(sch_1):page74_i20:vss(1188)" )
			)
			( pin "U2D1.AJ4"
				( objectStatus "@baseboard_fab2_lib.baseboard_fab2(sch_1):page74_i20:vss(1189)" )
			)
			( pin "U2D1.AR6"
				( objectStatus "@baseboard_fab2_lib.baseboard_fab2(sch_1):page74_i20:vss(1190)" )
			)
			( pin "U2D1.CG6"
				( objectStatus "@baseboard_fab2_lib.baseboard_fab2(sch_1):page74_i20:vss(1191)" )
			)
			( pin "U2D1.CW6"
				( objectStatus "@baseboard_fab2_lib.baseboard_fab2(sch_1):page74_i20:vss(1192)" )
			)
			( pin "U2D1.DE48"
				( objectStatus "@baseboard_fab2_lib.baseboard_fab2(sch_1):page74_i20:vss(1193)" )
			)
			( pin "U2D1.DE50"
				( objectStatus "@baseboard_fab2_lib.baseboard_fab2(sch_1):page74_i20:vss(1194)" )
			)
			( pin "U2D1.DE52"
				( objectStatus "@baseboard_fab2_lib.baseboard_fab2(sch_1):page74_i20:vss(1195)" )
			)
			( pin "U2D1.DE54"
				( objectStatus "@baseboard_fab2_lib.baseboard_fab2(sch_1):page74_i20:vss(1196)" )
			)
			( pin "U2D1.DE56"
				( objectStatus "@baseboard_fab2_lib.baseboard_fab2(sch_1):page74_i20:vss(1197)" )
			)
			( pin "U2D1.DE58"
				( objectStatus "@baseboard_fab2_lib.baseboard_fab2(sch_1):page74_i20:vss(1198)" )
			)
			( pin "U2D1.DE60"
				( objectStatus "@baseboard_fab2_lib.baseboard_fab2(sch_1):page74_i20:vss(1199)" )
			)
			( pin "U2D1.DE62"
				( objectStatus "@baseboard_fab2_lib.baseboard_fab2(sch_1):page74_i20:vss(1200)" )
			)
			( pin "U2D1.DL8"
				( objectStatus "@baseboard_fab2_lib.baseboard_fab2(sch_1):page74_i20:vss(1201)" )
			)
			( pin "U2D1.DN18"
				( objectStatus "@baseboard_fab2_lib.baseboard_fab2(sch_1):page74_i20:vss(1202)" )
			)
			( pin "U2D1.DP45"
				( objectStatus "@baseboard_fab2_lib.baseboard_fab2(sch_1):page74_i20:vss(1203)" )
			)
			( pin "U2D1.DP47"
				( objectStatus "@baseboard_fab2_lib.baseboard_fab2(sch_1):page74_i20:vss(1204)" )
			)
			( pin "U2D1.DP49"
				( objectStatus "@baseboard_fab2_lib.baseboard_fab2(sch_1):page74_i20:vss(1205)" )
			)
			( pin "U2D1.DP51"
				( objectStatus "@baseboard_fab2_lib.baseboard_fab2(sch_1):page74_i20:vss(1206)" )
			)
			( pin "U2D1.DP53"
				( objectStatus "@baseboard_fab2_lib.baseboard_fab2(sch_1):page74_i20:vss(1207)" )
			)
			( pin "U2D1.DP55"
				( objectStatus "@baseboard_fab2_lib.baseboard_fab2(sch_1):page74_i20:vss(1208)" )
			)
			( pin "U2D1.DP57"
				( objectStatus "@baseboard_fab2_lib.baseboard_fab2(sch_1):page74_i20:vss(1209)" )
			)
			( pin "U2D1.DP59"
				( objectStatus "@baseboard_fab2_lib.baseboard_fab2(sch_1):page74_i20:vss(1210)" )
			)
			( pin "U2D1.DP61"
				( objectStatus "@baseboard_fab2_lib.baseboard_fab2(sch_1):page74_i20:vss(1211)" )
			)
			( pin "U2D1.DP63"
				( objectStatus "@baseboard_fab2_lib.baseboard_fab2(sch_1):page74_i20:vss(1212)" )
			)
			( pin "U2D1.DP9"
				( objectStatus "@baseboard_fab2_lib.baseboard_fab2(sch_1):page74_i20:vss(1213)" )
			)
			( pin "U2D1.DV19"
				( objectStatus "@baseboard_fab2_lib.baseboard_fab2(sch_1):page74_i20:vss(1214)" )
			)
			( pin "U2D1.DY45"
				( objectStatus "@baseboard_fab2_lib.baseboard_fab2(sch_1):page74_i20:vss(1215)" )
			)
			( pin "U2D1.DY47"
				( objectStatus "@baseboard_fab2_lib.baseboard_fab2(sch_1):page74_i20:vss(1216)" )
			)
			( pin "U2D1.DY49"
				( objectStatus "@baseboard_fab2_lib.baseboard_fab2(sch_1):page74_i20:vss(1217)" )
			)
			( pin "U2D1.DY51"
				( objectStatus "@baseboard_fab2_lib.baseboard_fab2(sch_1):page74_i20:vss(1218)" )
			)
			( pin "U2D1.DY53"
				( objectStatus "@baseboard_fab2_lib.baseboard_fab2(sch_1):page74_i20:vss(1219)" )
			)
			( pin "U2D1.DY55"
				( objectStatus "@baseboard_fab2_lib.baseboard_fab2(sch_1):page74_i20:vss(1220)" )
			)
			( pin "U2D1.DY57"
				( objectStatus "@baseboard_fab2_lib.baseboard_fab2(sch_1):page74_i20:vss(1221)" )
			)
			( pin "U2D1.DY59"
				( objectStatus "@baseboard_fab2_lib.baseboard_fab2(sch_1):page74_i20:vss(1222)" )
			)
			( pin "U2D1.DY61"
				( objectStatus "@baseboard_fab2_lib.baseboard_fab2(sch_1):page74_i20:vss(1223)" )
			)
			( pin "U2D1.DY63"
				( objectStatus "@baseboard_fab2_lib.baseboard_fab2(sch_1):page74_i20:vss(1224)" )
			)
			( pin "U2D1.EA14"
				( objectStatus "@baseboard_fab2_lib.baseboard_fab2(sch_1):page74_i20:vss(1225)" )
			)
			( pin "U2D1.L8"
				( objectStatus "@baseboard_fab2_lib.baseboard_fab2(sch_1):page74_i20:vss(1226)" )
			)
			( pin "U2D1.V11"
				( objectStatus "@baseboard_fab2_lib.baseboard_fab2(sch_1):page74_i20:vss(1227)" )
			)
			( pin "U2D1.E66"
				( objectStatus "@baseboard_fab2_lib.baseboard_fab2(sch_1):page74_i20:vss(1228)" )
			)
			( pin "U2D1.ED69"
				( objectStatus "@baseboard_fab2_lib.baseboard_fab2(sch_1):page74_i20:vss(1229)" )
			)
			( pin "U2D1.EE80"
				( objectStatus "@baseboard_fab2_lib.baseboard_fab2(sch_1):page74_i20:vss(1230)" )
			)
			( pin "U2D1.EE8"
				( objectStatus "@baseboard_fab2_lib.baseboard_fab2(sch_1):page74_i20:vss(1231)" )
			)
			( pin "U2D1.EE40"
				( objectStatus "@baseboard_fab2_lib.baseboard_fab2(sch_1):page74_i20:vss(1232)" )
			)
			( pin "U2D1.ED81"
				( objectStatus "@baseboard_fab2_lib.baseboard_fab2(sch_1):page74_i20:vss(1233)" )
			)
			( pin "U2D1.ED7"
				( objectStatus "@baseboard_fab2_lib.baseboard_fab2(sch_1):page74_i20:vss(1234)" )
			)
			( pin "U2D1.ED41"
				( objectStatus "@baseboard_fab2_lib.baseboard_fab2(sch_1):page74_i20:vss(1235)" )
			)
			( pin "U2D1.EC82"
				( objectStatus "@baseboard_fab2_lib.baseboard_fab2(sch_1):page74_i20:vss(1236)" )
			)
			( pin "U2D1.EC6"
				( objectStatus "@baseboard_fab2_lib.baseboard_fab2(sch_1):page74_i20:vss(1237)" )
			)
			( pin "U2D1.EC42"
				( objectStatus "@baseboard_fab2_lib.baseboard_fab2(sch_1):page74_i20:vss(1238)" )
			)
			( pin "U2D1.DW2"
				( objectStatus "@baseboard_fab2_lib.baseboard_fab2(sch_1):page74_i20:vss(1239)" )
			)
			( pin "U2D1.EB83"
				( objectStatus "@baseboard_fab2_lib.baseboard_fab2(sch_1):page74_i20:vss(1240)" )
			)
			( pin "U2D1.EA84"
				( objectStatus "@baseboard_fab2_lib.baseboard_fab2(sch_1):page74_i20:vss(1241)" )
			)
			( pin "U2D1.DY85"
				( objectStatus "@baseboard_fab2_lib.baseboard_fab2(sch_1):page74_i20:vss(1242)" )
			)
			( pin "U2D1.J86"
				( objectStatus "@baseboard_fab2_lib.baseboard_fab2(sch_1):page74_i20:vss(1243)" )
			)
			( pin "U2D1.E82"
				( objectStatus "@baseboard_fab2_lib.baseboard_fab2(sch_1):page74_i20:vss(1244)" )
			)
			( pin "U2D1.D81"
				( objectStatus "@baseboard_fab2_lib.baseboard_fab2(sch_1):page74_i20:vss(1245)" )
			)
			( pin "U2D1.D3"
				( objectStatus "@baseboard_fab2_lib.baseboard_fab2(sch_1):page74_i20:vss(1246)" )
			)
			( pin "U2D1.C80"
				( objectStatus "@baseboard_fab2_lib.baseboard_fab2(sch_1):page74_i20:vss(1247)" )
			)
			( pin "U2D1.C4"
				( objectStatus "@baseboard_fab2_lib.baseboard_fab2(sch_1):page74_i20:vss(1248)" )
			)
			( pin "U2D1.B79"
				( objectStatus "@baseboard_fab2_lib.baseboard_fab2(sch_1):page74_i20:vss(1249)" )
			)
			( pin "U2D1.B5"
				( objectStatus "@baseboard_fab2_lib.baseboard_fab2(sch_1):page74_i20:vss(1250)" )
			)
			( pin "U2D1.B43"
				( objectStatus "@baseboard_fab2_lib.baseboard_fab2(sch_1):page74_i20:vss(1251)" )
			)
			( pin "U2D1.A42"
				( objectStatus "@baseboard_fab2_lib.baseboard_fab2(sch_1):page74_i20:vss(1252)" )
			)
			( pin "U2D1.B9"
				( objectStatus "@baseboard_fab2_lib.baseboard_fab2(sch_1):page74_i20:vss(1253)" )
			)
			( pin "U2D1.AA16"
				( objectStatus "@baseboard_fab2_lib.baseboard_fab2(sch_1):page74_i21:vss(934)" )
			)
			( pin "U2D1.AA4"
				( objectStatus "@baseboard_fab2_lib.baseboard_fab2(sch_1):page74_i21:vss(935)" )
			)
			( pin "U2D1.Y85"
				( objectStatus "@baseboard_fab2_lib.baseboard_fab2(sch_1):page74_i21:vss(936)" )
			)
			( pin "U2D1.Y83"
				( objectStatus "@baseboard_fab2_lib.baseboard_fab2(sch_1):page74_i21:vss(937)" )
			)
			( pin "U2D1.Y81"
				( objectStatus "@baseboard_fab2_lib.baseboard_fab2(sch_1):page74_i21:vss(938)" )
			)
			( pin "U2D1.Y79"
				( objectStatus "@baseboard_fab2_lib.baseboard_fab2(sch_1):page74_i21:vss(939)" )
			)
			( pin "U2D1.Y73"
				( objectStatus "@baseboard_fab2_lib.baseboard_fab2(sch_1):page74_i21:vss(940)" )
			)
			( pin "U2D1.Y71"
				( objectStatus "@baseboard_fab2_lib.baseboard_fab2(sch_1):page74_i21:vss(941)" )
			)
			( pin "U2D1.Y9"
				( objectStatus "@baseboard_fab2_lib.baseboard_fab2(sch_1):page74_i21:vss(942)" )
			)
			( pin "U2D1.Y7"
				( objectStatus "@baseboard_fab2_lib.baseboard_fab2(sch_1):page74_i21:vss(943)" )
			)
			( pin "U2D1.Y67"
				( objectStatus "@baseboard_fab2_lib.baseboard_fab2(sch_1):page74_i21:vss(944)" )
			)
			( pin "U2D1.Y5"
				( objectStatus "@baseboard_fab2_lib.baseboard_fab2(sch_1):page74_i21:vss(945)" )
			)
			( pin "U2D1.Y17"
				( objectStatus "@baseboard_fab2_lib.baseboard_fab2(sch_1):page74_i21:vss(946)" )
			)
			( pin "U2D1.Y15"
				( objectStatus "@baseboard_fab2_lib.baseboard_fab2(sch_1):page74_i21:vss(947)" )
			)
			( pin "U2D1.W82"
				( objectStatus "@baseboard_fab2_lib.baseboard_fab2(sch_1):page74_i21:vss(948)" )
			)
			( pin "U2D1.W78"
				( objectStatus "@baseboard_fab2_lib.baseboard_fab2(sch_1):page74_i21:vss(949)" )
			)
			( pin "U2D1.W74"
				( objectStatus "@baseboard_fab2_lib.baseboard_fab2(sch_1):page74_i21:vss(950)" )
			)
			( pin "U2D1.W68"
				( objectStatus "@baseboard_fab2_lib.baseboard_fab2(sch_1):page74_i21:vss(951)" )
			)
			( pin "U2D1.W42"
				( objectStatus "@baseboard_fab2_lib.baseboard_fab2(sch_1):page74_i21:vss(952)" )
			)
			( pin "U2D1.W40"
				( objectStatus "@baseboard_fab2_lib.baseboard_fab2(sch_1):page74_i21:vss(953)" )
			)
			( pin "U2D1.W38"
				( objectStatus "@baseboard_fab2_lib.baseboard_fab2(sch_1):page74_i21:vss(954)" )
			)
			( pin "U2D1.W36"
				( objectStatus "@baseboard_fab2_lib.baseboard_fab2(sch_1):page74_i21:vss(955)" )
			)
			( pin "U2D1.W34"
				( objectStatus "@baseboard_fab2_lib.baseboard_fab2(sch_1):page74_i21:vss(956)" )
			)
			( pin "U2D1.W32"
				( objectStatus "@baseboard_fab2_lib.baseboard_fab2(sch_1):page74_i21:vss(957)" )
			)
			( pin "U2D1.W30"
				( objectStatus "@baseboard_fab2_lib.baseboard_fab2(sch_1):page74_i21:vss(958)" )
			)
			( pin "U2D1.W28"
				( objectStatus "@baseboard_fab2_lib.baseboard_fab2(sch_1):page74_i21:vss(959)" )
			)
			( pin "U2D1.W26"
				( objectStatus "@baseboard_fab2_lib.baseboard_fab2(sch_1):page74_i21:vss(960)" )
			)
			( pin "U2D1.W24"
				( objectStatus "@baseboard_fab2_lib.baseboard_fab2(sch_1):page74_i21:vss(961)" )
			)
			( pin "U2D1.W22"
				( objectStatus "@baseboard_fab2_lib.baseboard_fab2(sch_1):page74_i21:vss(962)" )
			)
			( pin "U2D1.W12"
				( objectStatus "@baseboard_fab2_lib.baseboard_fab2(sch_1):page74_i21:vss(963)" )
			)
			( pin "U2D1.AC56"
				( objectStatus "@baseboard_fab2_lib.baseboard_fab2(sch_1):page74_i21:vss(964)" )
			)
			( pin "U2D1.W8"
				( objectStatus "@baseboard_fab2_lib.baseboard_fab2(sch_1):page74_i21:vss(965)" )
			)
			( pin "U2D1.V83"
				( objectStatus "@baseboard_fab2_lib.baseboard_fab2(sch_1):page74_i21:vss(966)" )
			)
			( pin "U2D1.V77"
				( objectStatus "@baseboard_fab2_lib.baseboard_fab2(sch_1):page74_i21:vss(967)" )
			)
			( pin "U2D1.V75"
				( objectStatus "@baseboard_fab2_lib.baseboard_fab2(sch_1):page74_i21:vss(968)" )
			)
			( pin "U2D1.V73"
				( objectStatus "@baseboard_fab2_lib.baseboard_fab2(sch_1):page74_i21:vss(969)" )
			)
			( pin "U2D1.V43"
				( objectStatus "@baseboard_fab2_lib.baseboard_fab2(sch_1):page74_i21:vss(970)" )
			)
			( pin "U2D1.V23"
				( objectStatus "@baseboard_fab2_lib.baseboard_fab2(sch_1):page74_i21:vss(971)" )
			)
			( pin "U2D1.V21"
				( objectStatus "@baseboard_fab2_lib.baseboard_fab2(sch_1):page74_i21:vss(972)" )
			)
			( pin "U2D1.V15"
				( objectStatus "@baseboard_fab2_lib.baseboard_fab2(sch_1):page74_i21:vss(973)" )
			)
			( pin "U2D1.V13"
				( objectStatus "@baseboard_fab2_lib.baseboard_fab2(sch_1):page74_i21:vss(974)" )
			)
			( pin "U2D1.V9"
				( objectStatus "@baseboard_fab2_lib.baseboard_fab2(sch_1):page74_i21:vss(975)" )
			)
			( pin "U2D1.V5"
				( objectStatus "@baseboard_fab2_lib.baseboard_fab2(sch_1):page74_i21:vss(976)" )
			)
			( pin "U2D1.V1"
				( objectStatus "@baseboard_fab2_lib.baseboard_fab2(sch_1):page74_i21:vss(977)" )
			)
			( pin "U2D1.U86"
				( objectStatus "@baseboard_fab2_lib.baseboard_fab2(sch_1):page74_i21:vss(978)" )
			)
			( pin "U2D1.U80"
				( objectStatus "@baseboard_fab2_lib.baseboard_fab2(sch_1):page74_i21:vss(979)" )
			)
			( pin "U2D1.U78"
				( objectStatus "@baseboard_fab2_lib.baseboard_fab2(sch_1):page74_i21:vss(980)" )
			)
			( pin "U2D1.U76"
				( objectStatus "@baseboard_fab2_lib.baseboard_fab2(sch_1):page74_i21:vss(981)" )
			)
			( pin "U2D1.U74"
				( objectStatus "@baseboard_fab2_lib.baseboard_fab2(sch_1):page74_i21:vss(982)" )
			)
			( pin "U2D1.U70"
				( objectStatus "@baseboard_fab2_lib.baseboard_fab2(sch_1):page74_i21:vss(983)" )
			)
			( pin "U2D1.U68"
				( objectStatus "@baseboard_fab2_lib.baseboard_fab2(sch_1):page74_i21:vss(984)" )
			)
			( pin "U2D1.U42"
				( objectStatus "@baseboard_fab2_lib.baseboard_fab2(sch_1):page74_i21:vss(985)" )
			)
			( pin "U2D1.U36"
				( objectStatus "@baseboard_fab2_lib.baseboard_fab2(sch_1):page74_i21:vss(986)" )
			)
			( pin "U2D1.U30"
				( objectStatus "@baseboard_fab2_lib.baseboard_fab2(sch_1):page74_i21:vss(987)" )
			)
			( pin "U2D1.U24"
				( objectStatus "@baseboard_fab2_lib.baseboard_fab2(sch_1):page74_i21:vss(988)" )
			)
			( pin "U2D1.U22"
				( objectStatus "@baseboard_fab2_lib.baseboard_fab2(sch_1):page74_i21:vss(989)" )
			)
			( pin "U2D1.U20"
				( objectStatus "@baseboard_fab2_lib.baseboard_fab2(sch_1):page74_i21:vss(990)" )
			)
			( pin "U2D1.U6"
				( objectStatus "@baseboard_fab2_lib.baseboard_fab2(sch_1):page74_i21:vss(991)" )
			)
			( pin "U2D1.U4"
				( objectStatus "@baseboard_fab2_lib.baseboard_fab2(sch_1):page74_i21:vss(992)" )
			)
			( pin "U2D1.U2"
				( objectStatus "@baseboard_fab2_lib.baseboard_fab2(sch_1):page74_i21:vss(993)" )
			)
			( pin "U2D1.T85"
				( objectStatus "@baseboard_fab2_lib.baseboard_fab2(sch_1):page74_i21:vss(994)" )
			)
			( pin "U2D1.T83"
				( objectStatus "@baseboard_fab2_lib.baseboard_fab2(sch_1):page74_i21:vss(995)" )
			)
			( pin "U2D1.T77"
				( objectStatus "@baseboard_fab2_lib.baseboard_fab2(sch_1):page74_i21:vss(996)" )
			)
			( pin "U2D1.T73"
				( objectStatus "@baseboard_fab2_lib.baseboard_fab2(sch_1):page74_i21:vss(997)" )
			)
			( pin "U2D1.T65"
				( objectStatus "@baseboard_fab2_lib.baseboard_fab2(sch_1):page74_i21:vss(998)" )
			)
			( pin "U2D1.T41"
				( objectStatus "@baseboard_fab2_lib.baseboard_fab2(sch_1):page74_i21:vss(999)" )
			)
			( pin "U2D1.T37"
				( objectStatus "@baseboard_fab2_lib.baseboard_fab2(sch_1):page74_i21:vss(1000)" )
			)
			( pin "U2D1.T35"
				( objectStatus "@baseboard_fab2_lib.baseboard_fab2(sch_1):page74_i21:vss(1001)" )
			)
			( pin "U2D1.T31"
				( objectStatus "@baseboard_fab2_lib.baseboard_fab2(sch_1):page74_i21:vss(1002)" )
			)
			( pin "U2D1.T29"
				( objectStatus "@baseboard_fab2_lib.baseboard_fab2(sch_1):page74_i21:vss(1003)" )
			)
			( pin "U2D1.T25"
				( objectStatus "@baseboard_fab2_lib.baseboard_fab2(sch_1):page74_i21:vss(1004)" )
			)
			( pin "U2D1.T17"
				( objectStatus "@baseboard_fab2_lib.baseboard_fab2(sch_1):page74_i21:vss(1005)" )
			)
			( pin "U2D1.T13"
				( objectStatus "@baseboard_fab2_lib.baseboard_fab2(sch_1):page74_i21:vss(1006)" )
			)
			( pin "U2D1.R86"
				( objectStatus "@baseboard_fab2_lib.baseboard_fab2(sch_1):page74_i21:vss(1007)" )
			)
			( pin "U2D1.R78"
				( objectStatus "@baseboard_fab2_lib.baseboard_fab2(sch_1):page74_i21:vss(1008)" )
			)
			( pin "U2D1.R72"
				( objectStatus "@baseboard_fab2_lib.baseboard_fab2(sch_1):page74_i21:vss(1009)" )
			)
			( pin "U2D1.R68"
				( objectStatus "@baseboard_fab2_lib.baseboard_fab2(sch_1):page74_i21:vss(1010)" )
			)
			( pin "U2D1.R40"
				( objectStatus "@baseboard_fab2_lib.baseboard_fab2(sch_1):page74_i21:vss(1011)" )
			)
			( pin "U2D1.R38"
				( objectStatus "@baseboard_fab2_lib.baseboard_fab2(sch_1):page74_i21:vss(1012)" )
			)
			( pin "U2D1.R34"
				( objectStatus "@baseboard_fab2_lib.baseboard_fab2(sch_1):page74_i21:vss(1013)" )
			)
			( pin "U2D1.R32"
				( objectStatus "@baseboard_fab2_lib.baseboard_fab2(sch_1):page74_i21:vss(1014)" )
			)
			( pin "U2D1.R28"
				( objectStatus "@baseboard_fab2_lib.baseboard_fab2(sch_1):page74_i21:vss(1015)" )
			)
			( pin "U2D1.R26"
				( objectStatus "@baseboard_fab2_lib.baseboard_fab2(sch_1):page74_i21:vss(1016)" )
			)
			( pin "U2D1.R22"
				( objectStatus "@baseboard_fab2_lib.baseboard_fab2(sch_1):page74_i21:vss(1017)" )
			)
			( pin "U2D1.R4"
				( objectStatus "@baseboard_fab2_lib.baseboard_fab2(sch_1):page74_i21:vss(1018)" )
			)
			( pin "U2D1.R2"
				( objectStatus "@baseboard_fab2_lib.baseboard_fab2(sch_1):page74_i21:vss(1019)" )
			)
			( pin "U2D1.R18"
				( objectStatus "@baseboard_fab2_lib.baseboard_fab2(sch_1):page74_i21:vss(1020)" )
			)
			( pin "U2D1.R14"
				( objectStatus "@baseboard_fab2_lib.baseboard_fab2(sch_1):page74_i21:vss(1021)" )
			)
			( pin "U2D1.P83"
				( objectStatus "@baseboard_fab2_lib.baseboard_fab2(sch_1):page74_i21:vss(1022)" )
			)
			( pin "U2D1.P81"
				( objectStatus "@baseboard_fab2_lib.baseboard_fab2(sch_1):page74_i21:vss(1023)" )
			)
			( pin "U2D1.P71"
				( objectStatus "@baseboard_fab2_lib.baseboard_fab2(sch_1):page74_i21:vss(1024)" )
			)
			( pin "U2D1.P69"
				( objectStatus "@baseboard_fab2_lib.baseboard_fab2(sch_1):page74_i21:vss(1025)" )
			)
			( pin "U2D1.P67"
				( objectStatus "@baseboard_fab2_lib.baseboard_fab2(sch_1):page74_i21:vss(1026)" )
			)
			( pin "U2D1.P39"
				( objectStatus "@baseboard_fab2_lib.baseboard_fab2(sch_1):page74_i21:vss(1027)" )
			)
			( pin "U2D1.P33"
				( objectStatus "@baseboard_fab2_lib.baseboard_fab2(sch_1):page74_i21:vss(1028)" )
			)
			( pin "U2D1.P27"
				( objectStatus "@baseboard_fab2_lib.baseboard_fab2(sch_1):page74_i21:vss(1029)" )
			)
			( pin "U2D1.P15"
				( objectStatus "@baseboard_fab2_lib.baseboard_fab2(sch_1):page74_i21:vss(1030)" )
			)
			( pin "U2D1.P11"
				( objectStatus "@baseboard_fab2_lib.baseboard_fab2(sch_1):page74_i21:vss(1031)" )
			)
			( pin "U2D1.N8"
				( objectStatus "@baseboard_fab2_lib.baseboard_fab2(sch_1):page74_i21:vss(1032)" )
			)
			( pin "U2D1.N4"
				( objectStatus "@baseboard_fab2_lib.baseboard_fab2(sch_1):page74_i21:vss(1033)" )
			)
			( pin "U2D1.N78"
				( objectStatus "@baseboard_fab2_lib.baseboard_fab2(sch_1):page74_i21:vss(1034)" )
			)
			( pin "U2D1.N76"
				( objectStatus "@baseboard_fab2_lib.baseboard_fab2(sch_1):page74_i21:vss(1035)" )
			)
			( pin "U2D1.N74"
				( objectStatus "@baseboard_fab2_lib.baseboard_fab2(sch_1):page74_i21:vss(1036)" )
			)
			( pin "U2D1.N72"
				( objectStatus "@baseboard_fab2_lib.baseboard_fab2(sch_1):page74_i21:vss(1037)" )
			)
			( pin "U2D1.N70"
				( objectStatus "@baseboard_fab2_lib.baseboard_fab2(sch_1):page74_i21:vss(1038)" )
			)
			( pin "U2D1.N66"
				( objectStatus "@baseboard_fab2_lib.baseboard_fab2(sch_1):page74_i21:vss(1039)" )
			)
			( pin "U2D1.N6"
				( objectStatus "@baseboard_fab2_lib.baseboard_fab2(sch_1):page74_i21:vss(1040)" )
			)
			( pin "U2D1.N22"
				( objectStatus "@baseboard_fab2_lib.baseboard_fab2(sch_1):page74_i21:vss(1041)" )
			)
			( pin "U2D1.N20"
				( objectStatus "@baseboard_fab2_lib.baseboard_fab2(sch_1):page74_i21:vss(1042)" )
			)
			( pin "U2D1.DM19"
				( objectStatus "@baseboard_fab2_lib.baseboard_fab2(sch_1):page74_i21:vss(1043)" )
			)
			( pin "U2D1.M85"
				( objectStatus "@baseboard_fab2_lib.baseboard_fab2(sch_1):page74_i21:vss(1044)" )
			)
			( pin "U2D1.M83"
				( objectStatus "@baseboard_fab2_lib.baseboard_fab2(sch_1):page74_i21:vss(1045)" )
			)
			( pin "U2D1.M79"
				( objectStatus "@baseboard_fab2_lib.baseboard_fab2(sch_1):page74_i21:vss(1046)" )
			)
			( pin "U2D1.M71"
				( objectStatus "@baseboard_fab2_lib.baseboard_fab2(sch_1):page74_i21:vss(1047)" )
			)
			( pin "U2D1.M65"
				( objectStatus "@baseboard_fab2_lib.baseboard_fab2(sch_1):page74_i21:vss(1048)" )
			)
			( pin "U2D1.M43"
				( objectStatus "@baseboard_fab2_lib.baseboard_fab2(sch_1):page74_i21:vss(1049)" )
			)
			( pin "U2D1.M41"
				( objectStatus "@baseboard_fab2_lib.baseboard_fab2(sch_1):page74_i21:vss(1050)" )
			)
			( pin "U2D1.M39"
				( objectStatus "@baseboard_fab2_lib.baseboard_fab2(sch_1):page74_i21:vss(1051)" )
			)
			( pin "U2D1.M37"
				( objectStatus "@baseboard_fab2_lib.baseboard_fab2(sch_1):page74_i21:vss(1052)" )
			)
			( pin "U2D1.M35"
				( objectStatus "@baseboard_fab2_lib.baseboard_fab2(sch_1):page74_i21:vss(1053)" )
			)
			( pin "U2D1.M33"
				( objectStatus "@baseboard_fab2_lib.baseboard_fab2(sch_1):page74_i21:vss(1054)" )
			)
			( pin "U2D1.M31"
				( objectStatus "@baseboard_fab2_lib.baseboard_fab2(sch_1):page74_i21:vss(1055)" )
			)
			( pin "U2D1.M29"
				( objectStatus "@baseboard_fab2_lib.baseboard_fab2(sch_1):page74_i21:vss(1056)" )
			)
			( pin "U2D1.M27"
				( objectStatus "@baseboard_fab2_lib.baseboard_fab2(sch_1):page74_i21:vss(1057)" )
			)
			( pin "U2D1.M25"
				( objectStatus "@baseboard_fab2_lib.baseboard_fab2(sch_1):page74_i21:vss(1058)" )
			)
			( pin "U2D1.M23"
				( objectStatus "@baseboard_fab2_lib.baseboard_fab2(sch_1):page74_i21:vss(1059)" )
			)
			( pin "U2D1.M19"
				( objectStatus "@baseboard_fab2_lib.baseboard_fab2(sch_1):page74_i21:vss(1060)" )
			)
			( pin "U2D1.M17"
				( objectStatus "@baseboard_fab2_lib.baseboard_fab2(sch_1):page74_i21:vss(1061)" )
			)
			( pin "U2D1.M15"
				( objectStatus "@baseboard_fab2_lib.baseboard_fab2(sch_1):page74_i21:vss(1062)" )
			)
			( pin "U2D1.CT7"
				( objectStatus "@baseboard_fab2_lib.baseboard_fab2(sch_1):page74_i21:vss(1063)" )
			)
			( pin "U2D1.BT9"
				( objectStatus "@baseboard_fab2_lib.baseboard_fab2(sch_1):page74_i21:vss(1064)" )
			)
			( pin "U2D1.L82"
				( objectStatus "@baseboard_fab2_lib.baseboard_fab2(sch_1):page74_i21:vss(1065)" )
			)
			( pin "U2D1.L80"
				( objectStatus "@baseboard_fab2_lib.baseboard_fab2(sch_1):page74_i21:vss(1066)" )
			)
			( pin "U2D1.L78"
				( objectStatus "@baseboard_fab2_lib.baseboard_fab2(sch_1):page74_i21:vss(1067)" )
			)
			( pin "U2D1.L72"
				( objectStatus "@baseboard_fab2_lib.baseboard_fab2(sch_1):page74_i21:vss(1068)" )
			)
			( pin "U2D1.L22"
				( objectStatus "@baseboard_fab2_lib.baseboard_fab2(sch_1):page74_i21:vss(1069)" )
			)
			( pin "U2D1.L20"
				( objectStatus "@baseboard_fab2_lib.baseboard_fab2(sch_1):page74_i21:vss(1070)" )
			)
			( pin "U2D1.L6"
				( objectStatus "@baseboard_fab2_lib.baseboard_fab2(sch_1):page74_i21:vss(1071)" )
			)
			( pin "U2D1.L2"
				( objectStatus "@baseboard_fab2_lib.baseboard_fab2(sch_1):page74_i21:vss(1072)" )
			)
			( pin "U2D1.L10"
				( objectStatus "@baseboard_fab2_lib.baseboard_fab2(sch_1):page74_i21:vss(1073)" )
			)
			( pin "U2D1.K85"
				( objectStatus "@baseboard_fab2_lib.baseboard_fab2(sch_1):page74_i21:vss(1074)" )
			)
			( pin "U2D1.K83"
				( objectStatus "@baseboard_fab2_lib.baseboard_fab2(sch_1):page74_i21:vss(1075)" )
			)
			( pin "U2D1.K81"
				( objectStatus "@baseboard_fab2_lib.baseboard_fab2(sch_1):page74_i21:vss(1076)" )
			)
			( pin "U2D1.K77"
				( objectStatus "@baseboard_fab2_lib.baseboard_fab2(sch_1):page74_i21:vss(1077)" )
			)
			( pin "U2D1.K73"
				( objectStatus "@baseboard_fab2_lib.baseboard_fab2(sch_1):page74_i21:vss(1078)" )
			)
			( pin "U2D1.K71"
				( objectStatus "@baseboard_fab2_lib.baseboard_fab2(sch_1):page74_i21:vss(1079)" )
			)
			( pin "U2D1.K69"
				( objectStatus "@baseboard_fab2_lib.baseboard_fab2(sch_1):page74_i21:vss(1080)" )
			)
			( pin "U2D1.K67"
				( objectStatus "@baseboard_fab2_lib.baseboard_fab2(sch_1):page74_i21:vss(1081)" )
			)
			( pin "U2D1.K65"
				( objectStatus "@baseboard_fab2_lib.baseboard_fab2(sch_1):page74_i21:vss(1082)" )
			)
			( pin "U2D1.K39"
				( objectStatus "@baseboard_fab2_lib.baseboard_fab2(sch_1):page74_i21:vss(1083)" )
			)
			( pin "U2D1.K33"
				( objectStatus "@baseboard_fab2_lib.baseboard_fab2(sch_1):page74_i21:vss(1084)" )
			)
			( pin "U2D1.K27"
				( objectStatus "@baseboard_fab2_lib.baseboard_fab2(sch_1):page74_i21:vss(1085)" )
			)
			( pin "U2D1.DB7"
				( objectStatus "@baseboard_fab2_lib.baseboard_fab2(sch_1):page74_i21:vss(1086)" )
			)
			( pin "U2D1.K17"
				( objectStatus "@baseboard_fab2_lib.baseboard_fab2(sch_1):page74_i21:vss(1087)" )
			)
			( pin "U2D1.K13"
				( objectStatus "@baseboard_fab2_lib.baseboard_fab2(sch_1):page74_i21:vss(1088)" )
			)
			( pin "U2D1.K11"
				( objectStatus "@baseboard_fab2_lib.baseboard_fab2(sch_1):page74_i21:vss(1089)" )
			)
			( pin "U2D1.K1"
				( objectStatus "@baseboard_fab2_lib.baseboard_fab2(sch_1):page74_i21:vss(1090)" )
			)
			( pin "U2D1.J84"
				( objectStatus "@baseboard_fab2_lib.baseboard_fab2(sch_1):page74_i21:vss(1091)" )
			)
			( pin "U2D1.J82"
				( objectStatus "@baseboard_fab2_lib.baseboard_fab2(sch_1):page74_i21:vss(1092)" )
			)
			( pin "U2D1.J76"
				( objectStatus "@baseboard_fab2_lib.baseboard_fab2(sch_1):page74_i21:vss(1093)" )
			)
			( pin "U2D1.AL68"
				( objectStatus "@baseboard_fab2_lib.baseboard_fab2(sch_1):page74_i22:vss(774)" )
			)
			( pin "U2D1.AL64"
				( objectStatus "@baseboard_fab2_lib.baseboard_fab2(sch_1):page74_i22:vss(775)" )
			)
			( pin "U2D1.AL56"
				( objectStatus "@baseboard_fab2_lib.baseboard_fab2(sch_1):page74_i22:vss(776)" )
			)
			( pin "U2D1.AL32"
				( objectStatus "@baseboard_fab2_lib.baseboard_fab2(sch_1):page74_i22:vss(777)" )
			)
			( pin "U2D1.AL30"
				( objectStatus "@baseboard_fab2_lib.baseboard_fab2(sch_1):page74_i22:vss(778)" )
			)
			( pin "U2D1.AL24"
				( objectStatus "@baseboard_fab2_lib.baseboard_fab2(sch_1):page74_i22:vss(779)" )
			)
			( pin "U2D1.AL10"
				( objectStatus "@baseboard_fab2_lib.baseboard_fab2(sch_1):page74_i22:vss(780)" )
			)
			( pin "U2D1.AL4"
				( objectStatus "@baseboard_fab2_lib.baseboard_fab2(sch_1):page74_i22:vss(781)" )
			)
			( pin "U2D1.AK85"
				( objectStatus "@baseboard_fab2_lib.baseboard_fab2(sch_1):page74_i22:vss(782)" )
			)
			( pin "U2D1.AK83"
				( objectStatus "@baseboard_fab2_lib.baseboard_fab2(sch_1):page74_i22:vss(783)" )
			)
			( pin "U2D1.AK81"
				( objectStatus "@baseboard_fab2_lib.baseboard_fab2(sch_1):page74_i22:vss(784)" )
			)
			( pin "U2D1.AK79"
				( objectStatus "@baseboard_fab2_lib.baseboard_fab2(sch_1):page74_i22:vss(785)" )
			)
			( pin "U2D1.AK73"
				( objectStatus "@baseboard_fab2_lib.baseboard_fab2(sch_1):page74_i22:vss(786)" )
			)
			( pin "U2D1.AK67"
				( objectStatus "@baseboard_fab2_lib.baseboard_fab2(sch_1):page74_i22:vss(787)" )
			)
			( pin "U2D1.AK65"
				( objectStatus "@baseboard_fab2_lib.baseboard_fab2(sch_1):page74_i22:vss(788)" )
			)
			( pin "U2D1.AK55"
				( objectStatus "@baseboard_fab2_lib.baseboard_fab2(sch_1):page74_i22:vss(789)" )
			)
			( pin "U2D1.AK33"
				( objectStatus "@baseboard_fab2_lib.baseboard_fab2(sch_1):page74_i22:vss(790)" )
			)
			( pin "U2D1.AK31"
				( objectStatus "@baseboard_fab2_lib.baseboard_fab2(sch_1):page74_i22:vss(791)" )
			)
			( pin "U2D1.AK29"
				( objectStatus "@baseboard_fab2_lib.baseboard_fab2(sch_1):page74_i22:vss(792)" )
			)
			( pin "U2D1.AK25"
				( objectStatus "@baseboard_fab2_lib.baseboard_fab2(sch_1):page74_i22:vss(793)" )
			)
			( pin "U2D1.AK23"
				( objectStatus "@baseboard_fab2_lib.baseboard_fab2(sch_1):page74_i22:vss(794)" )
			)
			( pin "U2D1.AK19"
				( objectStatus "@baseboard_fab2_lib.baseboard_fab2(sch_1):page74_i22:vss(795)" )
			)
			( pin "U2D1.AK13"
				( objectStatus "@baseboard_fab2_lib.baseboard_fab2(sch_1):page74_i22:vss(796)" )
			)
			( pin "U2D1.AK9"
				( objectStatus "@baseboard_fab2_lib.baseboard_fab2(sch_1):page74_i22:vss(797)" )
			)
			( pin "U2D1.AJ86"
				( objectStatus "@baseboard_fab2_lib.baseboard_fab2(sch_1):page74_i22:vss(798)" )
			)
			( pin "U2D1.AJ82"
				( objectStatus "@baseboard_fab2_lib.baseboard_fab2(sch_1):page74_i22:vss(799)" )
			)
			( pin "U2D1.AJ78"
				( objectStatus "@baseboard_fab2_lib.baseboard_fab2(sch_1):page74_i22:vss(800)" )
			)
			( pin "U2D1.AJ74"
				( objectStatus "@baseboard_fab2_lib.baseboard_fab2(sch_1):page74_i22:vss(801)" )
			)
			( pin "U2D1.AJ68"
				( objectStatus "@baseboard_fab2_lib.baseboard_fab2(sch_1):page74_i22:vss(802)" )
			)
			( pin "U2D1.AJ66"
				( objectStatus "@baseboard_fab2_lib.baseboard_fab2(sch_1):page74_i22:vss(803)" )
			)
			( pin "U2D1.AJ54"
				( objectStatus "@baseboard_fab2_lib.baseboard_fab2(sch_1):page74_i22:vss(804)" )
			)
			( pin "U2D1.AJ52"
				( objectStatus "@baseboard_fab2_lib.baseboard_fab2(sch_1):page74_i22:vss(805)" )
			)
			( pin "U2D1.AJ50"
				( objectStatus "@baseboard_fab2_lib.baseboard_fab2(sch_1):page74_i22:vss(806)" )
			)
			( pin "U2D1.AJ48"
				( objectStatus "@baseboard_fab2_lib.baseboard_fab2(sch_1):page74_i22:vss(807)" )
			)
			( pin "U2D1.AJ46"
				( objectStatus "@baseboard_fab2_lib.baseboard_fab2(sch_1):page74_i22:vss(808)" )
			)
			( pin "U2D1.AJ34"
				( objectStatus "@baseboard_fab2_lib.baseboard_fab2(sch_1):page74_i22:vss(809)" )
			)
			( pin "U2D1.AJ32"
				( objectStatus "@baseboard_fab2_lib.baseboard_fab2(sch_1):page74_i22:vss(810)" )
			)
			( pin "U2D1.AJ28"
				( objectStatus "@baseboard_fab2_lib.baseboard_fab2(sch_1):page74_i22:vss(811)" )
			)
			( pin "U2D1.AJ26"
				( objectStatus "@baseboard_fab2_lib.baseboard_fab2(sch_1):page74_i22:vss(812)" )
			)
			( pin "U2D1.AJ22"
				( objectStatus "@baseboard_fab2_lib.baseboard_fab2(sch_1):page74_i22:vss(813)" )
			)
			( pin "U2D1.AJ8"
				( objectStatus "@baseboard_fab2_lib.baseboard_fab2(sch_1):page74_i22:vss(814)" )
			)
			( pin "U2D1.AH83"
				( objectStatus "@baseboard_fab2_lib.baseboard_fab2(sch_1):page74_i22:vss(815)" )
			)
			( pin "U2D1.AH77"
				( objectStatus "@baseboard_fab2_lib.baseboard_fab2(sch_1):page74_i22:vss(816)" )
			)
			( pin "U2D1.AH75"
				( objectStatus "@baseboard_fab2_lib.baseboard_fab2(sch_1):page74_i22:vss(817)" )
			)
			( pin "U2D1.AH69"
				( objectStatus "@baseboard_fab2_lib.baseboard_fab2(sch_1):page74_i22:vss(818)" )
			)
			( pin "U2D1.AH65"
				( objectStatus "@baseboard_fab2_lib.baseboard_fab2(sch_1):page74_i22:vss(819)" )
			)
			( pin "U2D1.AH61"
				( objectStatus "@baseboard_fab2_lib.baseboard_fab2(sch_1):page74_i22:vss(820)" )
			)
			( pin "U2D1.AH59"
				( objectStatus "@baseboard_fab2_lib.baseboard_fab2(sch_1):page74_i22:vss(821)" )
			)
			( pin "U2D1.AH53"
				( objectStatus "@baseboard_fab2_lib.baseboard_fab2(sch_1):page74_i22:vss(822)" )
			)
			( pin "U2D1.AH51"
				( objectStatus "@baseboard_fab2_lib.baseboard_fab2(sch_1):page74_i22:vss(823)" )
			)
			( pin "U2D1.AH49"
				( objectStatus "@baseboard_fab2_lib.baseboard_fab2(sch_1):page74_i22:vss(824)" )
			)
			( pin "U2D1.AH47"
				( objectStatus "@baseboard_fab2_lib.baseboard_fab2(sch_1):page74_i22:vss(825)" )
			)
			( pin "U2D1.AH45"
				( objectStatus "@baseboard_fab2_lib.baseboard_fab2(sch_1):page74_i22:vss(826)" )
			)
			( pin "U2D1.AH35"
				( objectStatus "@baseboard_fab2_lib.baseboard_fab2(sch_1):page74_i22:vss(827)" )
			)
			( pin "U2D1.AH33"
				( objectStatus "@baseboard_fab2_lib.baseboard_fab2(sch_1):page74_i22:vss(828)" )
			)
			( pin "U2D1.AH27"
				( objectStatus "@baseboard_fab2_lib.baseboard_fab2(sch_1):page74_i22:vss(829)" )
			)
			( pin "U2D1.AH21"
				( objectStatus "@baseboard_fab2_lib.baseboard_fab2(sch_1):page74_i22:vss(830)" )
			)
			( pin "U2D1.AH5"
				( objectStatus "@baseboard_fab2_lib.baseboard_fab2(sch_1):page74_i22:vss(831)" )
			)
			( pin "U2D1.AH1"
				( objectStatus "@baseboard_fab2_lib.baseboard_fab2(sch_1):page74_i22:vss(832)" )
			)
			( pin "U2D1.AG80"
				( objectStatus "@baseboard_fab2_lib.baseboard_fab2(sch_1):page74_i22:vss(833)" )
			)
			( pin "U2D1.AG78"
				( objectStatus "@baseboard_fab2_lib.baseboard_fab2(sch_1):page74_i22:vss(834)" )
			)
			( pin "U2D1.AG76"
				( objectStatus "@baseboard_fab2_lib.baseboard_fab2(sch_1):page74_i22:vss(835)" )
			)
			( pin "U2D1.AG74"
				( objectStatus "@baseboard_fab2_lib.baseboard_fab2(sch_1):page74_i22:vss(836)" )
			)
			( pin "U2D1.AG70"
				( objectStatus "@baseboard_fab2_lib.baseboard_fab2(sch_1):page74_i22:vss(837)" )
			)
			( pin "U2D1.AG64"
				( objectStatus "@baseboard_fab2_lib.baseboard_fab2(sch_1):page74_i22:vss(838)" )
			)
			( pin "U2D1.AG36"
				( objectStatus "@baseboard_fab2_lib.baseboard_fab2(sch_1):page74_i22:vss(839)" )
			)
			( pin "U2D1.AG18"
				( objectStatus "@baseboard_fab2_lib.baseboard_fab2(sch_1):page74_i22:vss(840)" )
			)
			( pin "U2D1.AG14"
				( objectStatus "@baseboard_fab2_lib.baseboard_fab2(sch_1):page74_i22:vss(841)" )
			)
			( pin "U2D1.AG12"
				( objectStatus "@baseboard_fab2_lib.baseboard_fab2(sch_1):page74_i22:vss(842)" )
			)
			( pin "U2D1.AF85"
				( objectStatus "@baseboard_fab2_lib.baseboard_fab2(sch_1):page74_i22:vss(843)" )
			)
			( pin "U2D1.AF83"
				( objectStatus "@baseboard_fab2_lib.baseboard_fab2(sch_1):page74_i22:vss(844)" )
			)
			( pin "U2D1.AF77"
				( objectStatus "@baseboard_fab2_lib.baseboard_fab2(sch_1):page74_i22:vss(845)" )
			)
			( pin "U2D1.AF73"
				( objectStatus "@baseboard_fab2_lib.baseboard_fab2(sch_1):page74_i22:vss(846)" )
			)
			( pin "U2D1.AF41"
				( objectStatus "@baseboard_fab2_lib.baseboard_fab2(sch_1):page74_i22:vss(847)" )
			)
			( pin "U2D1.AF39"
				( objectStatus "@baseboard_fab2_lib.baseboard_fab2(sch_1):page74_i22:vss(848)" )
			)
			( pin "U2D1.AF37"
				( objectStatus "@baseboard_fab2_lib.baseboard_fab2(sch_1):page74_i22:vss(849)" )
			)
			( pin "U2D1.AF33"
				( objectStatus "@baseboard_fab2_lib.baseboard_fab2(sch_1):page74_i22:vss(850)" )
			)
			( pin "U2D1.AF31"
				( objectStatus "@baseboard_fab2_lib.baseboard_fab2(sch_1):page74_i22:vss(851)" )
			)
			( pin "U2D1.AF29"
				( objectStatus "@baseboard_fab2_lib.baseboard_fab2(sch_1):page74_i22:vss(852)" )
			)
			( pin "U2D1.AF27"
				( objectStatus "@baseboard_fab2_lib.baseboard_fab2(sch_1):page74_i22:vss(853)" )
			)
			( pin "U2D1.AF25"
				( objectStatus "@baseboard_fab2_lib.baseboard_fab2(sch_1):page74_i22:vss(854)" )
			)
			( pin "U2D1.AF23"
				( objectStatus "@baseboard_fab2_lib.baseboard_fab2(sch_1):page74_i22:vss(855)" )
			)
			( pin "U2D1.AF21"
				( objectStatus "@baseboard_fab2_lib.baseboard_fab2(sch_1):page74_i22:vss(856)" )
			)
			( pin "U2D1.AF9"
				( objectStatus "@baseboard_fab2_lib.baseboard_fab2(sch_1):page74_i22:vss(857)" )
			)
			( pin "U2D1.AC52"
				( objectStatus "@baseboard_fab2_lib.baseboard_fab2(sch_1):page74_i22:vss(858)" )
			)
			( pin "U2D1.AF1"
				( objectStatus "@baseboard_fab2_lib.baseboard_fab2(sch_1):page74_i22:vss(859)" )
			)
			( pin "U2D1.AE78"
				( objectStatus "@baseboard_fab2_lib.baseboard_fab2(sch_1):page74_i22:vss(860)" )
			)
			( pin "U2D1.AE70"
				( objectStatus "@baseboard_fab2_lib.baseboard_fab2(sch_1):page74_i22:vss(861)" )
			)
			( pin "U2D1.AE68"
				( objectStatus "@baseboard_fab2_lib.baseboard_fab2(sch_1):page74_i22:vss(862)" )
			)
			( pin "U2D1.AE66"
				( objectStatus "@baseboard_fab2_lib.baseboard_fab2(sch_1):page74_i22:vss(863)" )
			)
			( pin "U2D1.AE64"
				( objectStatus "@baseboard_fab2_lib.baseboard_fab2(sch_1):page74_i22:vss(864)" )
			)
			( pin "U2D1.AE42"
				( objectStatus "@baseboard_fab2_lib.baseboard_fab2(sch_1):page74_i22:vss(865)" )
			)
			( pin "U2D1.AE40"
				( objectStatus "@baseboard_fab2_lib.baseboard_fab2(sch_1):page74_i22:vss(866)" )
			)
			( pin "U2D1.AE38"
				( objectStatus "@baseboard_fab2_lib.baseboard_fab2(sch_1):page74_i22:vss(867)" )
			)
			( pin "U2D1.AE16"
				( objectStatus "@baseboard_fab2_lib.baseboard_fab2(sch_1):page74_i22:vss(868)" )
			)
			( pin "U2D1.AC54"
				( objectStatus "@baseboard_fab2_lib.baseboard_fab2(sch_1):page74_i22:vss(869)" )
			)
			( pin "U2D1.AE8"
				( objectStatus "@baseboard_fab2_lib.baseboard_fab2(sch_1):page74_i22:vss(870)" )
			)
			( pin "U2D1.AE4"
				( objectStatus "@baseboard_fab2_lib.baseboard_fab2(sch_1):page74_i22:vss(871)" )
			)
			( pin "U2D1.AD85"
				( objectStatus "@baseboard_fab2_lib.baseboard_fab2(sch_1):page74_i22:vss(872)" )
			)
			( pin "U2D1.AD83"
				( objectStatus "@baseboard_fab2_lib.baseboard_fab2(sch_1):page74_i22:vss(873)" )
			)
			( pin "U2D1.AD81"
				( objectStatus "@baseboard_fab2_lib.baseboard_fab2(sch_1):page74_i22:vss(874)" )
			)
			( pin "U2D1.AD75"
				( objectStatus "@baseboard_fab2_lib.baseboard_fab2(sch_1):page74_i22:vss(875)" )
			)
			( pin "U2D1.AD73"
				( objectStatus "@baseboard_fab2_lib.baseboard_fab2(sch_1):page74_i22:vss(876)" )
			)
			( pin "U2D1.AD71"
				( objectStatus "@baseboard_fab2_lib.baseboard_fab2(sch_1):page74_i22:vss(877)" )
			)
			( pin "U2D1.AD43"
				( objectStatus "@baseboard_fab2_lib.baseboard_fab2(sch_1):page74_i22:vss(878)" )
			)
			( pin "U2D1.AD39"
				( objectStatus "@baseboard_fab2_lib.baseboard_fab2(sch_1):page74_i22:vss(879)" )
			)
			( pin "U2D1.AD33"
				( objectStatus "@baseboard_fab2_lib.baseboard_fab2(sch_1):page74_i22:vss(880)" )
			)
			( pin "U2D1.AD27"
				( objectStatus "@baseboard_fab2_lib.baseboard_fab2(sch_1):page74_i22:vss(881)" )
			)
			( pin "U2D1.AD21"
				( objectStatus "@baseboard_fab2_lib.baseboard_fab2(sch_1):page74_i22:vss(882)" )
			)
			( pin "U2D1.AD19"
				( objectStatus "@baseboard_fab2_lib.baseboard_fab2(sch_1):page74_i22:vss(883)" )
			)
			( pin "U2D1.AD15"
				( objectStatus "@baseboard_fab2_lib.baseboard_fab2(sch_1):page74_i22:vss(884)" )
			)
			( pin "U2D1.AD13"
				( objectStatus "@baseboard_fab2_lib.baseboard_fab2(sch_1):page74_i22:vss(885)" )
			)
			( pin "U2D1.AD11"
				( objectStatus "@baseboard_fab2_lib.baseboard_fab2(sch_1):page74_i22:vss(886)" )
			)
			( pin "U2D1.AD9"
				( objectStatus "@baseboard_fab2_lib.baseboard_fab2(sch_1):page74_i22:vss(887)" )
			)
			( pin "U2D1.AD7"
				( objectStatus "@baseboard_fab2_lib.baseboard_fab2(sch_1):page74_i22:vss(888)" )
			)
			( pin "U2D1.AD3"
				( objectStatus "@baseboard_fab2_lib.baseboard_fab2(sch_1):page74_i22:vss(889)" )
			)
			( pin "U2D1.AC86"
				( objectStatus "@baseboard_fab2_lib.baseboard_fab2(sch_1):page74_i22:vss(890)" )
			)
			( pin "U2D1.AC84"
				( objectStatus "@baseboard_fab2_lib.baseboard_fab2(sch_1):page74_i22:vss(891)" )
			)
			( pin "U2D1.AC78"
				( objectStatus "@baseboard_fab2_lib.baseboard_fab2(sch_1):page74_i22:vss(892)" )
			)
			( pin "U2D1.AC72"
				( objectStatus "@baseboard_fab2_lib.baseboard_fab2(sch_1):page74_i22:vss(893)" )
			)
			( pin "U2D1.AC70"
				( objectStatus "@baseboard_fab2_lib.baseboard_fab2(sch_1):page74_i22:vss(894)" )
			)
			( pin "U2D1.AC64"
				( objectStatus "@baseboard_fab2_lib.baseboard_fab2(sch_1):page74_i22:vss(895)" )
			)
			( pin "U2D1.AC40"
				( objectStatus "@baseboard_fab2_lib.baseboard_fab2(sch_1):page74_i22:vss(896)" )
			)
			( pin "U2D1.AC38"
				( objectStatus "@baseboard_fab2_lib.baseboard_fab2(sch_1):page74_i22:vss(897)" )
			)
			( pin "U2D1.AC34"
				( objectStatus "@baseboard_fab2_lib.baseboard_fab2(sch_1):page74_i22:vss(898)" )
			)
			( pin "U2D1.AC32"
				( objectStatus "@baseboard_fab2_lib.baseboard_fab2(sch_1):page74_i22:vss(899)" )
			)
			( pin "U2D1.AC28"
				( objectStatus "@baseboard_fab2_lib.baseboard_fab2(sch_1):page74_i22:vss(900)" )
			)
			( pin "U2D1.AC26"
				( objectStatus "@baseboard_fab2_lib.baseboard_fab2(sch_1):page74_i22:vss(901)" )
			)
			( pin "U2D1.AC22"
				( objectStatus "@baseboard_fab2_lib.baseboard_fab2(sch_1):page74_i22:vss(902)" )
			)
			( pin "U2D1.AC18"
				( objectStatus "@baseboard_fab2_lib.baseboard_fab2(sch_1):page74_i22:vss(903)" )
			)
			( pin "U2D1.AB85"
				( objectStatus "@baseboard_fab2_lib.baseboard_fab2(sch_1):page74_i22:vss(904)" )
			)
			( pin "U2D1.AB83"
				( objectStatus "@baseboard_fab2_lib.baseboard_fab2(sch_1):page74_i22:vss(905)" )
			)
			( pin "U2D1.AB79"
				( objectStatus "@baseboard_fab2_lib.baseboard_fab2(sch_1):page74_i22:vss(906)" )
			)
			( pin "U2D1.AB73"
				( objectStatus "@baseboard_fab2_lib.baseboard_fab2(sch_1):page74_i22:vss(907)" )
			)
			( pin "U2D1.AB69"
				( objectStatus "@baseboard_fab2_lib.baseboard_fab2(sch_1):page74_i22:vss(908)" )
			)
			( pin "U2D1.AB65"
				( objectStatus "@baseboard_fab2_lib.baseboard_fab2(sch_1):page74_i22:vss(909)" )
			)
			( pin "U2D1.AB41"
				( objectStatus "@baseboard_fab2_lib.baseboard_fab2(sch_1):page74_i22:vss(910)" )
			)
			( pin "U2D1.AB37"
				( objectStatus "@baseboard_fab2_lib.baseboard_fab2(sch_1):page74_i22:vss(911)" )
			)
			( pin "U2D1.AB35"
				( objectStatus "@baseboard_fab2_lib.baseboard_fab2(sch_1):page74_i22:vss(912)" )
			)
			( pin "U2D1.AB31"
				( objectStatus "@baseboard_fab2_lib.baseboard_fab2(sch_1):page74_i22:vss(913)" )
			)
			( pin "U2D1.AB29"
				( objectStatus "@baseboard_fab2_lib.baseboard_fab2(sch_1):page74_i22:vss(914)" )
			)
			( pin "U2D1.AB25"
				( objectStatus "@baseboard_fab2_lib.baseboard_fab2(sch_1):page74_i22:vss(915)" )
			)
			( pin "U2D1.AB23"
				( objectStatus "@baseboard_fab2_lib.baseboard_fab2(sch_1):page74_i22:vss(916)" )
			)
			( pin "U2D1.AB21"
				( objectStatus "@baseboard_fab2_lib.baseboard_fab2(sch_1):page74_i22:vss(917)" )
			)
			( pin "U2D1.AB11"
				( objectStatus "@baseboard_fab2_lib.baseboard_fab2(sch_1):page74_i22:vss(918)" )
			)
			( pin "U2D1.AB5"
				( objectStatus "@baseboard_fab2_lib.baseboard_fab2(sch_1):page74_i22:vss(919)" )
			)
			( pin "U2D1.AB1"
				( objectStatus "@baseboard_fab2_lib.baseboard_fab2(sch_1):page74_i22:vss(920)" )
			)
			( pin "U2D1.AA82"
				( objectStatus "@baseboard_fab2_lib.baseboard_fab2(sch_1):page74_i22:vss(921)" )
			)
			( pin "U2D1.AA80"
				( objectStatus "@baseboard_fab2_lib.baseboard_fab2(sch_1):page74_i22:vss(922)" )
			)
			( pin "U2D1.AA78"
				( objectStatus "@baseboard_fab2_lib.baseboard_fab2(sch_1):page74_i22:vss(923)" )
			)
			( pin "U2D1.AA76"
				( objectStatus "@baseboard_fab2_lib.baseboard_fab2(sch_1):page74_i22:vss(924)" )
			)
			( pin "U2D1.AA68"
				( objectStatus "@baseboard_fab2_lib.baseboard_fab2(sch_1):page74_i22:vss(925)" )
			)
			( pin "U2D1.AA66"
				( objectStatus "@baseboard_fab2_lib.baseboard_fab2(sch_1):page74_i22:vss(926)" )
			)
			( pin "U2D1.AA64"
				( objectStatus "@baseboard_fab2_lib.baseboard_fab2(sch_1):page74_i22:vss(927)" )
			)
			( pin "U2D1.AA42"
				( objectStatus "@baseboard_fab2_lib.baseboard_fab2(sch_1):page74_i22:vss(928)" )
			)
			( pin "U2D1.AA36"
				( objectStatus "@baseboard_fab2_lib.baseboard_fab2(sch_1):page74_i22:vss(929)" )
			)
			( pin "U2D1.AA30"
				( objectStatus "@baseboard_fab2_lib.baseboard_fab2(sch_1):page74_i22:vss(930)" )
			)
			( pin "U2D1.AA24"
				( objectStatus "@baseboard_fab2_lib.baseboard_fab2(sch_1):page74_i22:vss(931)" )
			)
			( pin "U2D1.AA22"
				( objectStatus "@baseboard_fab2_lib.baseboard_fab2(sch_1):page74_i22:vss(932)" )
			)
			( pin "U2D1.AA18"
				( objectStatus "@baseboard_fab2_lib.baseboard_fab2(sch_1):page74_i22:vss(933)" )
			)
			( pin "U2D1.BG72"
				( objectStatus "@baseboard_fab2_lib.baseboard_fab2(sch_1):page74_i23:vss(614)" )
			)
			( pin "U2D1.BG24"
				( objectStatus "@baseboard_fab2_lib.baseboard_fab2(sch_1):page74_i23:vss(615)" )
			)
			( pin "U2D1.BG22"
				( objectStatus "@baseboard_fab2_lib.baseboard_fab2(sch_1):page74_i23:vss(616)" )
			)
			( pin "U2D1.BG10"
				( objectStatus "@baseboard_fab2_lib.baseboard_fab2(sch_1):page74_i23:vss(617)" )
			)
			( pin "U2D1.BG8"
				( objectStatus "@baseboard_fab2_lib.baseboard_fab2(sch_1):page74_i23:vss(618)" )
			)
			( pin "U2D1.BG6"
				( objectStatus "@baseboard_fab2_lib.baseboard_fab2(sch_1):page74_i23:vss(619)" )
			)
			( pin "U2D1.BF71"
				( objectStatus "@baseboard_fab2_lib.baseboard_fab2(sch_1):page74_i23:vss(620)" )
			)
			( pin "U2D1.BF69"
				( objectStatus "@baseboard_fab2_lib.baseboard_fab2(sch_1):page74_i23:vss(621)" )
			)
			( pin "U2D1.BF67"
				( objectStatus "@baseboard_fab2_lib.baseboard_fab2(sch_1):page74_i23:vss(622)" )
			)
			( pin "U2D1.BF65"
				( objectStatus "@baseboard_fab2_lib.baseboard_fab2(sch_1):page74_i23:vss(623)" )
			)
			( pin "U2D1.BF63"
				( objectStatus "@baseboard_fab2_lib.baseboard_fab2(sch_1):page74_i23:vss(624)" )
			)
			( pin "U2D1.BF25"
				( objectStatus "@baseboard_fab2_lib.baseboard_fab2(sch_1):page74_i23:vss(625)" )
			)
			( pin "U2D1.BF19"
				( objectStatus "@baseboard_fab2_lib.baseboard_fab2(sch_1):page74_i23:vss(626)" )
			)
			( pin "U2D1.BF17"
				( objectStatus "@baseboard_fab2_lib.baseboard_fab2(sch_1):page74_i23:vss(627)" )
			)
			( pin "U2D1.BF15"
				( objectStatus "@baseboard_fab2_lib.baseboard_fab2(sch_1):page74_i23:vss(628)" )
			)
			( pin "U2D1.BF9"
				( objectStatus "@baseboard_fab2_lib.baseboard_fab2(sch_1):page74_i23:vss(629)" )
			)
			( pin "U2D1.BE70"
				( objectStatus "@baseboard_fab2_lib.baseboard_fab2(sch_1):page74_i23:vss(630)" )
			)
			( pin "U2D1.BE68"
				( objectStatus "@baseboard_fab2_lib.baseboard_fab2(sch_1):page74_i23:vss(631)" )
			)
			( pin "U2D1.BE66"
				( objectStatus "@baseboard_fab2_lib.baseboard_fab2(sch_1):page74_i23:vss(632)" )
			)
			( pin "U2D1.BE64"
				( objectStatus "@baseboard_fab2_lib.baseboard_fab2(sch_1):page74_i23:vss(633)" )
			)
			( pin "U2D1.BE26"
				( objectStatus "@baseboard_fab2_lib.baseboard_fab2(sch_1):page74_i23:vss(634)" )
			)
			( pin "U2D1.BE10"
				( objectStatus "@baseboard_fab2_lib.baseboard_fab2(sch_1):page74_i23:vss(635)" )
			)
			( pin "U2D1.BE8"
				( objectStatus "@baseboard_fab2_lib.baseboard_fab2(sch_1):page74_i23:vss(636)" )
			)
			( pin "U2D1.BE6"
				( objectStatus "@baseboard_fab2_lib.baseboard_fab2(sch_1):page74_i23:vss(637)" )
			)
			( pin "U2D1.BE4"
				( objectStatus "@baseboard_fab2_lib.baseboard_fab2(sch_1):page74_i23:vss(638)" )
			)
			( pin "U2D1.BD71"
				( objectStatus "@baseboard_fab2_lib.baseboard_fab2(sch_1):page74_i23:vss(639)" )
			)
			( pin "U2D1.BD63"
				( objectStatus "@baseboard_fab2_lib.baseboard_fab2(sch_1):page74_i23:vss(640)" )
			)
			( pin "U2D1.BD27"
				( objectStatus "@baseboard_fab2_lib.baseboard_fab2(sch_1):page74_i23:vss(641)" )
			)
			( pin "U2D1.BD21"
				( objectStatus "@baseboard_fab2_lib.baseboard_fab2(sch_1):page74_i23:vss(642)" )
			)
			( pin "U2D1.BD15"
				( objectStatus "@baseboard_fab2_lib.baseboard_fab2(sch_1):page74_i23:vss(643)" )
			)
			( pin "U2D1.BD11"
				( objectStatus "@baseboard_fab2_lib.baseboard_fab2(sch_1):page74_i23:vss(644)" )
			)
			( pin "U2D1.BD5"
				( objectStatus "@baseboard_fab2_lib.baseboard_fab2(sch_1):page74_i23:vss(645)" )
			)
			( pin "U2D1.BC82"
				( objectStatus "@baseboard_fab2_lib.baseboard_fab2(sch_1):page74_i23:vss(646)" )
			)
			( pin "U2D1.BC80"
				( objectStatus "@baseboard_fab2_lib.baseboard_fab2(sch_1):page74_i23:vss(647)" )
			)
			( pin "U2D1.BC78"
				( objectStatus "@baseboard_fab2_lib.baseboard_fab2(sch_1):page74_i23:vss(648)" )
			)
			( pin "U2D1.BC76"
				( objectStatus "@baseboard_fab2_lib.baseboard_fab2(sch_1):page74_i23:vss(649)" )
			)
			( pin "U2D1.BC74"
				( objectStatus "@baseboard_fab2_lib.baseboard_fab2(sch_1):page74_i23:vss(650)" )
			)
			( pin "U2D1.BC72"
				( objectStatus "@baseboard_fab2_lib.baseboard_fab2(sch_1):page74_i23:vss(651)" )
			)
			( pin "U2D1.BC70"
				( objectStatus "@baseboard_fab2_lib.baseboard_fab2(sch_1):page74_i23:vss(652)" )
			)
			( pin "U2D1.BC16"
				( objectStatus "@baseboard_fab2_lib.baseboard_fab2(sch_1):page74_i23:vss(653)" )
			)
			( pin "U2D1.BC12"
				( objectStatus "@baseboard_fab2_lib.baseboard_fab2(sch_1):page74_i23:vss(654)" )
			)
			( pin "U2D1.BC8"
				( objectStatus "@baseboard_fab2_lib.baseboard_fab2(sch_1):page74_i23:vss(655)" )
			)
			( pin "U2D1.BC4"
				( objectStatus "@baseboard_fab2_lib.baseboard_fab2(sch_1):page74_i23:vss(656)" )
			)
			( pin "U2D1.BB83"
				( objectStatus "@baseboard_fab2_lib.baseboard_fab2(sch_1):page74_i23:vss(657)" )
			)
			( pin "U2D1.BB81"
				( objectStatus "@baseboard_fab2_lib.baseboard_fab2(sch_1):page74_i23:vss(658)" )
			)
			( pin "U2D1.BB79"
				( objectStatus "@baseboard_fab2_lib.baseboard_fab2(sch_1):page74_i23:vss(659)" )
			)
			( pin "U2D1.BB77"
				( objectStatus "@baseboard_fab2_lib.baseboard_fab2(sch_1):page74_i23:vss(660)" )
			)
			( pin "U2D1.BB75"
				( objectStatus "@baseboard_fab2_lib.baseboard_fab2(sch_1):page74_i23:vss(661)" )
			)
			( pin "U2D1.BB73"
				( objectStatus "@baseboard_fab2_lib.baseboard_fab2(sch_1):page74_i23:vss(662)" )
			)
			( pin "U2D1.BB69"
				( objectStatus "@baseboard_fab2_lib.baseboard_fab2(sch_1):page74_i23:vss(663)" )
			)
			( pin "U2D1.BB63"
				( objectStatus "@baseboard_fab2_lib.baseboard_fab2(sch_1):page74_i23:vss(664)" )
			)
			( pin "U2D1.BB23"
				( objectStatus "@baseboard_fab2_lib.baseboard_fab2(sch_1):page74_i23:vss(665)" )
			)
			( pin "U2D1.BB19"
				( objectStatus "@baseboard_fab2_lib.baseboard_fab2(sch_1):page74_i23:vss(666)" )
			)
			( pin "U2D1.BA84"
				( objectStatus "@baseboard_fab2_lib.baseboard_fab2(sch_1):page74_i23:vss(667)" )
			)
			( pin "U2D1.BA80"
				( objectStatus "@baseboard_fab2_lib.baseboard_fab2(sch_1):page74_i23:vss(668)" )
			)
			( pin "U2D1.BA74"
				( objectStatus "@baseboard_fab2_lib.baseboard_fab2(sch_1):page74_i23:vss(669)" )
			)
			( pin "U2D1.BA68"
				( objectStatus "@baseboard_fab2_lib.baseboard_fab2(sch_1):page74_i23:vss(670)" )
			)
			( pin "U2D1.BA62"
				( objectStatus "@baseboard_fab2_lib.baseboard_fab2(sch_1):page74_i23:vss(671)" )
			)
			( pin "U2D1.BA12"
				( objectStatus "@baseboard_fab2_lib.baseboard_fab2(sch_1):page74_i23:vss(672)" )
			)
			( pin "U2D1.BA6"
				( objectStatus "@baseboard_fab2_lib.baseboard_fab2(sch_1):page74_i23:vss(673)" )
			)
			( pin "U2D1.BA2"
				( objectStatus "@baseboard_fab2_lib.baseboard_fab2(sch_1):page74_i23:vss(674)" )
			)
			( pin "U2D1.AY81"
				( objectStatus "@baseboard_fab2_lib.baseboard_fab2(sch_1):page74_i23:vss(675)" )
			)
			( pin "U2D1.AY79"
				( objectStatus "@baseboard_fab2_lib.baseboard_fab2(sch_1):page74_i23:vss(676)" )
			)
			( pin "U2D1.AY63"
				( objectStatus "@baseboard_fab2_lib.baseboard_fab2(sch_1):page74_i23:vss(677)" )
			)
			( pin "U2D1.AY25"
				( objectStatus "@baseboard_fab2_lib.baseboard_fab2(sch_1):page74_i23:vss(678)" )
			)
			( pin "U2D1.AY23"
				( objectStatus "@baseboard_fab2_lib.baseboard_fab2(sch_1):page74_i23:vss(679)" )
			)
			( pin "U2D1.AY21"
				( objectStatus "@baseboard_fab2_lib.baseboard_fab2(sch_1):page74_i23:vss(680)" )
			)
			( pin "U2D1.AY17"
				( objectStatus "@baseboard_fab2_lib.baseboard_fab2(sch_1):page74_i23:vss(681)" )
			)
			( pin "U2D1.AY15"
				( objectStatus "@baseboard_fab2_lib.baseboard_fab2(sch_1):page74_i23:vss(682)" )
			)
			( pin "U2D1.AY5"
				( objectStatus "@baseboard_fab2_lib.baseboard_fab2(sch_1):page74_i23:vss(683)" )
			)
			( pin "U2D1.AW84"
				( objectStatus "@baseboard_fab2_lib.baseboard_fab2(sch_1):page74_i23:vss(684)" )
			)
			( pin "U2D1.AW82"
				( objectStatus "@baseboard_fab2_lib.baseboard_fab2(sch_1):page74_i23:vss(685)" )
			)
			( pin "U2D1.AW78"
				( objectStatus "@baseboard_fab2_lib.baseboard_fab2(sch_1):page74_i23:vss(686)" )
			)
			( pin "U2D1.AW74"
				( objectStatus "@baseboard_fab2_lib.baseboard_fab2(sch_1):page74_i23:vss(687)" )
			)
			( pin "U2D1.AW72"
				( objectStatus "@baseboard_fab2_lib.baseboard_fab2(sch_1):page74_i23:vss(688)" )
			)
			( pin "U2D1.AW70"
				( objectStatus "@baseboard_fab2_lib.baseboard_fab2(sch_1):page74_i23:vss(689)" )
			)
			( pin "U2D1.AW68"
				( objectStatus "@baseboard_fab2_lib.baseboard_fab2(sch_1):page74_i23:vss(690)" )
			)
			( pin "U2D1.AW66"
				( objectStatus "@baseboard_fab2_lib.baseboard_fab2(sch_1):page74_i23:vss(691)" )
			)
			( pin "U2D1.AW62"
				( objectStatus "@baseboard_fab2_lib.baseboard_fab2(sch_1):page74_i23:vss(692)" )
			)
			( pin "U2D1.AW10"
				( objectStatus "@baseboard_fab2_lib.baseboard_fab2(sch_1):page74_i23:vss(693)" )
			)
			( pin "U2D1.AW2"
				( objectStatus "@baseboard_fab2_lib.baseboard_fab2(sch_1):page74_i23:vss(694)" )
			)
			( pin "U2D1.AV83"
				( objectStatus "@baseboard_fab2_lib.baseboard_fab2(sch_1):page74_i23:vss(695)" )
			)
			( pin "U2D1.AV75"
				( objectStatus "@baseboard_fab2_lib.baseboard_fab2(sch_1):page74_i23:vss(696)" )
			)
			( pin "U2D1.AV67"
				( objectStatus "@baseboard_fab2_lib.baseboard_fab2(sch_1):page74_i23:vss(697)" )
			)
			( pin "U2D1.AV65"
				( objectStatus "@baseboard_fab2_lib.baseboard_fab2(sch_1):page74_i23:vss(698)" )
			)
			( pin "U2D1.AV63"
				( objectStatus "@baseboard_fab2_lib.baseboard_fab2(sch_1):page74_i23:vss(699)" )
			)
			( pin "U2D1.AV25"
				( objectStatus "@baseboard_fab2_lib.baseboard_fab2(sch_1):page74_i23:vss(700)" )
			)
			( pin "U2D1.AV23"
				( objectStatus "@baseboard_fab2_lib.baseboard_fab2(sch_1):page74_i23:vss(701)" )
			)
			( pin "U2D1.AV19"
				( objectStatus "@baseboard_fab2_lib.baseboard_fab2(sch_1):page74_i23:vss(702)" )
			)
			( pin "U2D1.AV13"
				( objectStatus "@baseboard_fab2_lib.baseboard_fab2(sch_1):page74_i23:vss(703)" )
			)
			( pin "U2D1.AV11"
				( objectStatus "@baseboard_fab2_lib.baseboard_fab2(sch_1):page74_i23:vss(704)" )
			)
			( pin "U2D1.AV7"
				( objectStatus "@baseboard_fab2_lib.baseboard_fab2(sch_1):page74_i23:vss(705)" )
			)
			( pin "U2D1.AV3"
				( objectStatus "@baseboard_fab2_lib.baseboard_fab2(sch_1):page74_i23:vss(706)" )
			)
			( pin "U2D1.AV1"
				( objectStatus "@baseboard_fab2_lib.baseboard_fab2(sch_1):page74_i23:vss(707)" )
			)
			( pin "U2D1.AU86"
				( objectStatus "@baseboard_fab2_lib.baseboard_fab2(sch_1):page74_i23:vss(708)" )
			)
			( pin "U2D1.AU84"
				( objectStatus "@baseboard_fab2_lib.baseboard_fab2(sch_1):page74_i23:vss(709)" )
			)
			( pin "U2D1.AU80"
				( objectStatus "@baseboard_fab2_lib.baseboard_fab2(sch_1):page74_i23:vss(710)" )
			)
			( pin "U2D1.AU78"
				( objectStatus "@baseboard_fab2_lib.baseboard_fab2(sch_1):page74_i23:vss(711)" )
			)
			( pin "U2D1.AU76"
				( objectStatus "@baseboard_fab2_lib.baseboard_fab2(sch_1):page74_i23:vss(712)" )
			)
			( pin "U2D1.AU74"
				( objectStatus "@baseboard_fab2_lib.baseboard_fab2(sch_1):page74_i23:vss(713)" )
			)
			( pin "U2D1.AU68"
				( objectStatus "@baseboard_fab2_lib.baseboard_fab2(sch_1):page74_i23:vss(714)" )
			)
			( pin "U2D1.AU64"
				( objectStatus "@baseboard_fab2_lib.baseboard_fab2(sch_1):page74_i23:vss(715)" )
			)
			( pin "U2D1.AU62"
				( objectStatus "@baseboard_fab2_lib.baseboard_fab2(sch_1):page74_i23:vss(716)" )
			)
			( pin "U2D1.AU28"
				( objectStatus "@baseboard_fab2_lib.baseboard_fab2(sch_1):page74_i23:vss(717)" )
			)
			( pin "U2D1.AU26"
				( objectStatus "@baseboard_fab2_lib.baseboard_fab2(sch_1):page74_i23:vss(718)" )
			)
			( pin "U2D1.AU6"
				( objectStatus "@baseboard_fab2_lib.baseboard_fab2(sch_1):page74_i23:vss(719)" )
			)
			( pin "U2D1.AU2"
				( objectStatus "@baseboard_fab2_lib.baseboard_fab2(sch_1):page74_i23:vss(720)" )
			)
			( pin "U2D1.AT85"
				( objectStatus "@baseboard_fab2_lib.baseboard_fab2(sch_1):page74_i23:vss(721)" )
			)
			( pin "U2D1.AT83"
				( objectStatus "@baseboard_fab2_lib.baseboard_fab2(sch_1):page74_i23:vss(722)" )
			)
			( pin "U2D1.AT77"
				( objectStatus "@baseboard_fab2_lib.baseboard_fab2(sch_1):page74_i23:vss(723)" )
			)
			( pin "U2D1.AT73"
				( objectStatus "@baseboard_fab2_lib.baseboard_fab2(sch_1):page74_i23:vss(724)" )
			)
			( pin "U2D1.AT69"
				( objectStatus "@baseboard_fab2_lib.baseboard_fab2(sch_1):page74_i23:vss(725)" )
			)
			( pin "U2D1.AT63"
				( objectStatus "@baseboard_fab2_lib.baseboard_fab2(sch_1):page74_i23:vss(726)" )
			)
			( pin "U2D1.AT61"
				( objectStatus "@baseboard_fab2_lib.baseboard_fab2(sch_1):page74_i23:vss(727)" )
			)
			( pin "U2D1.AT27"
				( objectStatus "@baseboard_fab2_lib.baseboard_fab2(sch_1):page74_i23:vss(728)" )
			)
			( pin "U2D1.AT21"
				( objectStatus "@baseboard_fab2_lib.baseboard_fab2(sch_1):page74_i23:vss(729)" )
			)
			( pin "U2D1.AT17"
				( objectStatus "@baseboard_fab2_lib.baseboard_fab2(sch_1):page74_i23:vss(730)" )
			)
			( pin "U2D1.AT15"
				( objectStatus "@baseboard_fab2_lib.baseboard_fab2(sch_1):page74_i23:vss(731)" )
			)
			( pin "U2D1.P63"
				( objectStatus "@baseboard_fab2_lib.baseboard_fab2(sch_1):page74_i23:vss(732)" )
			)
			( pin "U2D1.AC48"
				( objectStatus "@baseboard_fab2_lib.baseboard_fab2(sch_1):page74_i23:vss(733)" )
			)
			( pin "U2D1.AR78"
				( objectStatus "@baseboard_fab2_lib.baseboard_fab2(sch_1):page74_i23:vss(734)" )
			)
			( pin "U2D1.AR72"
				( objectStatus "@baseboard_fab2_lib.baseboard_fab2(sch_1):page74_i23:vss(735)" )
			)
			( pin "U2D1.AR60"
				( objectStatus "@baseboard_fab2_lib.baseboard_fab2(sch_1):page74_i23:vss(736)" )
			)
			( pin "U2D1.AR30"
				( objectStatus "@baseboard_fab2_lib.baseboard_fab2(sch_1):page74_i23:vss(737)" )
			)
			( pin "U2D1.AR24"
				( objectStatus "@baseboard_fab2_lib.baseboard_fab2(sch_1):page74_i23:vss(738)" )
			)
			( pin "U2D1.AR10"
				( objectStatus "@baseboard_fab2_lib.baseboard_fab2(sch_1):page74_i23:vss(739)" )
			)
			( pin "U2D1.AP85"
				( objectStatus "@baseboard_fab2_lib.baseboard_fab2(sch_1):page74_i23:vss(740)" )
			)
			( pin "U2D1.AP83"
				( objectStatus "@baseboard_fab2_lib.baseboard_fab2(sch_1):page74_i23:vss(741)" )
			)
			( pin "U2D1.AP81"
				( objectStatus "@baseboard_fab2_lib.baseboard_fab2(sch_1):page74_i23:vss(742)" )
			)
			( pin "U2D1.AP75"
				( objectStatus "@baseboard_fab2_lib.baseboard_fab2(sch_1):page74_i23:vss(743)" )
			)
			( pin "U2D1.AP73"
				( objectStatus "@baseboard_fab2_lib.baseboard_fab2(sch_1):page74_i23:vss(744)" )
			)
			( pin "U2D1.AP69"
				( objectStatus "@baseboard_fab2_lib.baseboard_fab2(sch_1):page74_i23:vss(745)" )
			)
			( pin "U2D1.AP67"
				( objectStatus "@baseboard_fab2_lib.baseboard_fab2(sch_1):page74_i23:vss(746)" )
			)
			( pin "U2D1.AP65"
				( objectStatus "@baseboard_fab2_lib.baseboard_fab2(sch_1):page74_i23:vss(747)" )
			)
			( pin "U2D1.AP63"
				( objectStatus "@baseboard_fab2_lib.baseboard_fab2(sch_1):page74_i23:vss(748)" )
			)
			( pin "U2D1.AP59"
				( objectStatus "@baseboard_fab2_lib.baseboard_fab2(sch_1):page74_i23:vss(749)" )
			)
			( pin "U2D1.AP31"
				( objectStatus "@baseboard_fab2_lib.baseboard_fab2(sch_1):page74_i23:vss(750)" )
			)
			( pin "U2D1.AP19"
				( objectStatus "@baseboard_fab2_lib.baseboard_fab2(sch_1):page74_i23:vss(751)" )
			)
			( pin "U2D1.AP13"
				( objectStatus "@baseboard_fab2_lib.baseboard_fab2(sch_1):page74_i23:vss(752)" )
			)
			( pin "U2D1.AP9"
				( objectStatus "@baseboard_fab2_lib.baseboard_fab2(sch_1):page74_i23:vss(753)" )
			)
			( pin "U2D1.AP5"
				( objectStatus "@baseboard_fab2_lib.baseboard_fab2(sch_1):page74_i23:vss(754)" )
			)
			( pin "U2D1.AN78"
				( objectStatus "@baseboard_fab2_lib.baseboard_fab2(sch_1):page74_i23:vss(755)" )
			)
			( pin "U2D1.AN58"
				( objectStatus "@baseboard_fab2_lib.baseboard_fab2(sch_1):page74_i23:vss(756)" )
			)
			( pin "U2D1.AN28"
				( objectStatus "@baseboard_fab2_lib.baseboard_fab2(sch_1):page74_i23:vss(757)" )
			)
			( pin "U2D1.AN6"
				( objectStatus "@baseboard_fab2_lib.baseboard_fab2(sch_1):page74_i23:vss(758)" )
			)
			( pin "U2D1.AN2"
				( objectStatus "@baseboard_fab2_lib.baseboard_fab2(sch_1):page74_i23:vss(759)" )
			)
			( pin "U2D1.AM83"
				( objectStatus "@baseboard_fab2_lib.baseboard_fab2(sch_1):page74_i23:vss(760)" )
			)
			( pin "U2D1.AM79"
				( objectStatus "@baseboard_fab2_lib.baseboard_fab2(sch_1):page74_i23:vss(761)" )
			)
			( pin "U2D1.AM73"
				( objectStatus "@baseboard_fab2_lib.baseboard_fab2(sch_1):page74_i23:vss(762)" )
			)
			( pin "U2D1.AM69"
				( objectStatus "@baseboard_fab2_lib.baseboard_fab2(sch_1):page74_i23:vss(763)" )
			)
			( pin "U2D1.AM63"
				( objectStatus "@baseboard_fab2_lib.baseboard_fab2(sch_1):page74_i23:vss(764)" )
			)
			( pin "U2D1.AM57"
				( objectStatus "@baseboard_fab2_lib.baseboard_fab2(sch_1):page74_i23:vss(765)" )
			)
			( pin "U2D1.AM31"
				( objectStatus "@baseboard_fab2_lib.baseboard_fab2(sch_1):page74_i23:vss(766)" )
			)
			( pin "U2D1.AC50"
				( objectStatus "@baseboard_fab2_lib.baseboard_fab2(sch_1):page74_i23:vss(767)" )
			)
			( pin "U2D1.AM1"
				( objectStatus "@baseboard_fab2_lib.baseboard_fab2(sch_1):page74_i23:vss(768)" )
			)
			( pin "U2D1.AL86"
				( objectStatus "@baseboard_fab2_lib.baseboard_fab2(sch_1):page74_i23:vss(769)" )
			)
			( pin "U2D1.AL82"
				( objectStatus "@baseboard_fab2_lib.baseboard_fab2(sch_1):page74_i23:vss(770)" )
			)
			( pin "U2D1.AL80"
				( objectStatus "@baseboard_fab2_lib.baseboard_fab2(sch_1):page74_i23:vss(771)" )
			)
			( pin "U2D1.AL78"
				( objectStatus "@baseboard_fab2_lib.baseboard_fab2(sch_1):page74_i23:vss(772)" )
			)
			( pin "U2D1.AL76"
				( objectStatus "@baseboard_fab2_lib.baseboard_fab2(sch_1):page74_i23:vss(773)" )
			)
			( pin "U2D1.P49"
				( objectStatus "@baseboard_fab2_lib.baseboard_fab2(sch_1):page75_i17:vss(454)" )
			)
			( pin "U2D1.CJ12"
				( objectStatus "@baseboard_fab2_lib.baseboard_fab2(sch_1):page75_i17:vss(455)" )
			)
			( pin "U2D1.CJ10"
				( objectStatus "@baseboard_fab2_lib.baseboard_fab2(sch_1):page75_i17:vss(456)" )
			)
			( pin "U2D1.CJ8"
				( objectStatus "@baseboard_fab2_lib.baseboard_fab2(sch_1):page75_i17:vss(457)" )
			)
			( pin "U2D1.CJ6"
				( objectStatus "@baseboard_fab2_lib.baseboard_fab2(sch_1):page75_i17:vss(458)" )
			)
			( pin "U2D1.CJ2"
				( objectStatus "@baseboard_fab2_lib.baseboard_fab2(sch_1):page75_i17:vss(459)" )
			)
			( pin "U2D1.CH83"
				( objectStatus "@baseboard_fab2_lib.baseboard_fab2(sch_1):page75_i17:vss(460)" )
			)
			( pin "U2D1.CH81"
				( objectStatus "@baseboard_fab2_lib.baseboard_fab2(sch_1):page75_i17:vss(461)" )
			)
			( pin "U2D1.CH79"
				( objectStatus "@baseboard_fab2_lib.baseboard_fab2(sch_1):page75_i17:vss(462)" )
			)
			( pin "U2D1.CH73"
				( objectStatus "@baseboard_fab2_lib.baseboard_fab2(sch_1):page75_i17:vss(463)" )
			)
			( pin "U2D1.CH67"
				( objectStatus "@baseboard_fab2_lib.baseboard_fab2(sch_1):page75_i17:vss(464)" )
			)
			( pin "U2D1.CH63"
				( objectStatus "@baseboard_fab2_lib.baseboard_fab2(sch_1):page75_i17:vss(465)" )
			)
			( pin "U2D1.CH19"
				( objectStatus "@baseboard_fab2_lib.baseboard_fab2(sch_1):page75_i17:vss(466)" )
			)
			( pin "U2D1.CH15"
				( objectStatus "@baseboard_fab2_lib.baseboard_fab2(sch_1):page75_i17:vss(467)" )
			)
			( pin "U2D1.CH3"
				( objectStatus "@baseboard_fab2_lib.baseboard_fab2(sch_1):page75_i17:vss(468)" )
			)
			( pin "U2D1.CH1"
				( objectStatus "@baseboard_fab2_lib.baseboard_fab2(sch_1):page75_i17:vss(469)" )
			)
			( pin "U2D1.CG80"
				( objectStatus "@baseboard_fab2_lib.baseboard_fab2(sch_1):page75_i17:vss(470)" )
			)
			( pin "U2D1.CG72"
				( objectStatus "@baseboard_fab2_lib.baseboard_fab2(sch_1):page75_i17:vss(471)" )
			)
			( pin "U2D1.CG68"
				( objectStatus "@baseboard_fab2_lib.baseboard_fab2(sch_1):page75_i17:vss(472)" )
			)
			( pin "U2D1.CG62"
				( objectStatus "@baseboard_fab2_lib.baseboard_fab2(sch_1):page75_i17:vss(473)" )
			)
			( pin "U2D1.CG22"
				( objectStatus "@baseboard_fab2_lib.baseboard_fab2(sch_1):page75_i17:vss(474)" )
			)
			( pin "U2D1.CG18"
				( objectStatus "@baseboard_fab2_lib.baseboard_fab2(sch_1):page75_i17:vss(475)" )
			)
			( pin "U2D1.P51"
				( objectStatus "@baseboard_fab2_lib.baseboard_fab2(sch_1):page75_i17:vss(476)" )
			)
			( pin "U2D1.CF83"
				( objectStatus "@baseboard_fab2_lib.baseboard_fab2(sch_1):page75_i17:vss(477)" )
			)
			( pin "U2D1.CF77"
				( objectStatus "@baseboard_fab2_lib.baseboard_fab2(sch_1):page75_i17:vss(478)" )
			)
			( pin "U2D1.CF71"
				( objectStatus "@baseboard_fab2_lib.baseboard_fab2(sch_1):page75_i17:vss(479)" )
			)
			( pin "U2D1.CF69"
				( objectStatus "@baseboard_fab2_lib.baseboard_fab2(sch_1):page75_i17:vss(480)" )
			)
			( pin "U2D1.CF63"
				( objectStatus "@baseboard_fab2_lib.baseboard_fab2(sch_1):page75_i17:vss(481)" )
			)
			( pin "U2D1.CF9"
				( objectStatus "@baseboard_fab2_lib.baseboard_fab2(sch_1):page75_i17:vss(482)" )
			)
			( pin "U2D1.P53"
				( objectStatus "@baseboard_fab2_lib.baseboard_fab2(sch_1):page75_i17:vss(483)" )
			)
			( pin "U2D1.CE82"
				( objectStatus "@baseboard_fab2_lib.baseboard_fab2(sch_1):page75_i17:vss(484)" )
			)
			( pin "U2D1.CE70"
				( objectStatus "@baseboard_fab2_lib.baseboard_fab2(sch_1):page75_i17:vss(485)" )
			)
			( pin "U2D1.CE62"
				( objectStatus "@baseboard_fab2_lib.baseboard_fab2(sch_1):page75_i17:vss(486)" )
			)
			( pin "U2D1.CE26"
				( objectStatus "@baseboard_fab2_lib.baseboard_fab2(sch_1):page75_i17:vss(487)" )
			)
			( pin "U2D1.CE20"
				( objectStatus "@baseboard_fab2_lib.baseboard_fab2(sch_1):page75_i17:vss(488)" )
			)
			( pin "U2D1.CE14"
				( objectStatus "@baseboard_fab2_lib.baseboard_fab2(sch_1):page75_i17:vss(489)" )
			)
			( pin "U2D1.CE10"
				( objectStatus "@baseboard_fab2_lib.baseboard_fab2(sch_1):page75_i17:vss(490)" )
			)
			( pin "U2D1.CD81"
				( objectStatus "@baseboard_fab2_lib.baseboard_fab2(sch_1):page75_i17:vss(491)" )
			)
			( pin "U2D1.CD79"
				( objectStatus "@baseboard_fab2_lib.baseboard_fab2(sch_1):page75_i17:vss(492)" )
			)
			( pin "U2D1.CD77"
				( objectStatus "@baseboard_fab2_lib.baseboard_fab2(sch_1):page75_i17:vss(493)" )
			)
			( pin "U2D1.CD75"
				( objectStatus "@baseboard_fab2_lib.baseboard_fab2(sch_1):page75_i17:vss(494)" )
			)
			( pin "U2D1.CD73"
				( objectStatus "@baseboard_fab2_lib.baseboard_fab2(sch_1):page75_i17:vss(495)" )
			)
			( pin "U2D1.CD63"
				( objectStatus "@baseboard_fab2_lib.baseboard_fab2(sch_1):page75_i17:vss(496)" )
			)
			( pin "U2D1.CD13"
				( objectStatus "@baseboard_fab2_lib.baseboard_fab2(sch_1):page75_i17:vss(497)" )
			)
			( pin "U2D1.CD5"
				( objectStatus "@baseboard_fab2_lib.baseboard_fab2(sch_1):page75_i17:vss(498)" )
			)
			( pin "U2D1.CC82"
				( objectStatus "@baseboard_fab2_lib.baseboard_fab2(sch_1):page75_i17:vss(499)" )
			)
			( pin "U2D1.CC80"
				( objectStatus "@baseboard_fab2_lib.baseboard_fab2(sch_1):page75_i17:vss(500)" )
			)
			( pin "U2D1.CC78"
				( objectStatus "@baseboard_fab2_lib.baseboard_fab2(sch_1):page75_i17:vss(501)" )
			)
			( pin "U2D1.CC76"
				( objectStatus "@baseboard_fab2_lib.baseboard_fab2(sch_1):page75_i17:vss(502)" )
			)
			( pin "U2D1.CC74"
				( objectStatus "@baseboard_fab2_lib.baseboard_fab2(sch_1):page75_i17:vss(503)" )
			)
			( pin "U2D1.CC72"
				( objectStatus "@baseboard_fab2_lib.baseboard_fab2(sch_1):page75_i17:vss(504)" )
			)
			( pin "U2D1.CC64"
				( objectStatus "@baseboard_fab2_lib.baseboard_fab2(sch_1):page75_i17:vss(505)" )
			)
			( pin "U2D1.CC24"
				( objectStatus "@baseboard_fab2_lib.baseboard_fab2(sch_1):page75_i17:vss(506)" )
			)
			( pin "U2D1.CC18"
				( objectStatus "@baseboard_fab2_lib.baseboard_fab2(sch_1):page75_i17:vss(507)" )
			)
			( pin "U2D1.CC16"
				( objectStatus "@baseboard_fab2_lib.baseboard_fab2(sch_1):page75_i17:vss(508)" )
			)
			( pin "U2D1.CC4"
				( objectStatus "@baseboard_fab2_lib.baseboard_fab2(sch_1):page75_i17:vss(509)" )
			)
			( pin "U2D1.CB71"
				( objectStatus "@baseboard_fab2_lib.baseboard_fab2(sch_1):page75_i17:vss(510)" )
			)
			( pin "U2D1.CB63"
				( objectStatus "@baseboard_fab2_lib.baseboard_fab2(sch_1):page75_i17:vss(511)" )
			)
			( pin "U2D1.CB27"
				( objectStatus "@baseboard_fab2_lib.baseboard_fab2(sch_1):page75_i17:vss(512)" )
			)
			( pin "U2D1.CB9"
				( objectStatus "@baseboard_fab2_lib.baseboard_fab2(sch_1):page75_i17:vss(513)" )
			)
			( pin "U2D1.CB7"
				( objectStatus "@baseboard_fab2_lib.baseboard_fab2(sch_1):page75_i17:vss(514)" )
			)
			( pin "U2D1.CA70"
				( objectStatus "@baseboard_fab2_lib.baseboard_fab2(sch_1):page75_i17:vss(515)" )
			)
			( pin "U2D1.CA68"
				( objectStatus "@baseboard_fab2_lib.baseboard_fab2(sch_1):page75_i17:vss(516)" )
			)
			( pin "U2D1.CA66"
				( objectStatus "@baseboard_fab2_lib.baseboard_fab2(sch_1):page75_i17:vss(517)" )
			)
			( pin "U2D1.CA64"
				( objectStatus "@baseboard_fab2_lib.baseboard_fab2(sch_1):page75_i17:vss(518)" )
			)
			( pin "U2D1.CA26"
				( objectStatus "@baseboard_fab2_lib.baseboard_fab2(sch_1):page75_i17:vss(519)" )
			)
			( pin "U2D1.CA18"
				( objectStatus "@baseboard_fab2_lib.baseboard_fab2(sch_1):page75_i17:vss(520)" )
			)
			( pin "U2D1.CA14"
				( objectStatus "@baseboard_fab2_lib.baseboard_fab2(sch_1):page75_i17:vss(521)" )
			)
			( pin "U2D1.CA10"
				( objectStatus "@baseboard_fab2_lib.baseboard_fab2(sch_1):page75_i17:vss(522)" )
			)
			( pin "U2D1.CA8"
				( objectStatus "@baseboard_fab2_lib.baseboard_fab2(sch_1):page75_i17:vss(523)" )
			)
			( pin "U2D1.CA6"
				( objectStatus "@baseboard_fab2_lib.baseboard_fab2(sch_1):page75_i17:vss(524)" )
			)
			( pin "U2D1.CA2"
				( objectStatus "@baseboard_fab2_lib.baseboard_fab2(sch_1):page75_i17:vss(525)" )
			)
			( pin "U2D1.BY71"
				( objectStatus "@baseboard_fab2_lib.baseboard_fab2(sch_1):page75_i17:vss(526)" )
			)
			( pin "U2D1.BY69"
				( objectStatus "@baseboard_fab2_lib.baseboard_fab2(sch_1):page75_i17:vss(527)" )
			)
			( pin "U2D1.BY67"
				( objectStatus "@baseboard_fab2_lib.baseboard_fab2(sch_1):page75_i17:vss(528)" )
			)
			( pin "U2D1.BY65"
				( objectStatus "@baseboard_fab2_lib.baseboard_fab2(sch_1):page75_i17:vss(529)" )
			)
			( pin "U2D1.BY63"
				( objectStatus "@baseboard_fab2_lib.baseboard_fab2(sch_1):page75_i17:vss(530)" )
			)
			( pin "U2D1.BY23"
				( objectStatus "@baseboard_fab2_lib.baseboard_fab2(sch_1):page75_i17:vss(531)" )
			)
			( pin "U2D1.BY13"
				( objectStatus "@baseboard_fab2_lib.baseboard_fab2(sch_1):page75_i17:vss(532)" )
			)
			( pin "U2D1.BY11"
				( objectStatus "@baseboard_fab2_lib.baseboard_fab2(sch_1):page75_i17:vss(533)" )
			)
			( pin "U2D1.BW82"
				( objectStatus "@baseboard_fab2_lib.baseboard_fab2(sch_1):page75_i17:vss(534)" )
			)
			( pin "U2D1.BW80"
				( objectStatus "@baseboard_fab2_lib.baseboard_fab2(sch_1):page75_i17:vss(535)" )
			)
			( pin "U2D1.BW78"
				( objectStatus "@baseboard_fab2_lib.baseboard_fab2(sch_1):page75_i17:vss(536)" )
			)
			( pin "U2D1.BW76"
				( objectStatus "@baseboard_fab2_lib.baseboard_fab2(sch_1):page75_i17:vss(537)" )
			)
			( pin "U2D1.BW74"
				( objectStatus "@baseboard_fab2_lib.baseboard_fab2(sch_1):page75_i17:vss(538)" )
			)
			( pin "U2D1.BW72"
				( objectStatus "@baseboard_fab2_lib.baseboard_fab2(sch_1):page75_i17:vss(539)" )
			)
			( pin "U2D1.BW26"
				( objectStatus "@baseboard_fab2_lib.baseboard_fab2(sch_1):page75_i17:vss(540)" )
			)
			( pin "U2D1.BW18"
				( objectStatus "@baseboard_fab2_lib.baseboard_fab2(sch_1):page75_i17:vss(541)" )
			)
			( pin "U2D1.BW16"
				( objectStatus "@baseboard_fab2_lib.baseboard_fab2(sch_1):page75_i17:vss(542)" )
			)
			( pin "U2D1.BW14"
				( objectStatus "@baseboard_fab2_lib.baseboard_fab2(sch_1):page75_i17:vss(543)" )
			)
			( pin "U2D1.BW12"
				( objectStatus "@baseboard_fab2_lib.baseboard_fab2(sch_1):page75_i17:vss(544)" )
			)
			( pin "U2D1.P55"
				( objectStatus "@baseboard_fab2_lib.baseboard_fab2(sch_1):page75_i17:vss(545)" )
			)
			( pin "U2D1.BW6"
				( objectStatus "@baseboard_fab2_lib.baseboard_fab2(sch_1):page75_i17:vss(546)" )
			)
			( pin "U2D1.BV25"
				( objectStatus "@baseboard_fab2_lib.baseboard_fab2(sch_1):page75_i17:vss(547)" )
			)
			( pin "U2D1.BV17"
				( objectStatus "@baseboard_fab2_lib.baseboard_fab2(sch_1):page75_i17:vss(548)" )
			)
			( pin "U2D1.BU10"
				( objectStatus "@baseboard_fab2_lib.baseboard_fab2(sch_1):page75_i17:vss(549)" )
			)
			( pin "U2D1.BV5"
				( objectStatus "@baseboard_fab2_lib.baseboard_fab2(sch_1):page75_i17:vss(550)" )
			)
			( pin "U2D1.BU8"
				( objectStatus "@baseboard_fab2_lib.baseboard_fab2(sch_1):page75_i17:vss(551)" )
			)
			( pin "U2D1.BT25"
				( objectStatus "@baseboard_fab2_lib.baseboard_fab2(sch_1):page75_i17:vss(552)" )
			)
			( pin "U2D1.BT23"
				( objectStatus "@baseboard_fab2_lib.baseboard_fab2(sch_1):page75_i17:vss(553)" )
			)
			( pin "U2D1.BT21"
				( objectStatus "@baseboard_fab2_lib.baseboard_fab2(sch_1):page75_i17:vss(554)" )
			)
			( pin "U2D1.BT5"
				( objectStatus "@baseboard_fab2_lib.baseboard_fab2(sch_1):page75_i17:vss(555)" )
			)
			( pin "U2D1.BT3"
				( objectStatus "@baseboard_fab2_lib.baseboard_fab2(sch_1):page75_i17:vss(556)" )
			)
			( pin "U2D1.BR82"
				( objectStatus "@baseboard_fab2_lib.baseboard_fab2(sch_1):page75_i17:vss(557)" )
			)
			( pin "U2D1.BR80"
				( objectStatus "@baseboard_fab2_lib.baseboard_fab2(sch_1):page75_i17:vss(558)" )
			)
			( pin "U2D1.BR78"
				( objectStatus "@baseboard_fab2_lib.baseboard_fab2(sch_1):page75_i17:vss(559)" )
			)
			( pin "U2D1.BR76"
				( objectStatus "@baseboard_fab2_lib.baseboard_fab2(sch_1):page75_i17:vss(560)" )
			)
			( pin "U2D1.BR74"
				( objectStatus "@baseboard_fab2_lib.baseboard_fab2(sch_1):page75_i17:vss(561)" )
			)
			( pin "U2D1.BR72"
				( objectStatus "@baseboard_fab2_lib.baseboard_fab2(sch_1):page75_i17:vss(562)" )
			)
			( pin "U2D1.BR70"
				( objectStatus "@baseboard_fab2_lib.baseboard_fab2(sch_1):page75_i17:vss(563)" )
			)
			( pin "U2D1.BR68"
				( objectStatus "@baseboard_fab2_lib.baseboard_fab2(sch_1):page75_i17:vss(564)" )
			)
			( pin "U2D1.BR66"
				( objectStatus "@baseboard_fab2_lib.baseboard_fab2(sch_1):page75_i17:vss(565)" )
			)
			( pin "U2D1.BR64"
				( objectStatus "@baseboard_fab2_lib.baseboard_fab2(sch_1):page75_i17:vss(566)" )
			)
			( pin "U2D1.P57"
				( objectStatus "@baseboard_fab2_lib.baseboard_fab2(sch_1):page75_i17:vss(567)" )
			)
			( pin "U2D1.BR16"
				( objectStatus "@baseboard_fab2_lib.baseboard_fab2(sch_1):page75_i17:vss(568)" )
			)
			( pin "U2D1.BR10"
				( objectStatus "@baseboard_fab2_lib.baseboard_fab2(sch_1):page75_i17:vss(569)" )
			)
			( pin "U2D1.BR6"
				( objectStatus "@baseboard_fab2_lib.baseboard_fab2(sch_1):page75_i17:vss(570)" )
			)
			( pin "U2D1.BP27"
				( objectStatus "@baseboard_fab2_lib.baseboard_fab2(sch_1):page75_i17:vss(571)" )
			)
			( pin "U2D1.BP3"
				( objectStatus "@baseboard_fab2_lib.baseboard_fab2(sch_1):page75_i17:vss(572)" )
			)
			( pin "U2D1.BN26"
				( objectStatus "@baseboard_fab2_lib.baseboard_fab2(sch_1):page75_i17:vss(573)" )
			)
			( pin "U2D1.BN20"
				( objectStatus "@baseboard_fab2_lib.baseboard_fab2(sch_1):page75_i17:vss(574)" )
			)
			( pin "U2D1.BN10"
				( objectStatus "@baseboard_fab2_lib.baseboard_fab2(sch_1):page75_i17:vss(575)" )
			)
			( pin "U2D1.BN6"
				( objectStatus "@baseboard_fab2_lib.baseboard_fab2(sch_1):page75_i17:vss(576)" )
			)
			( pin "U2D1.BM25"
				( objectStatus "@baseboard_fab2_lib.baseboard_fab2(sch_1):page75_i17:vss(577)" )
			)
			( pin "U2D1.P59"
				( objectStatus "@baseboard_fab2_lib.baseboard_fab2(sch_1):page75_i17:vss(578)" )
			)
			( pin "U2D1.BM15"
				( objectStatus "@baseboard_fab2_lib.baseboard_fab2(sch_1):page75_i17:vss(579)" )
			)
			( pin "U2D1.BM13"
				( objectStatus "@baseboard_fab2_lib.baseboard_fab2(sch_1):page75_i17:vss(580)" )
			)
			( pin "U2D1.BM9"
				( objectStatus "@baseboard_fab2_lib.baseboard_fab2(sch_1):page75_i17:vss(581)" )
			)
			( pin "U2D1.BL82"
				( objectStatus "@baseboard_fab2_lib.baseboard_fab2(sch_1):page75_i17:vss(582)" )
			)
			( pin "U2D1.BL80"
				( objectStatus "@baseboard_fab2_lib.baseboard_fab2(sch_1):page75_i17:vss(583)" )
			)
			( pin "U2D1.BL78"
				( objectStatus "@baseboard_fab2_lib.baseboard_fab2(sch_1):page75_i17:vss(584)" )
			)
			( pin "U2D1.BL76"
				( objectStatus "@baseboard_fab2_lib.baseboard_fab2(sch_1):page75_i17:vss(585)" )
			)
			( pin "U2D1.BL74"
				( objectStatus "@baseboard_fab2_lib.baseboard_fab2(sch_1):page75_i17:vss(586)" )
			)
			( pin "U2D1.BL72"
				( objectStatus "@baseboard_fab2_lib.baseboard_fab2(sch_1):page75_i17:vss(587)" )
			)
			( pin "U2D1.BL70"
				( objectStatus "@baseboard_fab2_lib.baseboard_fab2(sch_1):page75_i17:vss(588)" )
			)
			( pin "U2D1.BL68"
				( objectStatus "@baseboard_fab2_lib.baseboard_fab2(sch_1):page75_i17:vss(589)" )
			)
			( pin "U2D1.BL66"
				( objectStatus "@baseboard_fab2_lib.baseboard_fab2(sch_1):page75_i17:vss(590)" )
			)
			( pin "U2D1.BL64"
				( objectStatus "@baseboard_fab2_lib.baseboard_fab2(sch_1):page75_i17:vss(591)" )
			)
			( pin "U2D1.BL24"
				( objectStatus "@baseboard_fab2_lib.baseboard_fab2(sch_1):page75_i17:vss(592)" )
			)
			( pin "U2D1.BL22"
				( objectStatus "@baseboard_fab2_lib.baseboard_fab2(sch_1):page75_i17:vss(593)" )
			)
			( pin "U2D1.P61"
				( objectStatus "@baseboard_fab2_lib.baseboard_fab2(sch_1):page75_i17:vss(594)" )
			)
			( pin "U2D1.BL12"
				( objectStatus "@baseboard_fab2_lib.baseboard_fab2(sch_1):page75_i17:vss(595)" )
			)
			( pin "U2D1.BL10"
				( objectStatus "@baseboard_fab2_lib.baseboard_fab2(sch_1):page75_i17:vss(596)" )
			)
			( pin "U2D1.BL6"
				( objectStatus "@baseboard_fab2_lib.baseboard_fab2(sch_1):page75_i17:vss(597)" )
			)
			( pin "U2D1.BK19"
				( objectStatus "@baseboard_fab2_lib.baseboard_fab2(sch_1):page75_i17:vss(598)" )
			)
			( pin "U2D1.BK11"
				( objectStatus "@baseboard_fab2_lib.baseboard_fab2(sch_1):page75_i17:vss(599)" )
			)
			( pin "U2D1.BK7"
				( objectStatus "@baseboard_fab2_lib.baseboard_fab2(sch_1):page75_i17:vss(600)" )
			)
			( pin "U2D1.BK3"
				( objectStatus "@baseboard_fab2_lib.baseboard_fab2(sch_1):page75_i17:vss(601)" )
			)
			( pin "U2D1.BJ6"
				( objectStatus "@baseboard_fab2_lib.baseboard_fab2(sch_1):page75_i17:vss(602)" )
			)
			( pin "U2D1.BJ4"
				( objectStatus "@baseboard_fab2_lib.baseboard_fab2(sch_1):page75_i17:vss(603)" )
			)
			( pin "U2D1.BH21"
				( objectStatus "@baseboard_fab2_lib.baseboard_fab2(sch_1):page75_i17:vss(604)" )
			)
			( pin "U2D1.BH15"
				( objectStatus "@baseboard_fab2_lib.baseboard_fab2(sch_1):page75_i17:vss(605)" )
			)
			( pin "U2D1.BH11"
				( objectStatus "@baseboard_fab2_lib.baseboard_fab2(sch_1):page75_i17:vss(606)" )
			)
			( pin "U2D1.BH9"
				( objectStatus "@baseboard_fab2_lib.baseboard_fab2(sch_1):page75_i17:vss(607)" )
			)
			( pin "U2D1.BH7"
				( objectStatus "@baseboard_fab2_lib.baseboard_fab2(sch_1):page75_i17:vss(608)" )
			)
			( pin "U2D1.BG82"
				( objectStatus "@baseboard_fab2_lib.baseboard_fab2(sch_1):page75_i17:vss(609)" )
			)
			( pin "U2D1.BG80"
				( objectStatus "@baseboard_fab2_lib.baseboard_fab2(sch_1):page75_i17:vss(610)" )
			)
			( pin "U2D1.BG78"
				( objectStatus "@baseboard_fab2_lib.baseboard_fab2(sch_1):page75_i17:vss(611)" )
			)
			( pin "U2D1.BG76"
				( objectStatus "@baseboard_fab2_lib.baseboard_fab2(sch_1):page75_i17:vss(612)" )
			)
			( pin "U2D1.BG74"
				( objectStatus "@baseboard_fab2_lib.baseboard_fab2(sch_1):page75_i17:vss(613)" )
			)
			( pin "U2D1.DA46"
				( objectStatus "@baseboard_fab2_lib.baseboard_fab2(sch_1):page75_i18:vss(294)" )
			)
			( pin "U2D1.DA44"
				( objectStatus "@baseboard_fab2_lib.baseboard_fab2(sch_1):page75_i18:vss(295)" )
			)
			( pin "U2D1.DA38"
				( objectStatus "@baseboard_fab2_lib.baseboard_fab2(sch_1):page75_i18:vss(296)" )
			)
			( pin "U2D1.DA36"
				( objectStatus "@baseboard_fab2_lib.baseboard_fab2(sch_1):page75_i18:vss(297)" )
			)
			( pin "U2D1.DA34"
				( objectStatus "@baseboard_fab2_lib.baseboard_fab2(sch_1):page75_i18:vss(298)" )
			)
			( pin "U2D1.DA32"
				( objectStatus "@baseboard_fab2_lib.baseboard_fab2(sch_1):page75_i18:vss(299)" )
			)
			( pin "U2D1.DA30"
				( objectStatus "@baseboard_fab2_lib.baseboard_fab2(sch_1):page75_i18:vss(300)" )
			)
			( pin "U2D1.DA28"
				( objectStatus "@baseboard_fab2_lib.baseboard_fab2(sch_1):page75_i18:vss(301)" )
			)
			( pin "U2D1.DA26"
				( objectStatus "@baseboard_fab2_lib.baseboard_fab2(sch_1):page75_i18:vss(302)" )
			)
			( pin "U2D1.DA18"
				( objectStatus "@baseboard_fab2_lib.baseboard_fab2(sch_1):page75_i18:vss(303)" )
			)
			( pin "U2D1.H53"
				( objectStatus "@baseboard_fab2_lib.baseboard_fab2(sch_1):page75_i18:vss(304)" )
			)
			( pin "U2D1.DA6"
				( objectStatus "@baseboard_fab2_lib.baseboard_fab2(sch_1):page75_i18:vss(305)" )
			)
			( pin "U2D1.CY85"
				( objectStatus "@baseboard_fab2_lib.baseboard_fab2(sch_1):page75_i18:vss(306)" )
			)
			( pin "U2D1.CY83"
				( objectStatus "@baseboard_fab2_lib.baseboard_fab2(sch_1):page75_i18:vss(307)" )
			)
			( pin "U2D1.CY77"
				( objectStatus "@baseboard_fab2_lib.baseboard_fab2(sch_1):page75_i18:vss(308)" )
			)
			( pin "U2D1.CY75"
				( objectStatus "@baseboard_fab2_lib.baseboard_fab2(sch_1):page75_i18:vss(309)" )
			)
			( pin "U2D1.CY69"
				( objectStatus "@baseboard_fab2_lib.baseboard_fab2(sch_1):page75_i18:vss(310)" )
			)
			( pin "U2D1.CY65"
				( objectStatus "@baseboard_fab2_lib.baseboard_fab2(sch_1):page75_i18:vss(311)" )
			)
			( pin "U2D1.CY61"
				( objectStatus "@baseboard_fab2_lib.baseboard_fab2(sch_1):page75_i18:vss(312)" )
			)
			( pin "U2D1.CY59"
				( objectStatus "@baseboard_fab2_lib.baseboard_fab2(sch_1):page75_i18:vss(313)" )
			)
			( pin "U2D1.CY51"
				( objectStatus "@baseboard_fab2_lib.baseboard_fab2(sch_1):page75_i18:vss(314)" )
			)
			( pin "U2D1.CY45"
				( objectStatus "@baseboard_fab2_lib.baseboard_fab2(sch_1):page75_i18:vss(315)" )
			)
			( pin "U2D1.CY41"
				( objectStatus "@baseboard_fab2_lib.baseboard_fab2(sch_1):page75_i18:vss(316)" )
			)
			( pin "U2D1.CY21"
				( objectStatus "@baseboard_fab2_lib.baseboard_fab2(sch_1):page75_i18:vss(317)" )
			)
			( pin "U2D1.CY15"
				( objectStatus "@baseboard_fab2_lib.baseboard_fab2(sch_1):page75_i18:vss(318)" )
			)
			( pin "U2D1.CY13"
				( objectStatus "@baseboard_fab2_lib.baseboard_fab2(sch_1):page75_i18:vss(319)" )
			)
			( pin "U2D1.CY9"
				( objectStatus "@baseboard_fab2_lib.baseboard_fab2(sch_1):page75_i18:vss(320)" )
			)
			( pin "U2D1.CY1"
				( objectStatus "@baseboard_fab2_lib.baseboard_fab2(sch_1):page75_i18:vss(321)" )
			)
			( pin "U2D1.CW82"
				( objectStatus "@baseboard_fab2_lib.baseboard_fab2(sch_1):page75_i18:vss(322)" )
			)
			( pin "U2D1.CW78"
				( objectStatus "@baseboard_fab2_lib.baseboard_fab2(sch_1):page75_i18:vss(323)" )
			)
			( pin "U2D1.CW74"
				( objectStatus "@baseboard_fab2_lib.baseboard_fab2(sch_1):page75_i18:vss(324)" )
			)
			( pin "U2D1.CW68"
				( objectStatus "@baseboard_fab2_lib.baseboard_fab2(sch_1):page75_i18:vss(325)" )
			)
			( pin "U2D1.CW66"
				( objectStatus "@baseboard_fab2_lib.baseboard_fab2(sch_1):page75_i18:vss(326)" )
			)
			( pin "U2D1.CW64"
				( objectStatus "@baseboard_fab2_lib.baseboard_fab2(sch_1):page75_i18:vss(327)" )
			)
			( pin "U2D1.CW54"
				( objectStatus "@baseboard_fab2_lib.baseboard_fab2(sch_1):page75_i18:vss(328)" )
			)
			( pin "U2D1.CW52"
				( objectStatus "@baseboard_fab2_lib.baseboard_fab2(sch_1):page75_i18:vss(329)" )
			)
			( pin "U2D1.CW42"
				( objectStatus "@baseboard_fab2_lib.baseboard_fab2(sch_1):page75_i18:vss(330)" )
			)
			( pin "U2D1.CW40"
				( objectStatus "@baseboard_fab2_lib.baseboard_fab2(sch_1):page75_i18:vss(331)" )
			)
			( pin "U2D1.CW38"
				( objectStatus "@baseboard_fab2_lib.baseboard_fab2(sch_1):page75_i18:vss(332)" )
			)
			( pin "U2D1.CW32"
				( objectStatus "@baseboard_fab2_lib.baseboard_fab2(sch_1):page75_i18:vss(333)" )
			)
			( pin "U2D1.CW26"
				( objectStatus "@baseboard_fab2_lib.baseboard_fab2(sch_1):page75_i18:vss(334)" )
			)
			( pin "U2D1.CW12"
				( objectStatus "@baseboard_fab2_lib.baseboard_fab2(sch_1):page75_i18:vss(335)" )
			)
			( pin "U2D1.CV83"
				( objectStatus "@baseboard_fab2_lib.baseboard_fab2(sch_1):page75_i18:vss(336)" )
			)
			( pin "U2D1.CV81"
				( objectStatus "@baseboard_fab2_lib.baseboard_fab2(sch_1):page75_i18:vss(337)" )
			)
			( pin "U2D1.CV79"
				( objectStatus "@baseboard_fab2_lib.baseboard_fab2(sch_1):page75_i18:vss(338)" )
			)
			( pin "U2D1.CV73"
				( objectStatus "@baseboard_fab2_lib.baseboard_fab2(sch_1):page75_i18:vss(339)" )
			)
			( pin "U2D1.CV67"
				( objectStatus "@baseboard_fab2_lib.baseboard_fab2(sch_1):page75_i18:vss(340)" )
			)
			( pin "U2D1.CV63"
				( objectStatus "@baseboard_fab2_lib.baseboard_fab2(sch_1):page75_i18:vss(341)" )
			)
			( pin "U2D1.CV55"
				( objectStatus "@baseboard_fab2_lib.baseboard_fab2(sch_1):page75_i18:vss(342)" )
			)
			( pin "U2D1.CV53"
				( objectStatus "@baseboard_fab2_lib.baseboard_fab2(sch_1):page75_i18:vss(343)" )
			)
			( pin "U2D1.CV41"
				( objectStatus "@baseboard_fab2_lib.baseboard_fab2(sch_1):page75_i18:vss(344)" )
			)
			( pin "U2D1.CV39"
				( objectStatus "@baseboard_fab2_lib.baseboard_fab2(sch_1):page75_i18:vss(345)" )
			)
			( pin "U2D1.CV37"
				( objectStatus "@baseboard_fab2_lib.baseboard_fab2(sch_1):page75_i18:vss(346)" )
			)
			( pin "U2D1.CV33"
				( objectStatus "@baseboard_fab2_lib.baseboard_fab2(sch_1):page75_i18:vss(347)" )
			)
			( pin "U2D1.CV31"
				( objectStatus "@baseboard_fab2_lib.baseboard_fab2(sch_1):page75_i18:vss(348)" )
			)
			( pin "U2D1.CV27"
				( objectStatus "@baseboard_fab2_lib.baseboard_fab2(sch_1):page75_i18:vss(349)" )
			)
			( pin "U2D1.CV25"
				( objectStatus "@baseboard_fab2_lib.baseboard_fab2(sch_1):page75_i18:vss(350)" )
			)
			( pin "U2D1.CV17"
				( objectStatus "@baseboard_fab2_lib.baseboard_fab2(sch_1):page75_i18:vss(351)" )
			)
			( pin "U2D1.H55"
				( objectStatus "@baseboard_fab2_lib.baseboard_fab2(sch_1):page75_i18:vss(352)" )
			)
			( pin "U2D1.CV1"
				( objectStatus "@baseboard_fab2_lib.baseboard_fab2(sch_1):page75_i18:vss(353)" )
			)
			( pin "U2D1.CU86"
				( objectStatus "@baseboard_fab2_lib.baseboard_fab2(sch_1):page75_i18:vss(354)" )
			)
			( pin "U2D1.CU82"
				( objectStatus "@baseboard_fab2_lib.baseboard_fab2(sch_1):page75_i18:vss(355)" )
			)
			( pin "U2D1.CU80"
				( objectStatus "@baseboard_fab2_lib.baseboard_fab2(sch_1):page75_i18:vss(356)" )
			)
			( pin "U2D1.CU78"
				( objectStatus "@baseboard_fab2_lib.baseboard_fab2(sch_1):page75_i18:vss(357)" )
			)
			( pin "U2D1.CU76"
				( objectStatus "@baseboard_fab2_lib.baseboard_fab2(sch_1):page75_i18:vss(358)" )
			)
			( pin "U2D1.CU68"
				( objectStatus "@baseboard_fab2_lib.baseboard_fab2(sch_1):page75_i18:vss(359)" )
			)
			( pin "U2D1.CU62"
				( objectStatus "@baseboard_fab2_lib.baseboard_fab2(sch_1):page75_i18:vss(360)" )
			)
			( pin "U2D1.CU56"
				( objectStatus "@baseboard_fab2_lib.baseboard_fab2(sch_1):page75_i18:vss(361)" )
			)
			( pin "U2D1.CU36"
				( objectStatus "@baseboard_fab2_lib.baseboard_fab2(sch_1):page75_i18:vss(362)" )
			)
			( pin "U2D1.CU34"
				( objectStatus "@baseboard_fab2_lib.baseboard_fab2(sch_1):page75_i18:vss(363)" )
			)
			( pin "U2D1.CU30"
				( objectStatus "@baseboard_fab2_lib.baseboard_fab2(sch_1):page75_i18:vss(364)" )
			)
			( pin "U2D1.CU28"
				( objectStatus "@baseboard_fab2_lib.baseboard_fab2(sch_1):page75_i18:vss(365)" )
			)
			( pin "U2D1.CU22"
				( objectStatus "@baseboard_fab2_lib.baseboard_fab2(sch_1):page75_i18:vss(366)" )
			)
			( pin "U2D1.CU4"
				( objectStatus "@baseboard_fab2_lib.baseboard_fab2(sch_1):page75_i18:vss(367)" )
			)
			( pin "U2D1.CT85"
				( objectStatus "@baseboard_fab2_lib.baseboard_fab2(sch_1):page75_i18:vss(368)" )
			)
			( pin "U2D1.CT83"
				( objectStatus "@baseboard_fab2_lib.baseboard_fab2(sch_1):page75_i18:vss(369)" )
			)
			( pin "U2D1.CT79"
				( objectStatus "@baseboard_fab2_lib.baseboard_fab2(sch_1):page75_i18:vss(370)" )
			)
			( pin "U2D1.CT73"
				( objectStatus "@baseboard_fab2_lib.baseboard_fab2(sch_1):page75_i18:vss(371)" )
			)
			( pin "U2D1.CT57"
				( objectStatus "@baseboard_fab2_lib.baseboard_fab2(sch_1):page75_i18:vss(372)" )
			)
			( pin "U2D1.CT35"
				( objectStatus "@baseboard_fab2_lib.baseboard_fab2(sch_1):page75_i18:vss(373)" )
			)
			( pin "U2D1.CT33"
				( objectStatus "@baseboard_fab2_lib.baseboard_fab2(sch_1):page75_i18:vss(374)" )
			)
			( pin "U2D1.CT29"
				( objectStatus "@baseboard_fab2_lib.baseboard_fab2(sch_1):page75_i18:vss(375)" )
			)
			( pin "U2D1.CT27"
				( objectStatus "@baseboard_fab2_lib.baseboard_fab2(sch_1):page75_i18:vss(376)" )
			)
			( pin "U2D1.CT19"
				( objectStatus "@baseboard_fab2_lib.baseboard_fab2(sch_1):page75_i18:vss(377)" )
			)
			( pin "U2D1.CT13"
				( objectStatus "@baseboard_fab2_lib.baseboard_fab2(sch_1):page75_i18:vss(378)" )
			)
			( pin "U2D1.H57"
				( objectStatus "@baseboard_fab2_lib.baseboard_fab2(sch_1):page75_i18:vss(379)" )
			)
			( pin "U2D1.CR86"
				( objectStatus "@baseboard_fab2_lib.baseboard_fab2(sch_1):page75_i18:vss(380)" )
			)
			( pin "U2D1.CR78"
				( objectStatus "@baseboard_fab2_lib.baseboard_fab2(sch_1):page75_i18:vss(381)" )
			)
			( pin "U2D1.CR68"
				( objectStatus "@baseboard_fab2_lib.baseboard_fab2(sch_1):page75_i18:vss(382)" )
			)
			( pin "U2D1.CR66"
				( objectStatus "@baseboard_fab2_lib.baseboard_fab2(sch_1):page75_i18:vss(383)" )
			)
			( pin "U2D1.CR64"
				( objectStatus "@baseboard_fab2_lib.baseboard_fab2(sch_1):page75_i18:vss(384)" )
			)
			( pin "U2D1.CR62"
				( objectStatus "@baseboard_fab2_lib.baseboard_fab2(sch_1):page75_i18:vss(385)" )
			)
			( pin "U2D1.CR58"
				( objectStatus "@baseboard_fab2_lib.baseboard_fab2(sch_1):page75_i18:vss(386)" )
			)
			( pin "U2D1.CR32"
				( objectStatus "@baseboard_fab2_lib.baseboard_fab2(sch_1):page75_i18:vss(387)" )
			)
			( pin "U2D1.CR24"
				( objectStatus "@baseboard_fab2_lib.baseboard_fab2(sch_1):page75_i18:vss(388)" )
			)
			( pin "U2D1.CR22"
				( objectStatus "@baseboard_fab2_lib.baseboard_fab2(sch_1):page75_i18:vss(389)" )
			)
			( pin "U2D1.CR10"
				( objectStatus "@baseboard_fab2_lib.baseboard_fab2(sch_1):page75_i18:vss(390)" )
			)
			( pin "U2D1.CR6"
				( objectStatus "@baseboard_fab2_lib.baseboard_fab2(sch_1):page75_i18:vss(391)" )
			)
			( pin "U2D1.CP83"
				( objectStatus "@baseboard_fab2_lib.baseboard_fab2(sch_1):page75_i18:vss(392)" )
			)
			( pin "U2D1.CP81"
				( objectStatus "@baseboard_fab2_lib.baseboard_fab2(sch_1):page75_i18:vss(393)" )
			)
			( pin "U2D1.CP75"
				( objectStatus "@baseboard_fab2_lib.baseboard_fab2(sch_1):page75_i18:vss(394)" )
			)
			( pin "U2D1.CP73"
				( objectStatus "@baseboard_fab2_lib.baseboard_fab2(sch_1):page75_i18:vss(395)" )
			)
			( pin "U2D1.CP69"
				( objectStatus "@baseboard_fab2_lib.baseboard_fab2(sch_1):page75_i18:vss(396)" )
			)
			( pin "U2D1.CP59"
				( objectStatus "@baseboard_fab2_lib.baseboard_fab2(sch_1):page75_i18:vss(397)" )
			)
			( pin "U2D1.CP25"
				( objectStatus "@baseboard_fab2_lib.baseboard_fab2(sch_1):page75_i18:vss(398)" )
			)
			( pin "U2D1.H59"
				( objectStatus "@baseboard_fab2_lib.baseboard_fab2(sch_1):page75_i18:vss(399)" )
			)
			( pin "U2D1.CP1"
				( objectStatus "@baseboard_fab2_lib.baseboard_fab2(sch_1):page75_i18:vss(400)" )
			)
			( pin "U2D1.CN78"
				( objectStatus "@baseboard_fab2_lib.baseboard_fab2(sch_1):page75_i18:vss(401)" )
			)
			( pin "U2D1.CN68"
				( objectStatus "@baseboard_fab2_lib.baseboard_fab2(sch_1):page75_i18:vss(402)" )
			)
			( pin "U2D1.CN62"
				( objectStatus "@baseboard_fab2_lib.baseboard_fab2(sch_1):page75_i18:vss(403)" )
			)
			( pin "U2D1.CN60"
				( objectStatus "@baseboard_fab2_lib.baseboard_fab2(sch_1):page75_i18:vss(404)" )
			)
			( pin "U2D1.CN32"
				( objectStatus "@baseboard_fab2_lib.baseboard_fab2(sch_1):page75_i18:vss(405)" )
			)
			( pin "U2D1.CN26"
				( objectStatus "@baseboard_fab2_lib.baseboard_fab2(sch_1):page75_i18:vss(406)" )
			)
			( pin "U2D1.H61"
				( objectStatus "@baseboard_fab2_lib.baseboard_fab2(sch_1):page75_i18:vss(407)" )
			)
			( pin "U2D1.CN12"
				( objectStatus "@baseboard_fab2_lib.baseboard_fab2(sch_1):page75_i18:vss(408)" )
			)
			( pin "U2D1.CN2"
				( objectStatus "@baseboard_fab2_lib.baseboard_fab2(sch_1):page75_i18:vss(409)" )
			)
			( pin "U2D1.CM85"
				( objectStatus "@baseboard_fab2_lib.baseboard_fab2(sch_1):page75_i18:vss(410)" )
			)
			( pin "U2D1.CM83"
				( objectStatus "@baseboard_fab2_lib.baseboard_fab2(sch_1):page75_i18:vss(411)" )
			)
			( pin "U2D1.CM77"
				( objectStatus "@baseboard_fab2_lib.baseboard_fab2(sch_1):page75_i18:vss(412)" )
			)
			( pin "U2D1.CM73"
				( objectStatus "@baseboard_fab2_lib.baseboard_fab2(sch_1):page75_i18:vss(413)" )
			)
			( pin "U2D1.CM67"
				( objectStatus "@baseboard_fab2_lib.baseboard_fab2(sch_1):page75_i18:vss(414)" )
			)
			( pin "U2D1.CM63"
				( objectStatus "@baseboard_fab2_lib.baseboard_fab2(sch_1):page75_i18:vss(415)" )
			)
			( pin "U2D1.CM61"
				( objectStatus "@baseboard_fab2_lib.baseboard_fab2(sch_1):page75_i18:vss(416)" )
			)
			( pin "U2D1.CM31"
				( objectStatus "@baseboard_fab2_lib.baseboard_fab2(sch_1):page75_i18:vss(417)" )
			)
			( pin "U2D1.CM5"
				( objectStatus "@baseboard_fab2_lib.baseboard_fab2(sch_1):page75_i18:vss(418)" )
			)
			( pin "U2D1.CM29"
				( objectStatus "@baseboard_fab2_lib.baseboard_fab2(sch_1):page75_i18:vss(419)" )
			)
			( pin "U2D1.CM19"
				( objectStatus "@baseboard_fab2_lib.baseboard_fab2(sch_1):page75_i18:vss(420)" )
			)
			( pin "U2D1.CL80"
				( objectStatus "@baseboard_fab2_lib.baseboard_fab2(sch_1):page75_i18:vss(421)" )
			)
			( pin "U2D1.CL78"
				( objectStatus "@baseboard_fab2_lib.baseboard_fab2(sch_1):page75_i18:vss(422)" )
			)
			( pin "U2D1.CL76"
				( objectStatus "@baseboard_fab2_lib.baseboard_fab2(sch_1):page75_i18:vss(423)" )
			)
			( pin "U2D1.CL74"
				( objectStatus "@baseboard_fab2_lib.baseboard_fab2(sch_1):page75_i18:vss(424)" )
			)
			( pin "U2D1.CL66"
				( objectStatus "@baseboard_fab2_lib.baseboard_fab2(sch_1):page75_i18:vss(425)" )
			)
			( pin "U2D1.CL64"
				( objectStatus "@baseboard_fab2_lib.baseboard_fab2(sch_1):page75_i18:vss(426)" )
			)
			( pin "U2D1.CL62"
				( objectStatus "@baseboard_fab2_lib.baseboard_fab2(sch_1):page75_i18:vss(427)" )
			)
			( pin "U2D1.H63"
				( objectStatus "@baseboard_fab2_lib.baseboard_fab2(sch_1):page75_i18:vss(428)" )
			)
			( pin "U2D1.P45"
				( objectStatus "@baseboard_fab2_lib.baseboard_fab2(sch_1):page75_i18:vss(429)" )
			)
			( pin "U2D1.CL18"
				( objectStatus "@baseboard_fab2_lib.baseboard_fab2(sch_1):page75_i18:vss(430)" )
			)
			( pin "U2D1.CL14"
				( objectStatus "@baseboard_fab2_lib.baseboard_fab2(sch_1):page75_i18:vss(431)" )
			)
			( pin "U2D1.CL8"
				( objectStatus "@baseboard_fab2_lib.baseboard_fab2(sch_1):page75_i18:vss(432)" )
			)
			( pin "U2D1.CK85"
				( objectStatus "@baseboard_fab2_lib.baseboard_fab2(sch_1):page75_i18:vss(433)" )
			)
			( pin "U2D1.CK83"
				( objectStatus "@baseboard_fab2_lib.baseboard_fab2(sch_1):page75_i18:vss(434)" )
			)
			( pin "U2D1.CK75"
				( objectStatus "@baseboard_fab2_lib.baseboard_fab2(sch_1):page75_i18:vss(435)" )
			)
			( pin "U2D1.CK73"
				( objectStatus "@baseboard_fab2_lib.baseboard_fab2(sch_1):page75_i18:vss(436)" )
			)
			( pin "U2D1.CK71"
				( objectStatus "@baseboard_fab2_lib.baseboard_fab2(sch_1):page75_i18:vss(437)" )
			)
			( pin "U2D1.CK69"
				( objectStatus "@baseboard_fab2_lib.baseboard_fab2(sch_1):page75_i18:vss(438)" )
			)
			( pin "U2D1.CK67"
				( objectStatus "@baseboard_fab2_lib.baseboard_fab2(sch_1):page75_i18:vss(439)" )
			)
			( pin "U2D1.CK65"
				( objectStatus "@baseboard_fab2_lib.baseboard_fab2(sch_1):page75_i18:vss(440)" )
			)
			( pin "U2D1.CK63"
				( objectStatus "@baseboard_fab2_lib.baseboard_fab2(sch_1):page75_i18:vss(441)" )
			)
			( pin "U2D1.CK27"
				( objectStatus "@baseboard_fab2_lib.baseboard_fab2(sch_1):page75_i18:vss(442)" )
			)
			( pin "U2D1.CK21"
				( objectStatus "@baseboard_fab2_lib.baseboard_fab2(sch_1):page75_i18:vss(443)" )
			)
			( pin "U2D1.CK15"
				( objectStatus "@baseboard_fab2_lib.baseboard_fab2(sch_1):page75_i18:vss(444)" )
			)
			( pin "U2D1.CK11"
				( objectStatus "@baseboard_fab2_lib.baseboard_fab2(sch_1):page75_i18:vss(445)" )
			)
			( pin "U2D1.CJ86"
				( objectStatus "@baseboard_fab2_lib.baseboard_fab2(sch_1):page75_i18:vss(446)" )
			)
			( pin "U2D1.CJ84"
				( objectStatus "@baseboard_fab2_lib.baseboard_fab2(sch_1):page75_i18:vss(447)" )
			)
			( pin "U2D1.CJ82"
				( objectStatus "@baseboard_fab2_lib.baseboard_fab2(sch_1):page75_i18:vss(448)" )
			)
			( pin "U2D1.CJ78"
				( objectStatus "@baseboard_fab2_lib.baseboard_fab2(sch_1):page75_i18:vss(449)" )
			)
			( pin "U2D1.CJ76"
				( objectStatus "@baseboard_fab2_lib.baseboard_fab2(sch_1):page75_i18:vss(450)" )
			)
			( pin "U2D1.CJ74"
				( objectStatus "@baseboard_fab2_lib.baseboard_fab2(sch_1):page75_i18:vss(451)" )
			)
			( pin "U2D1.CJ62"
				( objectStatus "@baseboard_fab2_lib.baseboard_fab2(sch_1):page75_i18:vss(452)" )
			)
			( pin "U2D1.P47"
				( objectStatus "@baseboard_fab2_lib.baseboard_fab2(sch_1):page75_i18:vss(453)" )
			)
			( pin "U2D1.DN72"
				( objectStatus "@baseboard_fab2_lib.baseboard_fab2(sch_1):page75_i19:vss(134)" )
			)
			( pin "U2D1.DN68"
				( objectStatus "@baseboard_fab2_lib.baseboard_fab2(sch_1):page75_i19:vss(135)" )
			)
			( pin "U2D1.DN38"
				( objectStatus "@baseboard_fab2_lib.baseboard_fab2(sch_1):page75_i19:vss(136)" )
			)
			( pin "U2D1.DN32"
				( objectStatus "@baseboard_fab2_lib.baseboard_fab2(sch_1):page75_i19:vss(137)" )
			)
			( pin "U2D1.DN26"
				( objectStatus "@baseboard_fab2_lib.baseboard_fab2(sch_1):page75_i19:vss(138)" )
			)
			( pin "U2D1.DN22"
				( objectStatus "@baseboard_fab2_lib.baseboard_fab2(sch_1):page75_i19:vss(139)" )
			)
			( pin "U2D1.DN12"
				( objectStatus "@baseboard_fab2_lib.baseboard_fab2(sch_1):page75_i19:vss(140)" )
			)
			( pin "U2D1.BH17"
				( objectStatus "@baseboard_fab2_lib.baseboard_fab2(sch_1):page75_i19:vss(141)" )
			)
			( pin "U2D1.DN2"
				( objectStatus "@baseboard_fab2_lib.baseboard_fab2(sch_1):page75_i19:vss(142)" )
			)
			( pin "U2D1.DM83"
				( objectStatus "@baseboard_fab2_lib.baseboard_fab2(sch_1):page75_i19:vss(143)" )
			)
			( pin "U2D1.DM77"
				( objectStatus "@baseboard_fab2_lib.baseboard_fab2(sch_1):page75_i19:vss(144)" )
			)
			( pin "U2D1.DM73"
				( objectStatus "@baseboard_fab2_lib.baseboard_fab2(sch_1):page75_i19:vss(145)" )
			)
			( pin "U2D1.DM65"
				( objectStatus "@baseboard_fab2_lib.baseboard_fab2(sch_1):page75_i19:vss(146)" )
			)
			( pin "U2D1.DM39"
				( objectStatus "@baseboard_fab2_lib.baseboard_fab2(sch_1):page75_i19:vss(147)" )
			)
			( pin "U2D1.DM37"
				( objectStatus "@baseboard_fab2_lib.baseboard_fab2(sch_1):page75_i19:vss(148)" )
			)
			( pin "U2D1.DM33"
				( objectStatus "@baseboard_fab2_lib.baseboard_fab2(sch_1):page75_i19:vss(149)" )
			)
			( pin "U2D1.DM31"
				( objectStatus "@baseboard_fab2_lib.baseboard_fab2(sch_1):page75_i19:vss(150)" )
			)
			( pin "U2D1.DM27"
				( objectStatus "@baseboard_fab2_lib.baseboard_fab2(sch_1):page75_i19:vss(151)" )
			)
			( pin "U2D1.DM25"
				( objectStatus "@baseboard_fab2_lib.baseboard_fab2(sch_1):page75_i19:vss(152)" )
			)
			( pin "U2D1.H45"
				( objectStatus "@baseboard_fab2_lib.baseboard_fab2(sch_1):page75_i19:vss(153)" )
			)
			( pin "U2D1.DM15"
				( objectStatus "@baseboard_fab2_lib.baseboard_fab2(sch_1):page75_i19:vss(154)" )
			)
			( pin "U2D1.DL80"
				( objectStatus "@baseboard_fab2_lib.baseboard_fab2(sch_1):page75_i19:vss(155)" )
			)
			( pin "U2D1.DL78"
				( objectStatus "@baseboard_fab2_lib.baseboard_fab2(sch_1):page75_i19:vss(156)" )
			)
			( pin "U2D1.DL76"
				( objectStatus "@baseboard_fab2_lib.baseboard_fab2(sch_1):page75_i19:vss(157)" )
			)
			( pin "U2D1.DL74"
				( objectStatus "@baseboard_fab2_lib.baseboard_fab2(sch_1):page75_i19:vss(158)" )
			)
			( pin "U2D1.DL70"
				( objectStatus "@baseboard_fab2_lib.baseboard_fab2(sch_1):page75_i19:vss(159)" )
			)
			( pin "U2D1.DL68"
				( objectStatus "@baseboard_fab2_lib.baseboard_fab2(sch_1):page75_i19:vss(160)" )
			)
			( pin "U2D1.DL40"
				( objectStatus "@baseboard_fab2_lib.baseboard_fab2(sch_1):page75_i19:vss(161)" )
			)
			( pin "U2D1.DL36"
				( objectStatus "@baseboard_fab2_lib.baseboard_fab2(sch_1):page75_i19:vss(162)" )
			)
			( pin "U2D1.DL34"
				( objectStatus "@baseboard_fab2_lib.baseboard_fab2(sch_1):page75_i19:vss(163)" )
			)
			( pin "U2D1.DL30"
				( objectStatus "@baseboard_fab2_lib.baseboard_fab2(sch_1):page75_i19:vss(164)" )
			)
			( pin "U2D1.DL28"
				( objectStatus "@baseboard_fab2_lib.baseboard_fab2(sch_1):page75_i19:vss(165)" )
			)
			( pin "U2D1.DL24"
				( objectStatus "@baseboard_fab2_lib.baseboard_fab2(sch_1):page75_i19:vss(166)" )
			)
			( pin "U2D1.DL22"
				( objectStatus "@baseboard_fab2_lib.baseboard_fab2(sch_1):page75_i19:vss(167)" )
			)
			( pin "U2D1.DL4"
				( objectStatus "@baseboard_fab2_lib.baseboard_fab2(sch_1):page75_i19:vss(168)" )
			)
			( pin "U2D1.DL18"
				( objectStatus "@baseboard_fab2_lib.baseboard_fab2(sch_1):page75_i19:vss(169)" )
			)
			( pin "U2D1.DL16"
				( objectStatus "@baseboard_fab2_lib.baseboard_fab2(sch_1):page75_i19:vss(170)" )
			)
			( pin "U2D1.DK85"
				( objectStatus "@baseboard_fab2_lib.baseboard_fab2(sch_1):page75_i19:vss(171)" )
			)
			( pin "U2D1.DK83"
				( objectStatus "@baseboard_fab2_lib.baseboard_fab2(sch_1):page75_i19:vss(172)" )
			)
			( pin "U2D1.DK77"
				( objectStatus "@baseboard_fab2_lib.baseboard_fab2(sch_1):page75_i19:vss(173)" )
			)
			( pin "U2D1.DK75"
				( objectStatus "@baseboard_fab2_lib.baseboard_fab2(sch_1):page75_i19:vss(174)" )
			)
			( pin "U2D1.DK73"
				( objectStatus "@baseboard_fab2_lib.baseboard_fab2(sch_1):page75_i19:vss(175)" )
			)
			( pin "U2D1.DK41"
				( objectStatus "@baseboard_fab2_lib.baseboard_fab2(sch_1):page75_i19:vss(176)" )
			)
			( pin "U2D1.DK39"
				( objectStatus "@baseboard_fab2_lib.baseboard_fab2(sch_1):page75_i19:vss(177)" )
			)
			( pin "U2D1.DK35"
				( objectStatus "@baseboard_fab2_lib.baseboard_fab2(sch_1):page75_i19:vss(178)" )
			)
			( pin "U2D1.DK29"
				( objectStatus "@baseboard_fab2_lib.baseboard_fab2(sch_1):page75_i19:vss(179)" )
			)
			( pin "U2D1.DK23"
				( objectStatus "@baseboard_fab2_lib.baseboard_fab2(sch_1):page75_i19:vss(180)" )
			)
			( pin "U2D1.DK7"
				( objectStatus "@baseboard_fab2_lib.baseboard_fab2(sch_1):page75_i19:vss(181)" )
			)
			( pin "U2D1.DJ84"
				( objectStatus "@baseboard_fab2_lib.baseboard_fab2(sch_1):page75_i19:vss(182)" )
			)
			( pin "U2D1.DJ82"
				( objectStatus "@baseboard_fab2_lib.baseboard_fab2(sch_1):page75_i19:vss(183)" )
			)
			( pin "U2D1.DJ78"
				( objectStatus "@baseboard_fab2_lib.baseboard_fab2(sch_1):page75_i19:vss(184)" )
			)
			( pin "U2D1.DJ74"
				( objectStatus "@baseboard_fab2_lib.baseboard_fab2(sch_1):page75_i19:vss(185)" )
			)
			( pin "U2D1.DJ68"
				( objectStatus "@baseboard_fab2_lib.baseboard_fab2(sch_1):page75_i19:vss(186)" )
			)
			( pin "U2D1.DJ42"
				( objectStatus "@baseboard_fab2_lib.baseboard_fab2(sch_1):page75_i19:vss(187)" )
			)
			( pin "U2D1.DJ38"
				( objectStatus "@baseboard_fab2_lib.baseboard_fab2(sch_1):page75_i19:vss(188)" )
			)
			( pin "U2D1.DJ22"
				( objectStatus "@baseboard_fab2_lib.baseboard_fab2(sch_1):page75_i19:vss(189)" )
			)
			( pin "U2D1.H47"
				( objectStatus "@baseboard_fab2_lib.baseboard_fab2(sch_1):page75_i19:vss(190)" )
			)
			( pin "U2D1.DJ10"
				( objectStatus "@baseboard_fab2_lib.baseboard_fab2(sch_1):page75_i19:vss(191)" )
			)
			( pin "U2D1.DJ2"
				( objectStatus "@baseboard_fab2_lib.baseboard_fab2(sch_1):page75_i19:vss(192)" )
			)
			( pin "U2D1.DH83"
				( objectStatus "@baseboard_fab2_lib.baseboard_fab2(sch_1):page75_i19:vss(193)" )
			)
			( pin "U2D1.DH81"
				( objectStatus "@baseboard_fab2_lib.baseboard_fab2(sch_1):page75_i19:vss(194)" )
			)
			( pin "U2D1.DH79"
				( objectStatus "@baseboard_fab2_lib.baseboard_fab2(sch_1):page75_i19:vss(195)" )
			)
			( pin "U2D1.DH73"
				( objectStatus "@baseboard_fab2_lib.baseboard_fab2(sch_1):page75_i19:vss(196)" )
			)
			( pin "U2D1.DH71"
				( objectStatus "@baseboard_fab2_lib.baseboard_fab2(sch_1):page75_i19:vss(197)" )
			)
			( pin "U2D1.DH67"
				( objectStatus "@baseboard_fab2_lib.baseboard_fab2(sch_1):page75_i19:vss(198)" )
			)
			( pin "U2D1.DH41"
				( objectStatus "@baseboard_fab2_lib.baseboard_fab2(sch_1):page75_i19:vss(199)" )
			)
			( pin "U2D1.DH37"
				( objectStatus "@baseboard_fab2_lib.baseboard_fab2(sch_1):page75_i19:vss(200)" )
			)
			( pin "U2D1.DH35"
				( objectStatus "@baseboard_fab2_lib.baseboard_fab2(sch_1):page75_i19:vss(201)" )
			)
			( pin "U2D1.DH33"
				( objectStatus "@baseboard_fab2_lib.baseboard_fab2(sch_1):page75_i19:vss(202)" )
			)
			( pin "U2D1.DH31"
				( objectStatus "@baseboard_fab2_lib.baseboard_fab2(sch_1):page75_i19:vss(203)" )
			)
			( pin "U2D1.DH29"
				( objectStatus "@baseboard_fab2_lib.baseboard_fab2(sch_1):page75_i19:vss(204)" )
			)
			( pin "U2D1.DH27"
				( objectStatus "@baseboard_fab2_lib.baseboard_fab2(sch_1):page75_i19:vss(205)" )
			)
			( pin "U2D1.DH25"
				( objectStatus "@baseboard_fab2_lib.baseboard_fab2(sch_1):page75_i19:vss(206)" )
			)
			( pin "U2D1.DH23"
				( objectStatus "@baseboard_fab2_lib.baseboard_fab2(sch_1):page75_i19:vss(207)" )
			)
			( pin "U2D1.DH15"
				( objectStatus "@baseboard_fab2_lib.baseboard_fab2(sch_1):page75_i19:vss(208)" )
			)
			( pin "U2D1.DH13"
				( objectStatus "@baseboard_fab2_lib.baseboard_fab2(sch_1):page75_i19:vss(209)" )
			)
			( pin "U2D1.DG82"
				( objectStatus "@baseboard_fab2_lib.baseboard_fab2(sch_1):page75_i19:vss(210)" )
			)
			( pin "U2D1.DG80"
				( objectStatus "@baseboard_fab2_lib.baseboard_fab2(sch_1):page75_i19:vss(211)" )
			)
			( pin "U2D1.DG78"
				( objectStatus "@baseboard_fab2_lib.baseboard_fab2(sch_1):page75_i19:vss(212)" )
			)
			( pin "U2D1.DG76"
				( objectStatus "@baseboard_fab2_lib.baseboard_fab2(sch_1):page75_i19:vss(213)" )
			)
			( pin "U2D1.DG68"
				( objectStatus "@baseboard_fab2_lib.baseboard_fab2(sch_1):page75_i19:vss(214)" )
			)
			( pin "U2D1.DG66"
				( objectStatus "@baseboard_fab2_lib.baseboard_fab2(sch_1):page75_i19:vss(215)" )
			)
			( pin "U2D1.DG24"
				( objectStatus "@baseboard_fab2_lib.baseboard_fab2(sch_1):page75_i19:vss(216)" )
			)
			( pin "U2D1.DG16"
				( objectStatus "@baseboard_fab2_lib.baseboard_fab2(sch_1):page75_i19:vss(217)" )
			)
			( pin "U2D1.DG14"
				( objectStatus "@baseboard_fab2_lib.baseboard_fab2(sch_1):page75_i19:vss(218)" )
			)
			( pin "U2D1.H49"
				( objectStatus "@baseboard_fab2_lib.baseboard_fab2(sch_1):page75_i19:vss(219)" )
			)
			( pin "U2D1.DG2"
				( objectStatus "@baseboard_fab2_lib.baseboard_fab2(sch_1):page75_i19:vss(220)" )
			)
			( pin "U2D1.DF85"
				( objectStatus "@baseboard_fab2_lib.baseboard_fab2(sch_1):page75_i19:vss(221)" )
			)
			( pin "U2D1.DF83"
				( objectStatus "@baseboard_fab2_lib.baseboard_fab2(sch_1):page75_i19:vss(222)" )
			)
			( pin "U2D1.DF79"
				( objectStatus "@baseboard_fab2_lib.baseboard_fab2(sch_1):page75_i19:vss(223)" )
			)
			( pin "U2D1.DF73"
				( objectStatus "@baseboard_fab2_lib.baseboard_fab2(sch_1):page75_i19:vss(224)" )
			)
			( pin "U2D1.DF69"
				( objectStatus "@baseboard_fab2_lib.baseboard_fab2(sch_1):page75_i19:vss(225)" )
			)
			( pin "U2D1.DF65"
				( objectStatus "@baseboard_fab2_lib.baseboard_fab2(sch_1):page75_i19:vss(226)" )
			)
			( pin "U2D1.DF41"
				( objectStatus "@baseboard_fab2_lib.baseboard_fab2(sch_1):page75_i19:vss(227)" )
			)
			( pin "U2D1.DF39"
				( objectStatus "@baseboard_fab2_lib.baseboard_fab2(sch_1):page75_i19:vss(228)" )
			)
			( pin "U2D1.DF37"
				( objectStatus "@baseboard_fab2_lib.baseboard_fab2(sch_1):page75_i19:vss(229)" )
			)
			( pin "U2D1.DF35"
				( objectStatus "@baseboard_fab2_lib.baseboard_fab2(sch_1):page75_i19:vss(230)" )
			)
			( pin "U2D1.DF29"
				( objectStatus "@baseboard_fab2_lib.baseboard_fab2(sch_1):page75_i19:vss(231)" )
			)
			( pin "U2D1.DF19"
				( objectStatus "@baseboard_fab2_lib.baseboard_fab2(sch_1):page75_i19:vss(232)" )
			)
			( pin "U2D1.H51"
				( objectStatus "@baseboard_fab2_lib.baseboard_fab2(sch_1):page75_i19:vss(233)" )
			)
			( pin "U2D1.DF7"
				( objectStatus "@baseboard_fab2_lib.baseboard_fab2(sch_1):page75_i19:vss(234)" )
			)
			( pin "U2D1.DF5"
				( objectStatus "@baseboard_fab2_lib.baseboard_fab2(sch_1):page75_i19:vss(235)" )
			)
			( pin "U2D1.DE78"
				( objectStatus "@baseboard_fab2_lib.baseboard_fab2(sch_1):page75_i19:vss(236)" )
			)
			( pin "U2D1.DE72"
				( objectStatus "@baseboard_fab2_lib.baseboard_fab2(sch_1):page75_i19:vss(237)" )
			)
			( pin "U2D1.DE70"
				( objectStatus "@baseboard_fab2_lib.baseboard_fab2(sch_1):page75_i19:vss(238)" )
			)
			( pin "U2D1.DE64"
				( objectStatus "@baseboard_fab2_lib.baseboard_fab2(sch_1):page75_i19:vss(239)" )
			)
			( pin "U2D1.DE36"
				( objectStatus "@baseboard_fab2_lib.baseboard_fab2(sch_1):page75_i19:vss(240)" )
			)
			( pin "U2D1.DE34"
				( objectStatus "@baseboard_fab2_lib.baseboard_fab2(sch_1):page75_i19:vss(241)" )
			)
			( pin "U2D1.DE30"
				( objectStatus "@baseboard_fab2_lib.baseboard_fab2(sch_1):page75_i19:vss(242)" )
			)
			( pin "U2D1.DE28"
				( objectStatus "@baseboard_fab2_lib.baseboard_fab2(sch_1):page75_i19:vss(243)" )
			)
			( pin "U2D1.DE24"
				( objectStatus "@baseboard_fab2_lib.baseboard_fab2(sch_1):page75_i19:vss(244)" )
			)
			( pin "U2D1.DE20"
				( objectStatus "@baseboard_fab2_lib.baseboard_fab2(sch_1):page75_i19:vss(245)" )
			)
			( pin "U2D1.DE18"
				( objectStatus "@baseboard_fab2_lib.baseboard_fab2(sch_1):page75_i19:vss(246)" )
			)
			( pin "U2D1.DE8"
				( objectStatus "@baseboard_fab2_lib.baseboard_fab2(sch_1):page75_i19:vss(247)" )
			)
			( pin "U2D1.DE6"
				( objectStatus "@baseboard_fab2_lib.baseboard_fab2(sch_1):page75_i19:vss(248)" )
			)
			( pin "U2D1.DD83"
				( objectStatus "@baseboard_fab2_lib.baseboard_fab2(sch_1):page75_i19:vss(249)" )
			)
			( pin "U2D1.DD81"
				( objectStatus "@baseboard_fab2_lib.baseboard_fab2(sch_1):page75_i19:vss(250)" )
			)
			( pin "U2D1.DD75"
				( objectStatus "@baseboard_fab2_lib.baseboard_fab2(sch_1):page75_i19:vss(251)" )
			)
			( pin "U2D1.DD73"
				( objectStatus "@baseboard_fab2_lib.baseboard_fab2(sch_1):page75_i19:vss(252)" )
			)
			( pin "U2D1.DD71"
				( objectStatus "@baseboard_fab2_lib.baseboard_fab2(sch_1):page75_i19:vss(253)" )
			)
			( pin "U2D1.DD37"
				( objectStatus "@baseboard_fab2_lib.baseboard_fab2(sch_1):page75_i19:vss(254)" )
			)
			( pin "U2D1.DD33"
				( objectStatus "@baseboard_fab2_lib.baseboard_fab2(sch_1):page75_i19:vss(255)" )
			)
			( pin "U2D1.DD31"
				( objectStatus "@baseboard_fab2_lib.baseboard_fab2(sch_1):page75_i19:vss(256)" )
			)
			( pin "U2D1.DD27"
				( objectStatus "@baseboard_fab2_lib.baseboard_fab2(sch_1):page75_i19:vss(257)" )
			)
			( pin "U2D1.DD23"
				( objectStatus "@baseboard_fab2_lib.baseboard_fab2(sch_1):page75_i19:vss(258)" )
			)
			( pin "U2D1.DD11"
				( objectStatus "@baseboard_fab2_lib.baseboard_fab2(sch_1):page75_i19:vss(259)" )
			)
			( pin "U2D1.DC86"
				( objectStatus "@baseboard_fab2_lib.baseboard_fab2(sch_1):page75_i19:vss(260)" )
			)
			( pin "U2D1.DC84"
				( objectStatus "@baseboard_fab2_lib.baseboard_fab2(sch_1):page75_i19:vss(261)" )
			)
			( pin "U2D1.DC78"
				( objectStatus "@baseboard_fab2_lib.baseboard_fab2(sch_1):page75_i19:vss(262)" )
			)
			( pin "U2D1.DC70"
				( objectStatus "@baseboard_fab2_lib.baseboard_fab2(sch_1):page75_i19:vss(263)" )
			)
			( pin "U2D1.DC68"
				( objectStatus "@baseboard_fab2_lib.baseboard_fab2(sch_1):page75_i19:vss(264)" )
			)
			( pin "U2D1.DC66"
				( objectStatus "@baseboard_fab2_lib.baseboard_fab2(sch_1):page75_i19:vss(265)" )
			)
			( pin "U2D1.DC64"
				( objectStatus "@baseboard_fab2_lib.baseboard_fab2(sch_1):page75_i19:vss(266)" )
			)
			( pin "U2D1.DC42"
				( objectStatus "@baseboard_fab2_lib.baseboard_fab2(sch_1):page75_i19:vss(267)" )
			)
			( pin "U2D1.DC38"
				( objectStatus "@baseboard_fab2_lib.baseboard_fab2(sch_1):page75_i19:vss(268)" )
			)
			( pin "U2D1.DC32"
				( objectStatus "@baseboard_fab2_lib.baseboard_fab2(sch_1):page75_i19:vss(269)" )
			)
			( pin "U2D1.DC26"
				( objectStatus "@baseboard_fab2_lib.baseboard_fab2(sch_1):page75_i19:vss(270)" )
			)
			( pin "U2D1.DC24"
				( objectStatus "@baseboard_fab2_lib.baseboard_fab2(sch_1):page75_i19:vss(271)" )
			)
			( pin "U2D1.DC14"
				( objectStatus "@baseboard_fab2_lib.baseboard_fab2(sch_1):page75_i19:vss(272)" )
			)
			( pin "U2D1.DB85"
				( objectStatus "@baseboard_fab2_lib.baseboard_fab2(sch_1):page75_i19:vss(273)" )
			)
			( pin "U2D1.DB83"
				( objectStatus "@baseboard_fab2_lib.baseboard_fab2(sch_1):page75_i19:vss(274)" )
			)
			( pin "U2D1.DB77"
				( objectStatus "@baseboard_fab2_lib.baseboard_fab2(sch_1):page75_i19:vss(275)" )
			)
			( pin "U2D1.DB73"
				( objectStatus "@baseboard_fab2_lib.baseboard_fab2(sch_1):page75_i19:vss(276)" )
			)
			( pin "U2D1.DB49"
				( objectStatus "@baseboard_fab2_lib.baseboard_fab2(sch_1):page75_i19:vss(277)" )
			)
			( pin "U2D1.DB47"
				( objectStatus "@baseboard_fab2_lib.baseboard_fab2(sch_1):page75_i19:vss(278)" )
			)
			( pin "U2D1.DB41"
				( objectStatus "@baseboard_fab2_lib.baseboard_fab2(sch_1):page75_i19:vss(279)" )
			)
			( pin "U2D1.DB39"
				( objectStatus "@baseboard_fab2_lib.baseboard_fab2(sch_1):page75_i19:vss(280)" )
			)
			( pin "U2D1.DB25"
				( objectStatus "@baseboard_fab2_lib.baseboard_fab2(sch_1):page75_i19:vss(281)" )
			)
			( pin "U2D1.DB23"
				( objectStatus "@baseboard_fab2_lib.baseboard_fab2(sch_1):page75_i19:vss(282)" )
			)
			( pin "U2D1.DB17"
				( objectStatus "@baseboard_fab2_lib.baseboard_fab2(sch_1):page75_i19:vss(283)" )
			)
			( pin "U2D1.DB13"
				( objectStatus "@baseboard_fab2_lib.baseboard_fab2(sch_1):page75_i19:vss(284)" )
			)
			( pin "U2D1.DB3"
				( objectStatus "@baseboard_fab2_lib.baseboard_fab2(sch_1):page75_i19:vss(285)" )
			)
			( pin "U2D1.DA80"
				( objectStatus "@baseboard_fab2_lib.baseboard_fab2(sch_1):page75_i19:vss(286)" )
			)
			( pin "U2D1.DA78"
				( objectStatus "@baseboard_fab2_lib.baseboard_fab2(sch_1):page75_i19:vss(287)" )
			)
			( pin "U2D1.DA76"
				( objectStatus "@baseboard_fab2_lib.baseboard_fab2(sch_1):page75_i19:vss(288)" )
			)
			( pin "U2D1.DA74"
				( objectStatus "@baseboard_fab2_lib.baseboard_fab2(sch_1):page75_i19:vss(289)" )
			)
			( pin "U2D1.DA70"
				( objectStatus "@baseboard_fab2_lib.baseboard_fab2(sch_1):page75_i19:vss(290)" )
			)
			( pin "U2D1.DA64"
				( objectStatus "@baseboard_fab2_lib.baseboard_fab2(sch_1):page75_i19:vss(291)" )
			)
			( pin "U2D1.DA50"
				( objectStatus "@baseboard_fab2_lib.baseboard_fab2(sch_1):page75_i19:vss(292)" )
			)
			( pin "U2D1.DA48"
				( objectStatus "@baseboard_fab2_lib.baseboard_fab2(sch_1):page75_i19:vss(293)" )
			)
			( pin "U2D1.EF79"
				( objectStatus "@baseboard_fab2_lib.baseboard_fab2(sch_1):page75_i20:vss(0)" )
			)
			( pin "U2D1.EF75"
				( objectStatus "@baseboard_fab2_lib.baseboard_fab2(sch_1):page75_i20:vss(1)" )
			)
			( pin "U2D1.EF71"
				( objectStatus "@baseboard_fab2_lib.baseboard_fab2(sch_1):page75_i20:vss(2)" )
			)
			( pin "U2D1.EE78"
				( objectStatus "@baseboard_fab2_lib.baseboard_fab2(sch_1):page75_i20:vss(3)" )
			)
			( pin "U2D1.EE76"
				( objectStatus "@baseboard_fab2_lib.baseboard_fab2(sch_1):page75_i20:vss(4)" )
			)
			( pin "U2D1.EE70"
				( objectStatus "@baseboard_fab2_lib.baseboard_fab2(sch_1):page75_i20:vss(5)" )
			)
			( pin "U2D1.EE36"
				( objectStatus "@baseboard_fab2_lib.baseboard_fab2(sch_1):page75_i20:vss(6)" )
			)
			( pin "U2D1.EE34"
				( objectStatus "@baseboard_fab2_lib.baseboard_fab2(sch_1):page75_i20:vss(7)" )
			)
			( pin "U2D1.EE30"
				( objectStatus "@baseboard_fab2_lib.baseboard_fab2(sch_1):page75_i20:vss(8)" )
			)
			( pin "U2D1.EE28"
				( objectStatus "@baseboard_fab2_lib.baseboard_fab2(sch_1):page75_i20:vss(9)" )
			)
			( pin "U2D1.EE24"
				( objectStatus "@baseboard_fab2_lib.baseboard_fab2(sch_1):page75_i20:vss(10)" )
			)
			( pin "U2D1.ED77"
				( objectStatus "@baseboard_fab2_lib.baseboard_fab2(sch_1):page75_i20:vss(11)" )
			)
			( pin "U2D1.ED35"
				( objectStatus "@baseboard_fab2_lib.baseboard_fab2(sch_1):page75_i20:vss(12)" )
			)
			( pin "U2D1.ED29"
				( objectStatus "@baseboard_fab2_lib.baseboard_fab2(sch_1):page75_i20:vss(13)" )
			)
			( pin "U2D1.ED23"
				( objectStatus "@baseboard_fab2_lib.baseboard_fab2(sch_1):page75_i20:vss(14)" )
			)
			( pin "U2D1.ED15"
				( objectStatus "@baseboard_fab2_lib.baseboard_fab2(sch_1):page75_i20:vss(15)" )
			)
			( pin "U2D1.ED11"
				( objectStatus "@baseboard_fab2_lib.baseboard_fab2(sch_1):page75_i20:vss(16)" )
			)
			( pin "U2D1.EC76"
				( objectStatus "@baseboard_fab2_lib.baseboard_fab2(sch_1):page75_i20:vss(17)" )
			)
			( pin "U2D1.EC74"
				( objectStatus "@baseboard_fab2_lib.baseboard_fab2(sch_1):page75_i20:vss(18)" )
			)
			( pin "U2D1.EC72"
				( objectStatus "@baseboard_fab2_lib.baseboard_fab2(sch_1):page75_i20:vss(19)" )
			)
			( pin "U2D1.EC70"
				( objectStatus "@baseboard_fab2_lib.baseboard_fab2(sch_1):page75_i20:vss(20)" )
			)
			( pin "U2D1.EC10"
				( objectStatus "@baseboard_fab2_lib.baseboard_fab2(sch_1):page75_i20:vss(21)" )
			)
			( pin "U2D1.EB69"
				( objectStatus "@baseboard_fab2_lib.baseboard_fab2(sch_1):page75_i20:vss(22)" )
			)
			( pin "U2D1.EB65"
				( objectStatus "@baseboard_fab2_lib.baseboard_fab2(sch_1):page75_i20:vss(23)" )
			)
			( pin "U2D1.EB41"
				( objectStatus "@baseboard_fab2_lib.baseboard_fab2(sch_1):page75_i20:vss(24)" )
			)
			( pin "U2D1.EB39"
				( objectStatus "@baseboard_fab2_lib.baseboard_fab2(sch_1):page75_i20:vss(25)" )
			)
			( pin "U2D1.EB37"
				( objectStatus "@baseboard_fab2_lib.baseboard_fab2(sch_1):page75_i20:vss(26)" )
			)
			( pin "U2D1.EB35"
				( objectStatus "@baseboard_fab2_lib.baseboard_fab2(sch_1):page75_i20:vss(27)" )
			)
			( pin "U2D1.EB33"
				( objectStatus "@baseboard_fab2_lib.baseboard_fab2(sch_1):page75_i20:vss(28)" )
			)
			( pin "U2D1.EB31"
				( objectStatus "@baseboard_fab2_lib.baseboard_fab2(sch_1):page75_i20:vss(29)" )
			)
			( pin "U2D1.EB29"
				( objectStatus "@baseboard_fab2_lib.baseboard_fab2(sch_1):page75_i20:vss(30)" )
			)
			( pin "U2D1.EB27"
				( objectStatus "@baseboard_fab2_lib.baseboard_fab2(sch_1):page75_i20:vss(31)" )
			)
			( pin "U2D1.EB25"
				( objectStatus "@baseboard_fab2_lib.baseboard_fab2(sch_1):page75_i20:vss(32)" )
			)
			( pin "U2D1.EB23"
				( objectStatus "@baseboard_fab2_lib.baseboard_fab2(sch_1):page75_i20:vss(33)" )
			)
			( pin "U2D1.BR18"
				( objectStatus "@baseboard_fab2_lib.baseboard_fab2(sch_1):page75_i20:vss(34)" )
			)
			( pin "U2D1.EB13"
				( objectStatus "@baseboard_fab2_lib.baseboard_fab2(sch_1):page75_i20:vss(35)" )
			)
			( pin "U2D1.EA82"
				( objectStatus "@baseboard_fab2_lib.baseboard_fab2(sch_1):page75_i20:vss(36)" )
			)
			( pin "U2D1.EA80"
				( objectStatus "@baseboard_fab2_lib.baseboard_fab2(sch_1):page75_i20:vss(37)" )
			)
			( pin "U2D1.EA78"
				( objectStatus "@baseboard_fab2_lib.baseboard_fab2(sch_1):page75_i20:vss(38)" )
			)
			( pin "U2D1.EA76"
				( objectStatus "@baseboard_fab2_lib.baseboard_fab2(sch_1):page75_i20:vss(39)" )
			)
			( pin "U2D1.EA70"
				( objectStatus "@baseboard_fab2_lib.baseboard_fab2(sch_1):page75_i20:vss(40)" )
			)
			( pin "U2D1.EA64"
				( objectStatus "@baseboard_fab2_lib.baseboard_fab2(sch_1):page75_i20:vss(41)" )
			)
			( pin "U2D1.EA42"
				( objectStatus "@baseboard_fab2_lib.baseboard_fab2(sch_1):page75_i20:vss(42)" )
			)
			( pin "U2D1.EA22"
				( objectStatus "@baseboard_fab2_lib.baseboard_fab2(sch_1):page75_i20:vss(43)" )
			)
			( pin "U2D1.EA20"
				( objectStatus "@baseboard_fab2_lib.baseboard_fab2(sch_1):page75_i20:vss(44)" )
			)
			( pin "U2D1.EA16"
				( objectStatus "@baseboard_fab2_lib.baseboard_fab2(sch_1):page75_i20:vss(45)" )
			)
			( pin "U2D1.J16"
				( objectStatus "@baseboard_fab2_lib.baseboard_fab2(sch_1):page75_i20:vss(46)" )
			)
			( pin "U2D1.EA6"
				( objectStatus "@baseboard_fab2_lib.baseboard_fab2(sch_1):page75_i20:vss(47)" )
			)
			( pin "U2D1.DY75"
				( objectStatus "@baseboard_fab2_lib.baseboard_fab2(sch_1):page75_i20:vss(48)" )
			)
			( pin "U2D1.DY71"
				( objectStatus "@baseboard_fab2_lib.baseboard_fab2(sch_1):page75_i20:vss(49)" )
			)
			( pin "U2D1.DY41"
				( objectStatus "@baseboard_fab2_lib.baseboard_fab2(sch_1):page75_i20:vss(50)" )
			)
			( pin "U2D1.DY35"
				( objectStatus "@baseboard_fab2_lib.baseboard_fab2(sch_1):page75_i20:vss(51)" )
			)
			( pin "U2D1.DY29"
				( objectStatus "@baseboard_fab2_lib.baseboard_fab2(sch_1):page75_i20:vss(52)" )
			)
			( pin "U2D1.DY23"
				( objectStatus "@baseboard_fab2_lib.baseboard_fab2(sch_1):page75_i20:vss(53)" )
			)
			( pin "U2D1.DY19"
				( objectStatus "@baseboard_fab2_lib.baseboard_fab2(sch_1):page75_i20:vss(54)" )
			)
			( pin "U2D1.DY5"
				( objectStatus "@baseboard_fab2_lib.baseboard_fab2(sch_1):page75_i20:vss(55)" )
			)
			( pin "U2D1.DW84"
				( objectStatus "@baseboard_fab2_lib.baseboard_fab2(sch_1):page75_i20:vss(56)" )
			)
			( pin "U2D1.DW82"
				( objectStatus "@baseboard_fab2_lib.baseboard_fab2(sch_1):page75_i20:vss(57)" )
			)
			( pin "U2D1.DW8"
				( objectStatus "@baseboard_fab2_lib.baseboard_fab2(sch_1):page75_i20:vss(58)" )
			)
			( pin "U2D1.DW76"
				( objectStatus "@baseboard_fab2_lib.baseboard_fab2(sch_1):page75_i20:vss(59)" )
			)
			( pin "U2D1.DW74"
				( objectStatus "@baseboard_fab2_lib.baseboard_fab2(sch_1):page75_i20:vss(60)" )
			)
			( pin "U2D1.DW72"
				( objectStatus "@baseboard_fab2_lib.baseboard_fab2(sch_1):page75_i20:vss(61)" )
			)
			( pin "U2D1.DW70"
				( objectStatus "@baseboard_fab2_lib.baseboard_fab2(sch_1):page75_i20:vss(62)" )
			)
			( pin "U2D1.DW68"
				( objectStatus "@baseboard_fab2_lib.baseboard_fab2(sch_1):page75_i20:vss(63)" )
			)
			( pin "U2D1.DW66"
				( objectStatus "@baseboard_fab2_lib.baseboard_fab2(sch_1):page75_i20:vss(64)" )
			)
			( pin "U2D1.DW64"
				( objectStatus "@baseboard_fab2_lib.baseboard_fab2(sch_1):page75_i20:vss(65)" )
			)
			( pin "U2D1.DW40"
				( objectStatus "@baseboard_fab2_lib.baseboard_fab2(sch_1):page75_i20:vss(66)" )
			)
			( pin "U2D1.DW36"
				( objectStatus "@baseboard_fab2_lib.baseboard_fab2(sch_1):page75_i20:vss(67)" )
			)
			( pin "U2D1.DW34"
				( objectStatus "@baseboard_fab2_lib.baseboard_fab2(sch_1):page75_i20:vss(68)" )
			)
			( pin "U2D1.DW30"
				( objectStatus "@baseboard_fab2_lib.baseboard_fab2(sch_1):page75_i20:vss(69)" )
			)
			( pin "U2D1.DW28"
				( objectStatus "@baseboard_fab2_lib.baseboard_fab2(sch_1):page75_i20:vss(70)" )
			)
			( pin "U2D1.DW24"
				( objectStatus "@baseboard_fab2_lib.baseboard_fab2(sch_1):page75_i20:vss(71)" )
			)
			( pin "U2D1.DW20"
				( objectStatus "@baseboard_fab2_lib.baseboard_fab2(sch_1):page75_i20:vss(72)" )
			)
			( pin "U2D1.DW12"
				( objectStatus "@baseboard_fab2_lib.baseboard_fab2(sch_1):page75_i20:vss(73)" )
			)
			( pin "U2D1.DV81"
				( objectStatus "@baseboard_fab2_lib.baseboard_fab2(sch_1):page75_i20:vss(74)" )
			)
			( pin "U2D1.DV77"
				( objectStatus "@baseboard_fab2_lib.baseboard_fab2(sch_1):page75_i20:vss(75)" )
			)
			( pin "U2D1.DV73"
				( objectStatus "@baseboard_fab2_lib.baseboard_fab2(sch_1):page75_i20:vss(76)" )
			)
			( pin "U2D1.DV39"
				( objectStatus "@baseboard_fab2_lib.baseboard_fab2(sch_1):page75_i20:vss(77)" )
			)
			( pin "U2D1.DV37"
				( objectStatus "@baseboard_fab2_lib.baseboard_fab2(sch_1):page75_i20:vss(78)" )
			)
			( pin "U2D1.DV33"
				( objectStatus "@baseboard_fab2_lib.baseboard_fab2(sch_1):page75_i20:vss(79)" )
			)
			( pin "U2D1.DV31"
				( objectStatus "@baseboard_fab2_lib.baseboard_fab2(sch_1):page75_i20:vss(80)" )
			)
			( pin "U2D1.DV27"
				( objectStatus "@baseboard_fab2_lib.baseboard_fab2(sch_1):page75_i20:vss(81)" )
			)
			( pin "U2D1.DV25"
				( objectStatus "@baseboard_fab2_lib.baseboard_fab2(sch_1):page75_i20:vss(82)" )
			)
			( pin "U2D1.DV21"
				( objectStatus "@baseboard_fab2_lib.baseboard_fab2(sch_1):page75_i20:vss(83)" )
			)
			( pin "U2D1.DU84"
				( objectStatus "@baseboard_fab2_lib.baseboard_fab2(sch_1):page75_i20:vss(84)" )
			)
			( pin "U2D1.DU82"
				( objectStatus "@baseboard_fab2_lib.baseboard_fab2(sch_1):page75_i20:vss(85)" )
			)
			( pin "U2D1.DU80"
				( objectStatus "@baseboard_fab2_lib.baseboard_fab2(sch_1):page75_i20:vss(86)" )
			)
			( pin "U2D1.DU78"
				( objectStatus "@baseboard_fab2_lib.baseboard_fab2(sch_1):page75_i20:vss(87)" )
			)
			( pin "U2D1.DU72"
				( objectStatus "@baseboard_fab2_lib.baseboard_fab2(sch_1):page75_i20:vss(88)" )
			)
			( pin "U2D1.DU70"
				( objectStatus "@baseboard_fab2_lib.baseboard_fab2(sch_1):page75_i20:vss(89)" )
			)
			( pin "U2D1.DU38"
				( objectStatus "@baseboard_fab2_lib.baseboard_fab2(sch_1):page75_i20:vss(90)" )
			)
			( pin "U2D1.DU32"
				( objectStatus "@baseboard_fab2_lib.baseboard_fab2(sch_1):page75_i20:vss(91)" )
			)
			( pin "U2D1.DU26"
				( objectStatus "@baseboard_fab2_lib.baseboard_fab2(sch_1):page75_i20:vss(92)" )
			)
			( pin "U2D1.DU22"
				( objectStatus "@baseboard_fab2_lib.baseboard_fab2(sch_1):page75_i20:vss(93)" )
			)
			( pin "U2D1.CN14"
				( objectStatus "@baseboard_fab2_lib.baseboard_fab2(sch_1):page75_i20:vss(94)" )
			)
			( pin "U2D1.DU14"
				( objectStatus "@baseboard_fab2_lib.baseboard_fab2(sch_1):page75_i20:vss(95)" )
			)
			( pin "U2D1.DU10"
				( objectStatus "@baseboard_fab2_lib.baseboard_fab2(sch_1):page75_i20:vss(96)" )
			)
			( pin "U2D1.DT85"
				( objectStatus "@baseboard_fab2_lib.baseboard_fab2(sch_1):page75_i20:vss(97)" )
			)
			( pin "U2D1.DT83"
				( objectStatus "@baseboard_fab2_lib.baseboard_fab2(sch_1):page75_i20:vss(98)" )
			)
			( pin "U2D1.DT79"
				( objectStatus "@baseboard_fab2_lib.baseboard_fab2(sch_1):page75_i20:vss(99)" )
			)
			( pin "U2D1.DT69"
				( objectStatus "@baseboard_fab2_lib.baseboard_fab2(sch_1):page75_i20:vss(100)" )
			)
			( pin "U2D1.DT65"
				( objectStatus "@baseboard_fab2_lib.baseboard_fab2(sch_1):page75_i20:vss(101)" )
			)
			( pin "U2D1.DH21"
				( objectStatus "@baseboard_fab2_lib.baseboard_fab2(sch_1):page75_i20:vss(102)" )
			)
			( pin "U2D1.DT17"
				( objectStatus "@baseboard_fab2_lib.baseboard_fab2(sch_1):page75_i20:vss(103)" )
			)
			( pin "U2D1.DT3"
				( objectStatus "@baseboard_fab2_lib.baseboard_fab2(sch_1):page75_i20:vss(104)" )
			)
			( pin "U2D1.DR78"
				( objectStatus "@baseboard_fab2_lib.baseboard_fab2(sch_1):page75_i20:vss(105)" )
			)
			( pin "U2D1.DR76"
				( objectStatus "@baseboard_fab2_lib.baseboard_fab2(sch_1):page75_i20:vss(106)" )
			)
			( pin "U2D1.DR74"
				( objectStatus "@baseboard_fab2_lib.baseboard_fab2(sch_1):page75_i20:vss(107)" )
			)
			( pin "U2D1.DR72"
				( objectStatus "@baseboard_fab2_lib.baseboard_fab2(sch_1):page75_i20:vss(108)" )
			)
			( pin "U2D1.DR70"
				( objectStatus "@baseboard_fab2_lib.baseboard_fab2(sch_1):page75_i20:vss(109)" )
			)
			( pin "U2D1.DR68"
				( objectStatus "@baseboard_fab2_lib.baseboard_fab2(sch_1):page75_i20:vss(110)" )
			)
			( pin "U2D1.DR66"
				( objectStatus "@baseboard_fab2_lib.baseboard_fab2(sch_1):page75_i20:vss(111)" )
			)
			( pin "U2D1.DR42"
				( objectStatus "@baseboard_fab2_lib.baseboard_fab2(sch_1):page75_i20:vss(112)" )
			)
			( pin "U2D1.DR40"
				( objectStatus "@baseboard_fab2_lib.baseboard_fab2(sch_1):page75_i20:vss(113)" )
			)
			( pin "U2D1.DR38"
				( objectStatus "@baseboard_fab2_lib.baseboard_fab2(sch_1):page75_i20:vss(114)" )
			)
			( pin "U2D1.DR36"
				( objectStatus "@baseboard_fab2_lib.baseboard_fab2(sch_1):page75_i20:vss(115)" )
			)
			( pin "U2D1.DR34"
				( objectStatus "@baseboard_fab2_lib.baseboard_fab2(sch_1):page75_i20:vss(116)" )
			)
			( pin "U2D1.DR32"
				( objectStatus "@baseboard_fab2_lib.baseboard_fab2(sch_1):page75_i20:vss(117)" )
			)
			( pin "U2D1.DR30"
				( objectStatus "@baseboard_fab2_lib.baseboard_fab2(sch_1):page75_i20:vss(118)" )
			)
			( pin "U2D1.DR28"
				( objectStatus "@baseboard_fab2_lib.baseboard_fab2(sch_1):page75_i20:vss(119)" )
			)
			( pin "U2D1.DR26"
				( objectStatus "@baseboard_fab2_lib.baseboard_fab2(sch_1):page75_i20:vss(120)" )
			)
			( pin "U2D1.DR24"
				( objectStatus "@baseboard_fab2_lib.baseboard_fab2(sch_1):page75_i20:vss(121)" )
			)
			( pin "U2D1.DR22"
				( objectStatus "@baseboard_fab2_lib.baseboard_fab2(sch_1):page75_i20:vss(122)" )
			)
			( pin "U2D1.DR20"
				( objectStatus "@baseboard_fab2_lib.baseboard_fab2(sch_1):page75_i20:vss(123)" )
			)
			( pin "U2D1.CL22"
				( objectStatus "@baseboard_fab2_lib.baseboard_fab2(sch_1):page75_i20:vss(124)" )
			)
			( pin "U2D1.CA20"
				( objectStatus "@baseboard_fab2_lib.baseboard_fab2(sch_1):page75_i20:vss(125)" )
			)
			( pin "U2D1.DR6"
				( objectStatus "@baseboard_fab2_lib.baseboard_fab2(sch_1):page75_i20:vss(126)" )
			)
			( pin "U2D1.BR26"
				( objectStatus "@baseboard_fab2_lib.baseboard_fab2(sch_1):page75_i20:vss(127)" )
			)
			( pin "U2D1.DP83"
				( objectStatus "@baseboard_fab2_lib.baseboard_fab2(sch_1):page75_i20:vss(128)" )
			)
			( pin "U2D1.DP81"
				( objectStatus "@baseboard_fab2_lib.baseboard_fab2(sch_1):page75_i20:vss(129)" )
			)
			( pin "U2D1.DP71"
				( objectStatus "@baseboard_fab2_lib.baseboard_fab2(sch_1):page75_i20:vss(130)" )
			)
			( pin "U2D1.DP69"
				( objectStatus "@baseboard_fab2_lib.baseboard_fab2(sch_1):page75_i20:vss(131)" )
			)
			( pin "U2D1.DP67"
				( objectStatus "@baseboard_fab2_lib.baseboard_fab2(sch_1):page75_i20:vss(132)" )
			)
			( pin "U2D1.DN78"
				( objectStatus "@baseboard_fab2_lib.baseboard_fab2(sch_1):page75_i20:vss(133)" )
			)
			( pin "C3D21.1"
				( objectStatus "@baseboard_fab2_lib.baseboard_fab2(sch_1):page76_i1:a" )
			)
			( pin "C3D21.2"
				( objectStatus "@baseboard_fab2_lib.baseboard_fab2(sch_1):page76_i1:b" )
			)
			( pin "C3D5.1"
				( objectStatus "@baseboard_fab2_lib.baseboard_fab2(sch_1):page76_i3:a" )
			)
			( pin "C3D5.2"
				( objectStatus "@baseboard_fab2_lib.baseboard_fab2(sch_1):page76_i3:b" )
			)
			( pin "C3D12.1"
				( objectStatus "@baseboard_fab2_lib.baseboard_fab2(sch_1):page76_i4:a" )
			)
			( pin "C3D12.2"
				( objectStatus "@baseboard_fab2_lib.baseboard_fab2(sch_1):page76_i4:b" )
			)
			( pin "C3D4.1"
				( objectStatus "@baseboard_fab2_lib.baseboard_fab2(sch_1):page76_i5:a" )
			)
			( pin "C3D4.2"
				( objectStatus "@baseboard_fab2_lib.baseboard_fab2(sch_1):page76_i5:b" )
			)
			( pin "C3D11.1"
				( objectStatus "@baseboard_fab2_lib.baseboard_fab2(sch_1):page76_i7:a" )
			)
			( pin "C3D11.2"
				( objectStatus "@baseboard_fab2_lib.baseboard_fab2(sch_1):page76_i7:b" )
			)
			( pin "C3D13.1"
				( objectStatus "@baseboard_fab2_lib.baseboard_fab2(sch_1):page76_i8:a" )
			)
			( pin "C3D13.2"
				( objectStatus "@baseboard_fab2_lib.baseboard_fab2(sch_1):page76_i8:b" )
			)
			( pin "C2D40.1"
				( objectStatus "@baseboard_fab2_lib.baseboard_fab2(sch_1):page76_i10:a" )
			)
			( pin "C2D40.2"
				( objectStatus "@baseboard_fab2_lib.baseboard_fab2(sch_1):page76_i10:b" )
			)
			( pin "C3D9.1"
				( objectStatus "@baseboard_fab2_lib.baseboard_fab2(sch_1):page76_i15:a" )
			)
			( pin "C3D9.2"
				( objectStatus "@baseboard_fab2_lib.baseboard_fab2(sch_1):page76_i15:b" )
			)
			( pin "C3D8.1"
				( objectStatus "@baseboard_fab2_lib.baseboard_fab2(sch_1):page76_i18:a" )
			)
			( pin "C3D8.2"
				( objectStatus "@baseboard_fab2_lib.baseboard_fab2(sch_1):page76_i18:b" )
			)
			( pin "C7P6.1"
				( objectStatus "@baseboard_fab2_lib.baseboard_fab2(sch_1):page76_i23:a" )
			)
			( pin "C7P6.2"
				( objectStatus "@baseboard_fab2_lib.baseboard_fab2(sch_1):page76_i23:b" )
			)
			( pin "C7P13.1"
				( objectStatus "@baseboard_fab2_lib.baseboard_fab2(sch_1):page76_i25:a" )
			)
			( pin "C7P13.2"
				( objectStatus "@baseboard_fab2_lib.baseboard_fab2(sch_1):page76_i25:b" )
			)
			( pin "C7P10.1"
				( objectStatus "@baseboard_fab2_lib.baseboard_fab2(sch_1):page76_i26:a" )
			)
			( pin "C7P10.2"
				( objectStatus "@baseboard_fab2_lib.baseboard_fab2(sch_1):page76_i26:b" )
			)
			( pin "C7P7.1"
				( objectStatus "@baseboard_fab2_lib.baseboard_fab2(sch_1):page76_i27:a" )
			)
			( pin "C7P7.2"
				( objectStatus "@baseboard_fab2_lib.baseboard_fab2(sch_1):page76_i27:b" )
			)
			( pin "C8P22.1"
				( objectStatus "@baseboard_fab2_lib.baseboard_fab2(sch_1):page76_i28:a" )
			)
			( pin "C8P22.2"
				( objectStatus "@baseboard_fab2_lib.baseboard_fab2(sch_1):page76_i28:b" )
			)
			( pin "C7P17.1"
				( objectStatus "@baseboard_fab2_lib.baseboard_fab2(sch_1):page76_i29:a" )
			)
			( pin "C7P17.2"
				( objectStatus "@baseboard_fab2_lib.baseboard_fab2(sch_1):page76_i29:b" )
			)
			( pin "C2D8.1"
				( objectStatus "@baseboard_fab2_lib.baseboard_fab2(sch_1):page76_i33:a" )
			)
			( pin "C2D8.2"
				( objectStatus "@baseboard_fab2_lib.baseboard_fab2(sch_1):page76_i33:b" )
			)
			( pin "C2D10.1"
				( objectStatus "@baseboard_fab2_lib.baseboard_fab2(sch_1):page76_i37:a" )
			)
			( pin "C2D10.2"
				( objectStatus "@baseboard_fab2_lib.baseboard_fab2(sch_1):page76_i37:b" )
			)
			( pin "C2D11.1"
				( objectStatus "@baseboard_fab2_lib.baseboard_fab2(sch_1):page76_i42:a" )
			)
			( pin "C2D11.2"
				( objectStatus "@baseboard_fab2_lib.baseboard_fab2(sch_1):page76_i42:b" )
			)
			( pin "C2D9.1"
				( objectStatus "@baseboard_fab2_lib.baseboard_fab2(sch_1):page76_i43:a" )
			)
			( pin "C2D9.2"
				( objectStatus "@baseboard_fab2_lib.baseboard_fab2(sch_1):page76_i43:b" )
			)
			( pin "C7P15.1"
				( objectStatus "@baseboard_fab2_lib.baseboard_fab2(sch_1):page76_i45:a" )
			)
			( pin "C7P15.2"
				( objectStatus "@baseboard_fab2_lib.baseboard_fab2(sch_1):page76_i45:b" )
			)
			( pin "C8P23.1"
				( objectStatus "@baseboard_fab2_lib.baseboard_fab2(sch_1):page76_i48:a" )
			)
			( pin "C8P23.2"
				( objectStatus "@baseboard_fab2_lib.baseboard_fab2(sch_1):page76_i48:b" )
			)
			( pin "C7P14.1"
				( objectStatus "@baseboard_fab2_lib.baseboard_fab2(sch_1):page76_i49:a" )
			)
			( pin "C7P14.2"
				( objectStatus "@baseboard_fab2_lib.baseboard_fab2(sch_1):page76_i49:b" )
			)
			( pin "C8P7.1"
				( objectStatus "@baseboard_fab2_lib.baseboard_fab2(sch_1):page76_i50:a" )
			)
			( pin "C8P7.2"
				( objectStatus "@baseboard_fab2_lib.baseboard_fab2(sch_1):page76_i50:b" )
			)
			( pin "C7P18.1"
				( objectStatus "@baseboard_fab2_lib.baseboard_fab2(sch_1):page76_i51:a" )
			)
			( pin "C7P18.2"
				( objectStatus "@baseboard_fab2_lib.baseboard_fab2(sch_1):page76_i51:b" )
			)
			( pin "C7P3.1"
				( objectStatus "@baseboard_fab2_lib.baseboard_fab2(sch_1):page76_i52:a" )
			)
			( pin "C7P3.2"
				( objectStatus "@baseboard_fab2_lib.baseboard_fab2(sch_1):page76_i52:b" )
			)
			( pin "C8P6.1"
				( objectStatus "@baseboard_fab2_lib.baseboard_fab2(sch_1):page76_i55:a" )
			)
			( pin "C8P6.2"
				( objectStatus "@baseboard_fab2_lib.baseboard_fab2(sch_1):page76_i55:b" )
			)
			( pin "C8P5.1"
				( objectStatus "@baseboard_fab2_lib.baseboard_fab2(sch_1):page76_i58:a" )
			)
			( pin "C8P5.2"
				( objectStatus "@baseboard_fab2_lib.baseboard_fab2(sch_1):page76_i58:b" )
			)
			( pin "C2D12.1"
				( objectStatus "@baseboard_fab2_lib.baseboard_fab2(sch_1):page76_i59:a" )
			)
			( pin "C2D12.2"
				( objectStatus "@baseboard_fab2_lib.baseboard_fab2(sch_1):page76_i59:b" )
			)
			( pin "C2D22.1"
				( objectStatus "@baseboard_fab2_lib.baseboard_fab2(sch_1):page76_i61:a" )
			)
			( pin "C2D22.2"
				( objectStatus "@baseboard_fab2_lib.baseboard_fab2(sch_1):page76_i61:b" )
			)
			( pin "C2D31.1"
				( objectStatus "@baseboard_fab2_lib.baseboard_fab2(sch_1):page76_i63:a" )
			)
			( pin "C2D31.2"
				( objectStatus "@baseboard_fab2_lib.baseboard_fab2(sch_1):page76_i63:b" )
			)
			( pin "C2D21.1"
				( objectStatus "@baseboard_fab2_lib.baseboard_fab2(sch_1):page76_i65:a" )
			)
			( pin "C2D21.2"
				( objectStatus "@baseboard_fab2_lib.baseboard_fab2(sch_1):page76_i65:b" )
			)
			( pin "C2D27.1"
				( objectStatus "@baseboard_fab2_lib.baseboard_fab2(sch_1):page76_i66:a" )
			)
			( pin "C2D27.2"
				( objectStatus "@baseboard_fab2_lib.baseboard_fab2(sch_1):page76_i66:b" )
			)
			( pin "C3D2.1"
				( objectStatus "@baseboard_fab2_lib.baseboard_fab2(sch_1):page76_i69:a" )
			)
			( pin "C3D2.2"
				( objectStatus "@baseboard_fab2_lib.baseboard_fab2(sch_1):page76_i69:b" )
			)
			( pin "C2D36.1"
				( objectStatus "@baseboard_fab2_lib.baseboard_fab2(sch_1):page76_i70:a" )
			)
			( pin "C2D36.2"
				( objectStatus "@baseboard_fab2_lib.baseboard_fab2(sch_1):page76_i70:b" )
			)
			( pin "C2D13.1"
				( objectStatus "@baseboard_fab2_lib.baseboard_fab2(sch_1):page76_i73:a" )
			)
			( pin "C2D13.2"
				( objectStatus "@baseboard_fab2_lib.baseboard_fab2(sch_1):page76_i73:b" )
			)
			( pin "C2D19.1"
				( objectStatus "@baseboard_fab2_lib.baseboard_fab2(sch_1):page76_i75:a" )
			)
			( pin "C2D19.2"
				( objectStatus "@baseboard_fab2_lib.baseboard_fab2(sch_1):page76_i75:b" )
			)
			( pin "C2D14.1"
				( objectStatus "@baseboard_fab2_lib.baseboard_fab2(sch_1):page76_i76:a" )
			)
			( pin "C2D14.2"
				( objectStatus "@baseboard_fab2_lib.baseboard_fab2(sch_1):page76_i76:b" )
			)
			( pin "C2D20.1"
				( objectStatus "@baseboard_fab2_lib.baseboard_fab2(sch_1):page76_i79:a" )
			)
			( pin "C2D20.2"
				( objectStatus "@baseboard_fab2_lib.baseboard_fab2(sch_1):page76_i79:b" )
			)
			( pin "C2D24.1"
				( objectStatus "@baseboard_fab2_lib.baseboard_fab2(sch_1):page76_i80:a" )
			)
			( pin "C2D24.2"
				( objectStatus "@baseboard_fab2_lib.baseboard_fab2(sch_1):page76_i80:b" )
			)
			( pin "C2D25.1"
				( objectStatus "@baseboard_fab2_lib.baseboard_fab2(sch_1):page76_i82:a" )
			)
			( pin "C2D25.2"
				( objectStatus "@baseboard_fab2_lib.baseboard_fab2(sch_1):page76_i82:b" )
			)
			( pin "C2D30.1"
				( objectStatus "@baseboard_fab2_lib.baseboard_fab2(sch_1):page76_i83:a" )
			)
			( pin "C2D30.2"
				( objectStatus "@baseboard_fab2_lib.baseboard_fab2(sch_1):page76_i83:b" )
			)
			( pin "C2D33.1"
				( objectStatus "@baseboard_fab2_lib.baseboard_fab2(sch_1):page76_i85:a" )
			)
			( pin "C2D33.2"
				( objectStatus "@baseboard_fab2_lib.baseboard_fab2(sch_1):page76_i85:b" )
			)
			( pin "C8P4.1"
				( objectStatus "@baseboard_fab2_lib.baseboard_fab2(sch_1):page76_i88:a" )
			)
			( pin "C8P4.2"
				( objectStatus "@baseboard_fab2_lib.baseboard_fab2(sch_1):page76_i88:b" )
			)
			( pin "C8P20.1"
				( objectStatus "@baseboard_fab2_lib.baseboard_fab2(sch_1):page76_i89:a" )
			)
			( pin "C8P20.2"
				( objectStatus "@baseboard_fab2_lib.baseboard_fab2(sch_1):page76_i89:b" )
			)
			( pin "C2D32.1"
				( objectStatus "@baseboard_fab2_lib.baseboard_fab2(sch_1):page76_i90:a" )
			)
			( pin "C2D32.2"
				( objectStatus "@baseboard_fab2_lib.baseboard_fab2(sch_1):page76_i90:b" )
			)
			( pin "C8P18.1"
				( objectStatus "@baseboard_fab2_lib.baseboard_fab2(sch_1):page76_i92:a" )
			)
			( pin "C8P18.2"
				( objectStatus "@baseboard_fab2_lib.baseboard_fab2(sch_1):page76_i92:b" )
			)
			( pin "C7P2.1"
				( objectStatus "@baseboard_fab2_lib.baseboard_fab2(sch_1):page76_i100:a" )
			)
			( pin "C7P2.2"
				( objectStatus "@baseboard_fab2_lib.baseboard_fab2(sch_1):page76_i100:b" )
			)
			( pin "C8P3.1"
				( objectStatus "@baseboard_fab2_lib.baseboard_fab2(sch_1):page76_i101:a" )
			)
			( pin "C8P3.2"
				( objectStatus "@baseboard_fab2_lib.baseboard_fab2(sch_1):page76_i101:b" )
			)
			( pin "C8P19.1"
				( objectStatus "@baseboard_fab2_lib.baseboard_fab2(sch_1):page76_i103:a" )
			)
			( pin "C8P19.2"
				( objectStatus "@baseboard_fab2_lib.baseboard_fab2(sch_1):page76_i103:b" )
			)
			( pin "C7P1.1"
				( objectStatus "@baseboard_fab2_lib.baseboard_fab2(sch_1):page76_i105:a" )
			)
			( pin "C7P1.2"
				( objectStatus "@baseboard_fab2_lib.baseboard_fab2(sch_1):page76_i105:b" )
			)
			( pin "C8P34.1"
				( objectStatus "@baseboard_fab2_lib.baseboard_fab2(sch_1):page76_i106:a" )
			)
			( pin "C8P34.2"
				( objectStatus "@baseboard_fab2_lib.baseboard_fab2(sch_1):page76_i106:b" )
			)
			( pin "C8P12.1"
				( objectStatus "@baseboard_fab2_lib.baseboard_fab2(sch_1):page76_i107:a" )
			)
			( pin "C8P12.2"
				( objectStatus "@baseboard_fab2_lib.baseboard_fab2(sch_1):page76_i107:b" )
			)
			( pin "C2D26.1"
				( objectStatus "@baseboard_fab2_lib.baseboard_fab2(sch_1):page76_i108:a" )
			)
			( pin "C2D26.2"
				( objectStatus "@baseboard_fab2_lib.baseboard_fab2(sch_1):page76_i108:b" )
			)
			( pin "C3D1.1"
				( objectStatus "@baseboard_fab2_lib.baseboard_fab2(sch_1):page76_i111:a" )
			)
			( pin "C3D1.2"
				( objectStatus "@baseboard_fab2_lib.baseboard_fab2(sch_1):page76_i111:b" )
			)
			( pin "C2D23.1"
				( objectStatus "@baseboard_fab2_lib.baseboard_fab2(sch_1):page76_i112:a" )
			)
			( pin "C2D23.2"
				( objectStatus "@baseboard_fab2_lib.baseboard_fab2(sch_1):page76_i112:b" )
			)
			( pin "C2D17.1"
				( objectStatus "@baseboard_fab2_lib.baseboard_fab2(sch_1):page76_i114:a" )
			)
			( pin "C2D17.2"
				( objectStatus "@baseboard_fab2_lib.baseboard_fab2(sch_1):page76_i114:b" )
			)
			( pin "C2D1.1"
				( objectStatus "@baseboard_fab2_lib.baseboard_fab2(sch_1):page76_i116:a" )
			)
			( pin "C2D1.2"
				( objectStatus "@baseboard_fab2_lib.baseboard_fab2(sch_1):page76_i116:b" )
			)
			( pin "C8P26.1"
				( objectStatus "@baseboard_fab2_lib.baseboard_fab2(sch_1):page76_i118:a" )
			)
			( pin "C8P26.2"
				( objectStatus "@baseboard_fab2_lib.baseboard_fab2(sch_1):page76_i118:b" )
			)
			( pin "C2D37.1"
				( objectStatus "@baseboard_fab2_lib.baseboard_fab2(sch_1):page76_i119:a" )
			)
			( pin "C2D37.2"
				( objectStatus "@baseboard_fab2_lib.baseboard_fab2(sch_1):page76_i119:b" )
			)
			( pin "C2D34.1"
				( objectStatus "@baseboard_fab2_lib.baseboard_fab2(sch_1):page76_i122:a" )
			)
			( pin "C2D34.2"
				( objectStatus "@baseboard_fab2_lib.baseboard_fab2(sch_1):page76_i122:b" )
			)
			( pin "C2D45.1"
				( objectStatus "@baseboard_fab2_lib.baseboard_fab2(sch_1):page76_i123:a" )
			)
			( pin "C2D45.2"
				( objectStatus "@baseboard_fab2_lib.baseboard_fab2(sch_1):page76_i123:b" )
			)
			( pin "C2D16.1"
				( objectStatus "@baseboard_fab2_lib.baseboard_fab2(sch_1):page76_i124:a" )
			)
			( pin "C2D16.2"
				( objectStatus "@baseboard_fab2_lib.baseboard_fab2(sch_1):page76_i124:b" )
			)
			( pin "C8P29.1"
				( objectStatus "@baseboard_fab2_lib.baseboard_fab2(sch_1):page76_i125:a" )
			)
			( pin "C8P29.2"
				( objectStatus "@baseboard_fab2_lib.baseboard_fab2(sch_1):page76_i125:b" )
			)
			( pin "C8P10.1"
				( objectStatus "@baseboard_fab2_lib.baseboard_fab2(sch_1):page76_i127:a" )
			)
			( pin "C8P10.2"
				( objectStatus "@baseboard_fab2_lib.baseboard_fab2(sch_1):page76_i127:b" )
			)
			( pin "C8P16.1"
				( objectStatus "@baseboard_fab2_lib.baseboard_fab2(sch_1):page76_i129:a" )
			)
			( pin "C8P16.2"
				( objectStatus "@baseboard_fab2_lib.baseboard_fab2(sch_1):page76_i129:b" )
			)
			( pin "C8P33.1"
				( objectStatus "@baseboard_fab2_lib.baseboard_fab2(sch_1):page76_i131:a" )
			)
			( pin "C8P33.2"
				( objectStatus "@baseboard_fab2_lib.baseboard_fab2(sch_1):page76_i131:b" )
			)
			( pin "C8P13.1"
				( objectStatus "@baseboard_fab2_lib.baseboard_fab2(sch_1):page76_i132:a" )
			)
			( pin "C8P13.2"
				( objectStatus "@baseboard_fab2_lib.baseboard_fab2(sch_1):page76_i132:b" )
			)
			( pin "C8P17.1"
				( objectStatus "@baseboard_fab2_lib.baseboard_fab2(sch_1):page76_i133:a" )
			)
			( pin "C8P17.2"
				( objectStatus "@baseboard_fab2_lib.baseboard_fab2(sch_1):page76_i133:b" )
			)
			( pin "C8P21.1"
				( objectStatus "@baseboard_fab2_lib.baseboard_fab2(sch_1):page76_i135:a" )
			)
			( pin "C8P21.2"
				( objectStatus "@baseboard_fab2_lib.baseboard_fab2(sch_1):page76_i135:b" )
			)
			( pin "C8P25.1"
				( objectStatus "@baseboard_fab2_lib.baseboard_fab2(sch_1):page76_i136:a" )
			)
			( pin "C8P25.2"
				( objectStatus "@baseboard_fab2_lib.baseboard_fab2(sch_1):page76_i136:b" )
			)
			( pin "C8P28.1"
				( objectStatus "@baseboard_fab2_lib.baseboard_fab2(sch_1):page76_i137:a" )
			)
			( pin "C8P28.2"
				( objectStatus "@baseboard_fab2_lib.baseboard_fab2(sch_1):page76_i137:b" )
			)
			( pin "C8P11.1"
				( objectStatus "@baseboard_fab2_lib.baseboard_fab2(sch_1):page76_i139:a" )
			)
			( pin "C8P11.2"
				( objectStatus "@baseboard_fab2_lib.baseboard_fab2(sch_1):page76_i139:b" )
			)
			( pin "C8P27.1"
				( objectStatus "@baseboard_fab2_lib.baseboard_fab2(sch_1):page76_i141:a" )
			)
			( pin "C8P27.2"
				( objectStatus "@baseboard_fab2_lib.baseboard_fab2(sch_1):page76_i141:b" )
			)
			( pin "C2D15.1"
				( objectStatus "@baseboard_fab2_lib.baseboard_fab2(sch_1):page76_i159:a" )
			)
			( pin "C2D15.2"
				( objectStatus "@baseboard_fab2_lib.baseboard_fab2(sch_1):page76_i159:b" )
			)
			( pin "C2D38.1"
				( objectStatus "@baseboard_fab2_lib.baseboard_fab2(sch_1):page76_i160:a" )
			)
			( pin "C2D38.2"
				( objectStatus "@baseboard_fab2_lib.baseboard_fab2(sch_1):page76_i160:b" )
			)
			( pin "C2D35.1"
				( objectStatus "@baseboard_fab2_lib.baseboard_fab2(sch_1):page76_i161:a" )
			)
			( pin "C2D35.2"
				( objectStatus "@baseboard_fab2_lib.baseboard_fab2(sch_1):page76_i161:b" )
			)
			( pin "C3D7.1"
				( objectStatus "@baseboard_fab2_lib.baseboard_fab2(sch_1):page76_i164:a" )
			)
			( pin "C3D7.2"
				( objectStatus "@baseboard_fab2_lib.baseboard_fab2(sch_1):page76_i164:b" )
			)
			( pin "C2D39.1"
				( objectStatus "@baseboard_fab2_lib.baseboard_fab2(sch_1):page76_i165:a" )
			)
			( pin "C2D39.2"
				( objectStatus "@baseboard_fab2_lib.baseboard_fab2(sch_1):page76_i165:b" )
			)
			( pin "C3D17.1"
				( objectStatus "@baseboard_fab2_lib.baseboard_fab2(sch_1):page76_i166:a" )
			)
			( pin "C3D17.2"
				( objectStatus "@baseboard_fab2_lib.baseboard_fab2(sch_1):page76_i166:b" )
			)
			( pin "C3D18.1"
				( objectStatus "@baseboard_fab2_lib.baseboard_fab2(sch_1):page76_i169:a" )
			)
			( pin "C3D18.2"
				( objectStatus "@baseboard_fab2_lib.baseboard_fab2(sch_1):page76_i169:b" )
			)
			( pin "C3D6.1"
				( objectStatus "@baseboard_fab2_lib.baseboard_fab2(sch_1):page76_i170:a" )
			)
			( pin "C3D6.2"
				( objectStatus "@baseboard_fab2_lib.baseboard_fab2(sch_1):page76_i170:b" )
			)
			( pin "C3D14.1"
				( objectStatus "@baseboard_fab2_lib.baseboard_fab2(sch_1):page76_i171:a" )
			)
			( pin "C3D14.2"
				( objectStatus "@baseboard_fab2_lib.baseboard_fab2(sch_1):page76_i171:b" )
			)
			( pin "C3D23.1"
				( objectStatus "@baseboard_fab2_lib.baseboard_fab2(sch_1):page76_i172:a" )
			)
			( pin "C3D23.2"
				( objectStatus "@baseboard_fab2_lib.baseboard_fab2(sch_1):page76_i172:b" )
			)
			( pin "C3D15.1"
				( objectStatus "@baseboard_fab2_lib.baseboard_fab2(sch_1):page76_i174:a" )
			)
			( pin "C3D15.2"
				( objectStatus "@baseboard_fab2_lib.baseboard_fab2(sch_1):page76_i174:b" )
			)
			( pin "C3D24.1"
				( objectStatus "@baseboard_fab2_lib.baseboard_fab2(sch_1):page76_i175:a" )
			)
			( pin "C3D24.2"
				( objectStatus "@baseboard_fab2_lib.baseboard_fab2(sch_1):page76_i175:b" )
			)
			( pin "C3D16.1"
				( objectStatus "@baseboard_fab2_lib.baseboard_fab2(sch_1):page76_i176:a" )
			)
			( pin "C3D16.2"
				( objectStatus "@baseboard_fab2_lib.baseboard_fab2(sch_1):page76_i176:b" )
			)
			( pin "C7P12.1"
				( objectStatus "@baseboard_fab2_lib.baseboard_fab2(sch_1):page76_i179:a" )
			)
			( pin "C7P12.2"
				( objectStatus "@baseboard_fab2_lib.baseboard_fab2(sch_1):page76_i179:b" )
			)
			( pin "C7P9.1"
				( objectStatus "@baseboard_fab2_lib.baseboard_fab2(sch_1):page76_i181:a" )
			)
			( pin "C7P9.2"
				( objectStatus "@baseboard_fab2_lib.baseboard_fab2(sch_1):page76_i181:b" )
			)
			( pin "C7P5.1"
				( objectStatus "@baseboard_fab2_lib.baseboard_fab2(sch_1):page76_i182:a" )
			)
			( pin "C7P5.2"
				( objectStatus "@baseboard_fab2_lib.baseboard_fab2(sch_1):page76_i182:b" )
			)
			( pin "C7P11.1"
				( objectStatus "@baseboard_fab2_lib.baseboard_fab2(sch_1):page76_i183:a" )
			)
			( pin "C7P11.2"
				( objectStatus "@baseboard_fab2_lib.baseboard_fab2(sch_1):page76_i183:b" )
			)
			( pin "C7P8.1"
				( objectStatus "@baseboard_fab2_lib.baseboard_fab2(sch_1):page76_i184:a" )
			)
			( pin "C7P8.2"
				( objectStatus "@baseboard_fab2_lib.baseboard_fab2(sch_1):page76_i184:b" )
			)
			( pin "C7P4.1"
				( objectStatus "@baseboard_fab2_lib.baseboard_fab2(sch_1):page76_i195:a" )
			)
			( pin "C7P4.2"
				( objectStatus "@baseboard_fab2_lib.baseboard_fab2(sch_1):page76_i195:b" )
			)
			( pin "C3D10.1"
				( objectStatus "@baseboard_fab2_lib.baseboard_fab2(sch_1):page76_i196:a" )
			)
			( pin "C3D10.2"
				( objectStatus "@baseboard_fab2_lib.baseboard_fab2(sch_1):page76_i196:b" )
			)
			( pin "C2D18.1"
				( objectStatus "@baseboard_fab2_lib.baseboard_fab2(sch_1):page76_i197:a" )
			)
			( pin "C2D18.2"
				( objectStatus "@baseboard_fab2_lib.baseboard_fab2(sch_1):page76_i197:b" )
			)
			( pin "C2D28.1"
				( objectStatus "@baseboard_fab2_lib.baseboard_fab2(sch_1):page76_i198:a" )
			)
			( pin "C2D28.2"
				( objectStatus "@baseboard_fab2_lib.baseboard_fab2(sch_1):page76_i198:b" )
			)
			( pin "C2D29.1"
				( objectStatus "@baseboard_fab2_lib.baseboard_fab2(sch_1):page76_i199:a" )
			)
			( pin "C2D29.2"
				( objectStatus "@baseboard_fab2_lib.baseboard_fab2(sch_1):page76_i199:b" )
			)
			( pin "C2D2.1"
				( objectStatus "@baseboard_fab2_lib.baseboard_fab2(sch_1):page76_i201:a" )
			)
			( pin "C2D2.2"
				( objectStatus "@baseboard_fab2_lib.baseboard_fab2(sch_1):page76_i201:b" )
			)
			( pin "C2D3.1"
				( objectStatus "@baseboard_fab2_lib.baseboard_fab2(sch_1):page76_i202:a" )
			)
			( pin "C2D3.2"
				( objectStatus "@baseboard_fab2_lib.baseboard_fab2(sch_1):page76_i202:b" )
			)
			( pin "C2D47.1"
				( objectStatus "@baseboard_fab2_lib.baseboard_fab2(sch_1):page76_i203:a" )
			)
			( pin "C2D47.2"
				( objectStatus "@baseboard_fab2_lib.baseboard_fab2(sch_1):page76_i203:b" )
			)
			( pin "C2D46.1"
				( objectStatus "@baseboard_fab2_lib.baseboard_fab2(sch_1):page76_i204:a" )
			)
			( pin "C2D46.2"
				( objectStatus "@baseboard_fab2_lib.baseboard_fab2(sch_1):page76_i204:b" )
			)
			( pin "C3D25.1"
				( objectStatus "@baseboard_fab2_lib.baseboard_fab2(sch_1):page76_i205:a" )
			)
			( pin "C3D25.2"
				( objectStatus "@baseboard_fab2_lib.baseboard_fab2(sch_1):page76_i205:b" )
			)
			( pin "C7P16.1"
				( objectStatus "@baseboard_fab2_lib.baseboard_fab2(sch_1):page76_i206:a" )
			)
			( pin "C7P16.2"
				( objectStatus "@baseboard_fab2_lib.baseboard_fab2(sch_1):page76_i206:b" )
			)
			( pin "C3D20.1"
				( objectStatus "@baseboard_fab2_lib.baseboard_fab2(sch_1):page76_i207:a" )
			)
			( pin "C3D20.2"
				( objectStatus "@baseboard_fab2_lib.baseboard_fab2(sch_1):page76_i207:b" )
			)
			( pin "C3D19.1"
				( objectStatus "@baseboard_fab2_lib.baseboard_fab2(sch_1):page76_i208:a" )
			)
			( pin "C3D19.2"
				( objectStatus "@baseboard_fab2_lib.baseboard_fab2(sch_1):page76_i208:b" )
			)
			( pin "C8P14.1"
				( objectStatus "@baseboard_fab2_lib.baseboard_fab2(sch_1):page76_i211:a" )
			)
			( pin "C8P14.2"
				( objectStatus "@baseboard_fab2_lib.baseboard_fab2(sch_1):page76_i211:b" )
			)
			( pin "C8P15.1"
				( objectStatus "@baseboard_fab2_lib.baseboard_fab2(sch_1):page76_i212:a" )
			)
			( pin "C8P15.2"
				( objectStatus "@baseboard_fab2_lib.baseboard_fab2(sch_1):page76_i212:b" )
			)
			( pin "C8P8.1"
				( objectStatus "@baseboard_fab2_lib.baseboard_fab2(sch_1):page76_i213:a" )
			)
			( pin "C8P8.2"
				( objectStatus "@baseboard_fab2_lib.baseboard_fab2(sch_1):page76_i213:b" )
			)
			( pin "C8P9.1"
				( objectStatus "@baseboard_fab2_lib.baseboard_fab2(sch_1):page76_i214:a" )
			)
			( pin "C8P9.2"
				( objectStatus "@baseboard_fab2_lib.baseboard_fab2(sch_1):page76_i214:b" )
			)
			( pin "C7P19.1"
				( objectStatus "@baseboard_fab2_lib.baseboard_fab2(sch_1):page76_i215:a" )
			)
			( pin "C7P19.2"
				( objectStatus "@baseboard_fab2_lib.baseboard_fab2(sch_1):page76_i215:b" )
			)
			( pin "C8P32.1"
				( objectStatus "@baseboard_fab2_lib.baseboard_fab2(sch_1):page76_i216:a" )
			)
			( pin "C8P32.2"
				( objectStatus "@baseboard_fab2_lib.baseboard_fab2(sch_1):page76_i216:b" )
			)
			( pin "C8P24.1"
				( objectStatus "@baseboard_fab2_lib.baseboard_fab2(sch_1):page76_i217:a" )
			)
			( pin "C8P24.2"
				( objectStatus "@baseboard_fab2_lib.baseboard_fab2(sch_1):page76_i217:b" )
			)
			( pin "C7P20.1"
				( objectStatus "@baseboard_fab2_lib.baseboard_fab2(sch_1):page76_i218:a" )
			)
			( pin "C7P20.2"
				( objectStatus "@baseboard_fab2_lib.baseboard_fab2(sch_1):page76_i218:b" )
			)
			( pin "J1G1.283"
				( objectStatus "@baseboard_fab2_lib.baseboard_fab2(sch_1):page77_i43:vss(0)" )
			)
			( pin "J1G1.281"
				( objectStatus "@baseboard_fab2_lib.baseboard_fab2(sch_1):page77_i43:vss(1)" )
			)
			( pin "J1G1.279"
				( objectStatus "@baseboard_fab2_lib.baseboard_fab2(sch_1):page77_i43:vss(2)" )
			)
			( pin "J1G1.276"
				( objectStatus "@baseboard_fab2_lib.baseboard_fab2(sch_1):page77_i43:vss(3)" )
			)
			( pin "J1G1.274"
				( objectStatus "@baseboard_fab2_lib.baseboard_fab2(sch_1):page77_i43:vss(4)" )
			)
			( pin "J1G1.272"
				( objectStatus "@baseboard_fab2_lib.baseboard_fab2(sch_1):page77_i43:vss(5)" )
			)
			( pin "J1G1.270"
				( objectStatus "@baseboard_fab2_lib.baseboard_fab2(sch_1):page77_i43:vss(6)" )
			)
			( pin "J1G1.268"
				( objectStatus "@baseboard_fab2_lib.baseboard_fab2(sch_1):page77_i43:vss(7)" )
			)
			( pin "J1G1.265"
				( objectStatus "@baseboard_fab2_lib.baseboard_fab2(sch_1):page77_i43:vss(8)" )
			)
			( pin "J1G1.263"
				( objectStatus "@baseboard_fab2_lib.baseboard_fab2(sch_1):page77_i43:vss(9)" )
			)
			( pin "J1G1.261"
				( objectStatus "@baseboard_fab2_lib.baseboard_fab2(sch_1):page77_i43:vss(10)" )
			)
			( pin "J1G1.259"
				( objectStatus "@baseboard_fab2_lib.baseboard_fab2(sch_1):page77_i43:vss(11)" )
			)
			( pin "J1G1.257"
				( objectStatus "@baseboard_fab2_lib.baseboard_fab2(sch_1):page77_i43:vss(12)" )
			)
			( pin "J1G1.254"
				( objectStatus "@baseboard_fab2_lib.baseboard_fab2(sch_1):page77_i43:vss(13)" )
			)
			( pin "J1G1.252"
				( objectStatus "@baseboard_fab2_lib.baseboard_fab2(sch_1):page77_i43:vss(14)" )
			)
			( pin "J1G1.250"
				( objectStatus "@baseboard_fab2_lib.baseboard_fab2(sch_1):page77_i43:vss(15)" )
			)
			( pin "J1G1.248"
				( objectStatus "@baseboard_fab2_lib.baseboard_fab2(sch_1):page77_i43:vss(16)" )
			)
			( pin "J1G1.246"
				( objectStatus "@baseboard_fab2_lib.baseboard_fab2(sch_1):page77_i43:vss(17)" )
			)
			( pin "J1G1.243"
				( objectStatus "@baseboard_fab2_lib.baseboard_fab2(sch_1):page77_i43:vss(18)" )
			)
			( pin "J1G1.241"
				( objectStatus "@baseboard_fab2_lib.baseboard_fab2(sch_1):page77_i43:vss(19)" )
			)
			( pin "J1G1.239"
				( objectStatus "@baseboard_fab2_lib.baseboard_fab2(sch_1):page77_i43:vss(20)" )
			)
			( pin "J1G1.202"
				( objectStatus "@baseboard_fab2_lib.baseboard_fab2(sch_1):page77_i43:vss(21)" )
			)
			( pin "J1G1.200"
				( objectStatus "@baseboard_fab2_lib.baseboard_fab2(sch_1):page77_i43:vss(22)" )
			)
			( pin "J1G1.198"
				( objectStatus "@baseboard_fab2_lib.baseboard_fab2(sch_1):page77_i43:vss(23)" )
			)
			( pin "J1G1.195"
				( objectStatus "@baseboard_fab2_lib.baseboard_fab2(sch_1):page77_i43:vss(24)" )
			)
			( pin "J1G1.193"
				( objectStatus "@baseboard_fab2_lib.baseboard_fab2(sch_1):page77_i43:vss(25)" )
			)
			( pin "J1G1.191"
				( objectStatus "@baseboard_fab2_lib.baseboard_fab2(sch_1):page77_i43:vss(26)" )
			)
			( pin "J1G1.189"
				( objectStatus "@baseboard_fab2_lib.baseboard_fab2(sch_1):page77_i43:vss(27)" )
			)
			( pin "J1G1.187"
				( objectStatus "@baseboard_fab2_lib.baseboard_fab2(sch_1):page77_i43:vss(28)" )
			)
			( pin "J1G1.184"
				( objectStatus "@baseboard_fab2_lib.baseboard_fab2(sch_1):page77_i43:vss(29)" )
			)
			( pin "J1G1.182"
				( objectStatus "@baseboard_fab2_lib.baseboard_fab2(sch_1):page77_i43:vss(30)" )
			)
			( pin "J1G1.180"
				( objectStatus "@baseboard_fab2_lib.baseboard_fab2(sch_1):page77_i43:vss(31)" )
			)
			( pin "J1G1.178"
				( objectStatus "@baseboard_fab2_lib.baseboard_fab2(sch_1):page77_i43:vss(32)" )
			)
			( pin "J1G1.176"
				( objectStatus "@baseboard_fab2_lib.baseboard_fab2(sch_1):page77_i43:vss(33)" )
			)
			( pin "J1G1.173"
				( objectStatus "@baseboard_fab2_lib.baseboard_fab2(sch_1):page77_i43:vss(34)" )
			)
			( pin "J1G1.171"
				( objectStatus "@baseboard_fab2_lib.baseboard_fab2(sch_1):page77_i43:vss(35)" )
			)
			( pin "J1G1.169"
				( objectStatus "@baseboard_fab2_lib.baseboard_fab2(sch_1):page77_i43:vss(36)" )
			)
			( pin "J1G1.167"
				( objectStatus "@baseboard_fab2_lib.baseboard_fab2(sch_1):page77_i43:vss(37)" )
			)
			( pin "J1G1.165"
				( objectStatus "@baseboard_fab2_lib.baseboard_fab2(sch_1):page77_i43:vss(38)" )
			)
			( pin "J1G1.162"
				( objectStatus "@baseboard_fab2_lib.baseboard_fab2(sch_1):page77_i43:vss(39)" )
			)
			( pin "J1G1.160"
				( objectStatus "@baseboard_fab2_lib.baseboard_fab2(sch_1):page77_i43:vss(40)" )
			)
			( pin "J1G1.158"
				( objectStatus "@baseboard_fab2_lib.baseboard_fab2(sch_1):page77_i43:vss(41)" )
			)
			( pin "J1G1.156"
				( objectStatus "@baseboard_fab2_lib.baseboard_fab2(sch_1):page77_i43:vss(42)" )
			)
			( pin "J1G1.154"
				( objectStatus "@baseboard_fab2_lib.baseboard_fab2(sch_1):page77_i43:vss(43)" )
			)
			( pin "J1G1.151"
				( objectStatus "@baseboard_fab2_lib.baseboard_fab2(sch_1):page77_i43:vss(44)" )
			)
			( pin "J1G1.149"
				( objectStatus "@baseboard_fab2_lib.baseboard_fab2(sch_1):page77_i43:vss(45)" )
			)
			( pin "J1G1.147"
				( objectStatus "@baseboard_fab2_lib.baseboard_fab2(sch_1):page77_i43:vss(46)" )
			)
			( pin "J1G1.138"
				( objectStatus "@baseboard_fab2_lib.baseboard_fab2(sch_1):page77_i43:vss(47)" )
			)
			( pin "J1G1.136"
				( objectStatus "@baseboard_fab2_lib.baseboard_fab2(sch_1):page77_i43:vss(48)" )
			)
			( pin "J1G1.134"
				( objectStatus "@baseboard_fab2_lib.baseboard_fab2(sch_1):page77_i43:vss(49)" )
			)
			( pin "J1G1.131"
				( objectStatus "@baseboard_fab2_lib.baseboard_fab2(sch_1):page77_i43:vss(50)" )
			)
			( pin "J1G1.129"
				( objectStatus "@baseboard_fab2_lib.baseboard_fab2(sch_1):page77_i43:vss(51)" )
			)
			( pin "J1G1.127"
				( objectStatus "@baseboard_fab2_lib.baseboard_fab2(sch_1):page77_i43:vss(52)" )
			)
			( pin "J1G1.125"
				( objectStatus "@baseboard_fab2_lib.baseboard_fab2(sch_1):page77_i43:vss(53)" )
			)
			( pin "J1G1.123"
				( objectStatus "@baseboard_fab2_lib.baseboard_fab2(sch_1):page77_i43:vss(54)" )
			)
			( pin "J1G1.120"
				( objectStatus "@baseboard_fab2_lib.baseboard_fab2(sch_1):page77_i43:vss(55)" )
			)
			( pin "J1G1.118"
				( objectStatus "@baseboard_fab2_lib.baseboard_fab2(sch_1):page77_i43:vss(56)" )
			)
			( pin "J1G1.116"
				( objectStatus "@baseboard_fab2_lib.baseboard_fab2(sch_1):page77_i43:vss(57)" )
			)
			( pin "J1G1.114"
				( objectStatus "@baseboard_fab2_lib.baseboard_fab2(sch_1):page77_i43:vss(58)" )
			)
			( pin "J1G1.112"
				( objectStatus "@baseboard_fab2_lib.baseboard_fab2(sch_1):page77_i43:vss(59)" )
			)
			( pin "J1G1.109"
				( objectStatus "@baseboard_fab2_lib.baseboard_fab2(sch_1):page77_i43:vss(60)" )
			)
			( pin "J1G1.107"
				( objectStatus "@baseboard_fab2_lib.baseboard_fab2(sch_1):page77_i43:vss(61)" )
			)
			( pin "J1G1.105"
				( objectStatus "@baseboard_fab2_lib.baseboard_fab2(sch_1):page77_i43:vss(62)" )
			)
			( pin "J1G1.103"
				( objectStatus "@baseboard_fab2_lib.baseboard_fab2(sch_1):page77_i43:vss(63)" )
			)
			( pin "J1G1.101"
				( objectStatus "@baseboard_fab2_lib.baseboard_fab2(sch_1):page77_i43:vss(64)" )
			)
			( pin "J1G1.98"
				( objectStatus "@baseboard_fab2_lib.baseboard_fab2(sch_1):page77_i43:vss(65)" )
			)
			( pin "J1G1.96"
				( objectStatus "@baseboard_fab2_lib.baseboard_fab2(sch_1):page77_i43:vss(66)" )
			)
			( pin "J1G1.94"
				( objectStatus "@baseboard_fab2_lib.baseboard_fab2(sch_1):page77_i43:vss(67)" )
			)
			( pin "J1G1.57"
				( objectStatus "@baseboard_fab2_lib.baseboard_fab2(sch_1):page77_i43:vss(68)" )
			)
			( pin "J1G1.55"
				( objectStatus "@baseboard_fab2_lib.baseboard_fab2(sch_1):page77_i43:vss(69)" )
			)
			( pin "J1G1.53"
				( objectStatus "@baseboard_fab2_lib.baseboard_fab2(sch_1):page77_i43:vss(70)" )
			)
			( pin "J1G1.50"
				( objectStatus "@baseboard_fab2_lib.baseboard_fab2(sch_1):page77_i43:vss(71)" )
			)
			( pin "J1G1.48"
				( objectStatus "@baseboard_fab2_lib.baseboard_fab2(sch_1):page77_i43:vss(72)" )
			)
			( pin "J1G1.46"
				( objectStatus "@baseboard_fab2_lib.baseboard_fab2(sch_1):page77_i43:vss(73)" )
			)
			( pin "J1G1.44"
				( objectStatus "@baseboard_fab2_lib.baseboard_fab2(sch_1):page77_i43:vss(74)" )
			)
			( pin "J1G1.42"
				( objectStatus "@baseboard_fab2_lib.baseboard_fab2(sch_1):page77_i43:vss(75)" )
			)
			( pin "J1G1.39"
				( objectStatus "@baseboard_fab2_lib.baseboard_fab2(sch_1):page77_i43:vss(76)" )
			)
			( pin "J1G1.37"
				( objectStatus "@baseboard_fab2_lib.baseboard_fab2(sch_1):page77_i43:vss(77)" )
			)
			( pin "J1G1.35"
				( objectStatus "@baseboard_fab2_lib.baseboard_fab2(sch_1):page77_i43:vss(78)" )
			)
			( pin "J1G1.33"
				( objectStatus "@baseboard_fab2_lib.baseboard_fab2(sch_1):page77_i43:vss(79)" )
			)
			( pin "J1G1.31"
				( objectStatus "@baseboard_fab2_lib.baseboard_fab2(sch_1):page77_i43:vss(80)" )
			)
			( pin "J1G1.28"
				( objectStatus "@baseboard_fab2_lib.baseboard_fab2(sch_1):page77_i43:vss(81)" )
			)
			( pin "J1G1.26"
				( objectStatus "@baseboard_fab2_lib.baseboard_fab2(sch_1):page77_i43:vss(82)" )
			)
			( pin "J1G1.24"
				( objectStatus "@baseboard_fab2_lib.baseboard_fab2(sch_1):page77_i43:vss(83)" )
			)
			( pin "J1G1.22"
				( objectStatus "@baseboard_fab2_lib.baseboard_fab2(sch_1):page77_i43:vss(84)" )
			)
			( pin "J1G1.20"
				( objectStatus "@baseboard_fab2_lib.baseboard_fab2(sch_1):page77_i43:vss(85)" )
			)
			( pin "J1G1.17"
				( objectStatus "@baseboard_fab2_lib.baseboard_fab2(sch_1):page77_i43:vss(86)" )
			)
			( pin "J1G1.15"
				( objectStatus "@baseboard_fab2_lib.baseboard_fab2(sch_1):page77_i43:vss(87)" )
			)
			( pin "J1G1.13"
				( objectStatus "@baseboard_fab2_lib.baseboard_fab2(sch_1):page77_i43:vss(88)" )
			)
			( pin "J1G1.11"
				( objectStatus "@baseboard_fab2_lib.baseboard_fab2(sch_1):page77_i43:vss(89)" )
			)
			( pin "J1G1.9"
				( objectStatus "@baseboard_fab2_lib.baseboard_fab2(sch_1):page77_i43:vss(90)" )
			)
			( pin "J1G1.6"
				( objectStatus "@baseboard_fab2_lib.baseboard_fab2(sch_1):page77_i43:vss(91)" )
			)
			( pin "J1G1.4"
				( objectStatus "@baseboard_fab2_lib.baseboard_fab2(sch_1):page77_i43:vss(92)" )
			)
			( pin "J1G1.2"
				( objectStatus "@baseboard_fab2_lib.baseboard_fab2(sch_1):page77_i43:vss(93)" )
			)
			( pin "J1G1.152"
				( objectStatus "@baseboard_fab2_lib.baseboard_fab2(sch_1):page77_i66:dqs0n" )
			)
			( pin "J1G1.153"
				( objectStatus "@baseboard_fab2_lib.baseboard_fab2(sch_1):page77_i66:dqs0p" )
			)
			( pin "J1G1.163"
				( objectStatus "@baseboard_fab2_lib.baseboard_fab2(sch_1):page77_i66:dqs1n" )
			)
			( pin "J1G1.164"
				( objectStatus "@baseboard_fab2_lib.baseboard_fab2(sch_1):page77_i66:dqs1p" )
			)
			( pin "J1G1.174"
				( objectStatus "@baseboard_fab2_lib.baseboard_fab2(sch_1):page77_i66:dqs2n" )
			)
			( pin "J1G1.175"
				( objectStatus "@baseboard_fab2_lib.baseboard_fab2(sch_1):page77_i66:dqs2p" )
			)
			( pin "J1G1.185"
				( objectStatus "@baseboard_fab2_lib.baseboard_fab2(sch_1):page77_i66:dqs3n" )
			)
			( pin "J1G1.186"
				( objectStatus "@baseboard_fab2_lib.baseboard_fab2(sch_1):page77_i66:dqs3p" )
			)
			( pin "J1G1.244"
				( objectStatus "@baseboard_fab2_lib.baseboard_fab2(sch_1):page77_i66:dqs4n" )
			)
			( pin "J1G1.245"
				( objectStatus "@baseboard_fab2_lib.baseboard_fab2(sch_1):page77_i66:dqs4p" )
			)
			( pin "J1G1.255"
				( objectStatus "@baseboard_fab2_lib.baseboard_fab2(sch_1):page77_i66:dqs5n" )
			)
			( pin "J1G1.256"
				( objectStatus "@baseboard_fab2_lib.baseboard_fab2(sch_1):page77_i66:dqs5p" )
			)
			( pin "J1G1.266"
				( objectStatus "@baseboard_fab2_lib.baseboard_fab2(sch_1):page77_i66:dqs6n" )
			)
			( pin "J1G1.267"
				( objectStatus "@baseboard_fab2_lib.baseboard_fab2(sch_1):page77_i66:dqs6p" )
			)
			( pin "J1G1.277"
				( objectStatus "@baseboard_fab2_lib.baseboard_fab2(sch_1):page77_i66:dqs7n" )
			)
			( pin "J1G1.278"
				( objectStatus "@baseboard_fab2_lib.baseboard_fab2(sch_1):page77_i66:dqs7p" )
			)
			( pin "J1G1.196"
				( objectStatus "@baseboard_fab2_lib.baseboard_fab2(sch_1):page77_i66:dqs8n" )
			)
			( pin "J1G1.197"
				( objectStatus "@baseboard_fab2_lib.baseboard_fab2(sch_1):page77_i66:dqs8p" )
			)
			( pin "J1G1.8"
				( objectStatus "@baseboard_fab2_lib.baseboard_fab2(sch_1):page77_i66:dqs9n" )
			)
			( pin "J1G1.7"
				( objectStatus "@baseboard_fab2_lib.baseboard_fab2(sch_1):page77_i66:dqs9p" )
			)
			( pin "J1G1.19"
				( objectStatus "@baseboard_fab2_lib.baseboard_fab2(sch_1):page77_i66:dqs10n" )
			)
			( pin "J1G1.18"
				( objectStatus "@baseboard_fab2_lib.baseboard_fab2(sch_1):page77_i66:dqs10p" )
			)
			( pin "J1G1.30"
				( objectStatus "@baseboard_fab2_lib.baseboard_fab2(sch_1):page77_i66:dqs11n" )
			)
			( pin "J1G1.29"
				( objectStatus "@baseboard_fab2_lib.baseboard_fab2(sch_1):page77_i66:dqs11p" )
			)
			( pin "J1G1.41"
				( objectStatus "@baseboard_fab2_lib.baseboard_fab2(sch_1):page77_i66:dqs12n" )
			)
			( pin "J1G1.40"
				( objectStatus "@baseboard_fab2_lib.baseboard_fab2(sch_1):page77_i66:dqs12p" )
			)
			( pin "J1G1.100"
				( objectStatus "@baseboard_fab2_lib.baseboard_fab2(sch_1):page77_i66:dqs13n" )
			)
			( pin "J1G1.99"
				( objectStatus "@baseboard_fab2_lib.baseboard_fab2(sch_1):page77_i66:dqs13p" )
			)
			( pin "J1G1.111"
				( objectStatus "@baseboard_fab2_lib.baseboard_fab2(sch_1):page77_i66:dqs14n" )
			)
			( pin "J1G1.110"
				( objectStatus "@baseboard_fab2_lib.baseboard_fab2(sch_1):page77_i66:dqs14p" )
			)
			( pin "J1G1.122"
				( objectStatus "@baseboard_fab2_lib.baseboard_fab2(sch_1):page77_i66:dqs15n" )
			)
			( pin "J1G1.121"
				( objectStatus "@baseboard_fab2_lib.baseboard_fab2(sch_1):page77_i66:dqs15p" )
			)
			( pin "J1G1.133"
				( objectStatus "@baseboard_fab2_lib.baseboard_fab2(sch_1):page77_i66:dqs16n" )
			)
			( pin "J1G1.132"
				( objectStatus "@baseboard_fab2_lib.baseboard_fab2(sch_1):page77_i66:dqs16p" )
			)
			( pin "J1G1.52"
				( objectStatus "@baseboard_fab2_lib.baseboard_fab2(sch_1):page77_i66:dqs17n" )
			)
			( pin "J1G1.51"
				( objectStatus "@baseboard_fab2_lib.baseboard_fab2(sch_1):page77_i66:dqs17p" )
			)
			( pin "J1G1.79"
				( objectStatus "@baseboard_fab2_lib.baseboard_fab2(sch_1):page77_i111:a0" )
			)
			( pin "J1G1.72"
				( objectStatus "@baseboard_fab2_lib.baseboard_fab2(sch_1):page77_i111:a1" )
			)
			( pin "J1G1.216"
				( objectStatus "@baseboard_fab2_lib.baseboard_fab2(sch_1):page77_i111:a2" )
			)
			( pin "J1G1.71"
				( objectStatus "@baseboard_fab2_lib.baseboard_fab2(sch_1):page77_i111:a3" )
			)
			( pin "J1G1.214"
				( objectStatus "@baseboard_fab2_lib.baseboard_fab2(sch_1):page77_i111:a4" )
			)
			( pin "J1G1.213"
				( objectStatus "@baseboard_fab2_lib.baseboard_fab2(sch_1):page77_i111:a5" )
			)
			( pin "J1G1.69"
				( objectStatus "@baseboard_fab2_lib.baseboard_fab2(sch_1):page77_i111:a6" )
			)
			( pin "J1G1.211"
				( objectStatus "@baseboard_fab2_lib.baseboard_fab2(sch_1):page77_i111:a7" )
			)
			( pin "J1G1.68"
				( objectStatus "@baseboard_fab2_lib.baseboard_fab2(sch_1):page77_i111:a8" )
			)
			( pin "J1G1.66"
				( objectStatus "@baseboard_fab2_lib.baseboard_fab2(sch_1):page77_i111:a9" )
			)
			( pin "J1G1.225"
				( objectStatus "@baseboard_fab2_lib.baseboard_fab2(sch_1):page77_i111:a10" )
			)
			( pin "J1G1.210"
				( objectStatus "@baseboard_fab2_lib.baseboard_fab2(sch_1):page77_i111:a11" )
			)
			( pin "J1G1.65"
				( objectStatus "@baseboard_fab2_lib.baseboard_fab2(sch_1):page77_i111:a12" )
			)
			( pin "J1G1.232"
				( objectStatus "@baseboard_fab2_lib.baseboard_fab2(sch_1):page77_i111:a13" )
			)
			( pin "J1G1.228"
				( objectStatus "@baseboard_fab2_lib.baseboard_fab2(sch_1):page77_i111:a14_we_n" )
			)
			( pin "J1G1.86"
				( objectStatus "@baseboard_fab2_lib.baseboard_fab2(sch_1):page77_i111:a15_cas_n" )
			)
			( pin "J1G1.82"
				( objectStatus "@baseboard_fab2_lib.baseboard_fab2(sch_1):page77_i111:a16_ras_n" )
			)
			( pin "J1G1.234"
				( objectStatus "@baseboard_fab2_lib.baseboard_fab2(sch_1):page77_i111:a17" )
			)
			( pin "J1G1.62"
				( objectStatus "@baseboard_fab2_lib.baseboard_fab2(sch_1):page77_i111:act_n" )
			)
			( pin "J1G1.208"
				( objectStatus "@baseboard_fab2_lib.baseboard_fab2(sch_1):page77_i111:alert_n" )
			)
			( pin "J1G1.81"
				( objectStatus "@baseboard_fab2_lib.baseboard_fab2(sch_1):page77_i111:ba(0)" )
			)
			( pin "J1G1.224"
				( objectStatus "@baseboard_fab2_lib.baseboard_fab2(sch_1):page77_i111:ba(1)" )
			)
			( pin "J1G1.63"
				( objectStatus "@baseboard_fab2_lib.baseboard_fab2(sch_1):page77_i111:bg(0)" )
			)
			( pin "J1G1.207"
				( objectStatus "@baseboard_fab2_lib.baseboard_fab2(sch_1):page77_i111:bg(1)" )
			)
			( pin "J1G1.235"
				( objectStatus "@baseboard_fab2_lib.baseboard_fab2(sch_1):page77_i111:c(2)" )
			)
			( pin "J1G1.49"
				( objectStatus "@baseboard_fab2_lib.baseboard_fab2(sch_1):page77_i111:cb(0)" )
			)
			( pin "J1G1.194"
				( objectStatus "@baseboard_fab2_lib.baseboard_fab2(sch_1):page77_i111:cb(1)" )
			)
			( pin "J1G1.56"
				( objectStatus "@baseboard_fab2_lib.baseboard_fab2(sch_1):page77_i111:cb(2)" )
			)
			( pin "J1G1.201"
				( objectStatus "@baseboard_fab2_lib.baseboard_fab2(sch_1):page77_i111:cb(3)" )
			)
			( pin "J1G1.47"
				( objectStatus "@baseboard_fab2_lib.baseboard_fab2(sch_1):page77_i111:cb(4)" )
			)
			( pin "J1G1.192"
				( objectStatus "@baseboard_fab2_lib.baseboard_fab2(sch_1):page77_i111:cb(5)" )
			)
			( pin "J1G1.54"
				( objectStatus "@baseboard_fab2_lib.baseboard_fab2(sch_1):page77_i111:cb(6)" )
			)
			( pin "J1G1.199"
				( objectStatus "@baseboard_fab2_lib.baseboard_fab2(sch_1):page77_i111:cb(7)" )
			)
			( pin "J1G1.75"
				( objectStatus "@baseboard_fab2_lib.baseboard_fab2(sch_1):page77_i111:ck0n" )
			)
			( pin "J1G1.74"
				( objectStatus "@baseboard_fab2_lib.baseboard_fab2(sch_1):page77_i111:ck0p" )
			)
			( pin "J1G1.219"
				( objectStatus "@baseboard_fab2_lib.baseboard_fab2(sch_1):page77_i111:ck1n" )
			)
			( pin "J1G1.218"
				( objectStatus "@baseboard_fab2_lib.baseboard_fab2(sch_1):page77_i111:ck1p" )
			)
			( pin "J1G1.60"
				( objectStatus "@baseboard_fab2_lib.baseboard_fab2(sch_1):page77_i111:cke(0)" )
			)
			( pin "J1G1.203"
				( objectStatus "@baseboard_fab2_lib.baseboard_fab2(sch_1):page77_i111:cke(1)" )
			)
			( pin "J1G1.5"
				( objectStatus "@baseboard_fab2_lib.baseboard_fab2(sch_1):page77_i111:dq(0)" )
			)
			( pin "J1G1.150"
				( objectStatus "@baseboard_fab2_lib.baseboard_fab2(sch_1):page77_i111:dq(1)" )
			)
			( pin "J1G1.12"
				( objectStatus "@baseboard_fab2_lib.baseboard_fab2(sch_1):page77_i111:dq(2)" )
			)
			( pin "J1G1.157"
				( objectStatus "@baseboard_fab2_lib.baseboard_fab2(sch_1):page77_i111:dq(3)" )
			)
			( pin "J1G1.3"
				( objectStatus "@baseboard_fab2_lib.baseboard_fab2(sch_1):page77_i111:dq(4)" )
			)
			( pin "J1G1.148"
				( objectStatus "@baseboard_fab2_lib.baseboard_fab2(sch_1):page77_i111:dq(5)" )
			)
			( pin "J1G1.10"
				( objectStatus "@baseboard_fab2_lib.baseboard_fab2(sch_1):page77_i111:dq(6)" )
			)
			( pin "J1G1.155"
				( objectStatus "@baseboard_fab2_lib.baseboard_fab2(sch_1):page77_i111:dq(7)" )
			)
			( pin "J1G1.16"
				( objectStatus "@baseboard_fab2_lib.baseboard_fab2(sch_1):page77_i111:dq(8)" )
			)
			( pin "J1G1.161"
				( objectStatus "@baseboard_fab2_lib.baseboard_fab2(sch_1):page77_i111:dq(9)" )
			)
			( pin "J1G1.23"
				( objectStatus "@baseboard_fab2_lib.baseboard_fab2(sch_1):page77_i111:dq(10)" )
			)
			( pin "J1G1.168"
				( objectStatus "@baseboard_fab2_lib.baseboard_fab2(sch_1):page77_i111:dq(11)" )
			)
			( pin "J1G1.14"
				( objectStatus "@baseboard_fab2_lib.baseboard_fab2(sch_1):page77_i111:dq(12)" )
			)
			( pin "J1G1.159"
				( objectStatus "@baseboard_fab2_lib.baseboard_fab2(sch_1):page77_i111:dq(13)" )
			)
			( pin "J1G1.21"
				( objectStatus "@baseboard_fab2_lib.baseboard_fab2(sch_1):page77_i111:dq(14)" )
			)
			( pin "J1G1.166"
				( objectStatus "@baseboard_fab2_lib.baseboard_fab2(sch_1):page77_i111:dq(15)" )
			)
			( pin "J1G1.27"
				( objectStatus "@baseboard_fab2_lib.baseboard_fab2(sch_1):page77_i111:dq(16)" )
			)
			( pin "J1G1.172"
				( objectStatus "@baseboard_fab2_lib.baseboard_fab2(sch_1):page77_i111:dq(17)" )
			)
			( pin "J1G1.34"
				( objectStatus "@baseboard_fab2_lib.baseboard_fab2(sch_1):page77_i111:dq(18)" )
			)
			( pin "J1G1.179"
				( objectStatus "@baseboard_fab2_lib.baseboard_fab2(sch_1):page77_i111:dq(19)" )
			)
			( pin "J1G1.25"
				( objectStatus "@baseboard_fab2_lib.baseboard_fab2(sch_1):page77_i111:dq(20)" )
			)
			( pin "J1G1.170"
				( objectStatus "@baseboard_fab2_lib.baseboard_fab2(sch_1):page77_i111:dq(21)" )
			)
			( pin "J1G1.32"
				( objectStatus "@baseboard_fab2_lib.baseboard_fab2(sch_1):page77_i111:dq(22)" )
			)
			( pin "J1G1.177"
				( objectStatus "@baseboard_fab2_lib.baseboard_fab2(sch_1):page77_i111:dq(23)" )
			)
			( pin "J1G1.38"
				( objectStatus "@baseboard_fab2_lib.baseboard_fab2(sch_1):page77_i111:dq(24)" )
			)
			( pin "J1G1.183"
				( objectStatus "@baseboard_fab2_lib.baseboard_fab2(sch_1):page77_i111:dq(25)" )
			)
			( pin "J1G1.45"
				( objectStatus "@baseboard_fab2_lib.baseboard_fab2(sch_1):page77_i111:dq(26)" )
			)
			( pin "J1G1.190"
				( objectStatus "@baseboard_fab2_lib.baseboard_fab2(sch_1):page77_i111:dq(27)" )
			)
			( pin "J1G1.36"
				( objectStatus "@baseboard_fab2_lib.baseboard_fab2(sch_1):page77_i111:dq(28)" )
			)
			( pin "J1G1.181"
				( objectStatus "@baseboard_fab2_lib.baseboard_fab2(sch_1):page77_i111:dq(29)" )
			)
			( pin "J1G1.43"
				( objectStatus "@baseboard_fab2_lib.baseboard_fab2(sch_1):page77_i111:dq(30)" )
			)
			( pin "J1G1.188"
				( objectStatus "@baseboard_fab2_lib.baseboard_fab2(sch_1):page77_i111:dq(31)" )
			)
			( pin "J1G1.97"
				( objectStatus "@baseboard_fab2_lib.baseboard_fab2(sch_1):page77_i111:dq(32)" )
			)
			( pin "J1G1.242"
				( objectStatus "@baseboard_fab2_lib.baseboard_fab2(sch_1):page77_i111:dq(33)" )
			)
			( pin "J1G1.104"
				( objectStatus "@baseboard_fab2_lib.baseboard_fab2(sch_1):page77_i111:dq(34)" )
			)
			( pin "J1G1.249"
				( objectStatus "@baseboard_fab2_lib.baseboard_fab2(sch_1):page77_i111:dq(35)" )
			)
			( pin "J1G1.95"
				( objectStatus "@baseboard_fab2_lib.baseboard_fab2(sch_1):page77_i111:dq(36)" )
			)
			( pin "J1G1.240"
				( objectStatus "@baseboard_fab2_lib.baseboard_fab2(sch_1):page77_i111:dq(37)" )
			)
			( pin "J1G1.102"
				( objectStatus "@baseboard_fab2_lib.baseboard_fab2(sch_1):page77_i111:dq(38)" )
			)
			( pin "J1G1.247"
				( objectStatus "@baseboard_fab2_lib.baseboard_fab2(sch_1):page77_i111:dq(39)" )
			)
			( pin "J1G1.108"
				( objectStatus "@baseboard_fab2_lib.baseboard_fab2(sch_1):page77_i111:dq(40)" )
			)
			( pin "J1G1.253"
				( objectStatus "@baseboard_fab2_lib.baseboard_fab2(sch_1):page77_i111:dq(41)" )
			)
			( pin "J1G1.115"
				( objectStatus "@baseboard_fab2_lib.baseboard_fab2(sch_1):page77_i111:dq(42)" )
			)
			( pin "J1G1.260"
				( objectStatus "@baseboard_fab2_lib.baseboard_fab2(sch_1):page77_i111:dq(43)" )
			)
			( pin "J1G1.106"
				( objectStatus "@baseboard_fab2_lib.baseboard_fab2(sch_1):page77_i111:dq(44)" )
			)
			( pin "J1G1.251"
				( objectStatus "@baseboard_fab2_lib.baseboard_fab2(sch_1):page77_i111:dq(45)" )
			)
			( pin "J1G1.113"
				( objectStatus "@baseboard_fab2_lib.baseboard_fab2(sch_1):page77_i111:dq(46)" )
			)
			( pin "J1G1.258"
				( objectStatus "@baseboard_fab2_lib.baseboard_fab2(sch_1):page77_i111:dq(47)" )
			)
			( pin "J1G1.119"
				( objectStatus "@baseboard_fab2_lib.baseboard_fab2(sch_1):page77_i111:dq(48)" )
			)
			( pin "J1G1.264"
				( objectStatus "@baseboard_fab2_lib.baseboard_fab2(sch_1):page77_i111:dq(49)" )
			)
			( pin "J1G1.126"
				( objectStatus "@baseboard_fab2_lib.baseboard_fab2(sch_1):page77_i111:dq(50)" )
			)
			( pin "J1G1.271"
				( objectStatus "@baseboard_fab2_lib.baseboard_fab2(sch_1):page77_i111:dq(51)" )
			)
			( pin "J1G1.117"
				( objectStatus "@baseboard_fab2_lib.baseboard_fab2(sch_1):page77_i111:dq(52)" )
			)
			( pin "J1G1.262"
				( objectStatus "@baseboard_fab2_lib.baseboard_fab2(sch_1):page77_i111:dq(53)" )
			)
			( pin "J1G1.124"
				( objectStatus "@baseboard_fab2_lib.baseboard_fab2(sch_1):page77_i111:dq(54)" )
			)
			( pin "J1G1.269"
				( objectStatus "@baseboard_fab2_lib.baseboard_fab2(sch_1):page77_i111:dq(55)" )
			)
			( pin "J1G1.130"
				( objectStatus "@baseboard_fab2_lib.baseboard_fab2(sch_1):page77_i111:dq(56)" )
			)
			( pin "J1G1.275"
				( objectStatus "@baseboard_fab2_lib.baseboard_fab2(sch_1):page77_i111:dq(57)" )
			)
			( pin "J1G1.137"
				( objectStatus "@baseboard_fab2_lib.baseboard_fab2(sch_1):page77_i111:dq(58)" )
			)
			( pin "J1G1.282"
				( objectStatus "@baseboard_fab2_lib.baseboard_fab2(sch_1):page77_i111:dq(59)" )
			)
			( pin "J1G1.128"
				( objectStatus "@baseboard_fab2_lib.baseboard_fab2(sch_1):page77_i111:dq(60)" )
			)
			( pin "J1G1.273"
				( objectStatus "@baseboard_fab2_lib.baseboard_fab2(sch_1):page77_i111:dq(61)" )
			)
			( pin "J1G1.135"
				( objectStatus "@baseboard_fab2_lib.baseboard_fab2(sch_1):page77_i111:dq(62)" )
			)
			( pin "J1G1.280"
				( objectStatus "@baseboard_fab2_lib.baseboard_fab2(sch_1):page77_i111:dq(63)" )
			)
			( pin "J1G1.78"
				( objectStatus "@baseboard_fab2_lib.baseboard_fab2(sch_1):page77_i111:event_n" )
			)
			( pin "J1G1.87"
				( objectStatus "@baseboard_fab2_lib.baseboard_fab2(sch_1):page77_i111:odt(0)" )
			)
			( pin "J1G1.91"
				( objectStatus "@baseboard_fab2_lib.baseboard_fab2(sch_1):page77_i111:odt(1)" )
			)
			( pin "J1G1.222"
				( objectStatus "@baseboard_fab2_lib.baseboard_fab2(sch_1):page77_i111:par" )
			)
			( pin "J1G1.58"
				( objectStatus "@baseboard_fab2_lib.baseboard_fab2(sch_1):page77_i111:reset_n" )
			)
			( pin "J1G1.205"
				( objectStatus "@baseboard_fab2_lib.baseboard_fab2(sch_1):page77_i111:rfu(0)" )
			)
			( pin "J1G1.227"
				( objectStatus "@baseboard_fab2_lib.baseboard_fab2(sch_1):page77_i111:rfu(1)" )
			)
			( pin "J1G1.144"
				( objectStatus "@baseboard_fab2_lib.baseboard_fab2(sch_1):page77_i111:rfu(2)" )
			)
			( pin "J1G1.84"
				( objectStatus "@baseboard_fab2_lib.baseboard_fab2(sch_1):page77_i111:s0_n" )
			)
			( pin "J1G1.89"
				( objectStatus "@baseboard_fab2_lib.baseboard_fab2(sch_1):page77_i111:s1_n" )
			)
			( pin "J1G1.93"
				( objectStatus "@baseboard_fab2_lib.baseboard_fab2(sch_1):page77_i111:s2_n_c(0)" )
			)
			( pin "J1G1.237"
				( objectStatus "@baseboard_fab2_lib.baseboard_fab2(sch_1):page77_i111:s3_n_c(1)" )
			)
			( pin "J1G1.139"
				( objectStatus "@baseboard_fab2_lib.baseboard_fab2(sch_1):page77_i111:sa(0)" )
			)
			( pin "J1G1.140"
				( objectStatus "@baseboard_fab2_lib.baseboard_fab2(sch_1):page77_i111:sa(1)" )
			)
			( pin "J1G1.238"
				( objectStatus "@baseboard_fab2_lib.baseboard_fab2(sch_1):page77_i111:sa(2)" )
			)
			( pin "J1G1.230"
				( objectStatus "@baseboard_fab2_lib.baseboard_fab2(sch_1):page77_i111:save_n_nc" )
			)
			( pin "J1G1.141"
				( objectStatus "@baseboard_fab2_lib.baseboard_fab2(sch_1):page77_i111:scl" )
			)
			( pin "J1G1.285"
				( objectStatus "@baseboard_fab2_lib.baseboard_fab2(sch_1):page77_i111:sda" )
			)
			( pin "J1G1.284"
				( objectStatus "@baseboard_fab2_lib.baseboard_fab2(sch_1):page77_i111:vddspd" )
			)
			( pin "J1G1.146"
				( objectStatus "@baseboard_fab2_lib.baseboard_fab2(sch_1):page77_i111:vrefca" )
			)
			( pin "J1G1.145"
				( objectStatus "@baseboard_fab2_lib.baseboard_fab2(sch_1):page77_i171:\12v\(0)" )
			)
			( pin "J1G1.1"
				( objectStatus "@baseboard_fab2_lib.baseboard_fab2(sch_1):page77_i171:\12v\(1)" )
			)
			( pin "J1G1.236"
				( objectStatus "@baseboard_fab2_lib.baseboard_fab2(sch_1):page77_i171:vdd(0)" )
			)
			( pin "J1G1.233"
				( objectStatus "@baseboard_fab2_lib.baseboard_fab2(sch_1):page77_i171:vdd(1)" )
			)
			( pin "J1G1.231"
				( objectStatus "@baseboard_fab2_lib.baseboard_fab2(sch_1):page77_i171:vdd(2)" )
			)
			( pin "J1G1.229"
				( objectStatus "@baseboard_fab2_lib.baseboard_fab2(sch_1):page77_i171:vdd(3)" )
			)
			( pin "J1G1.226"
				( objectStatus "@baseboard_fab2_lib.baseboard_fab2(sch_1):page77_i171:vdd(4)" )
			)
			( pin "J1G1.223"
				( objectStatus "@baseboard_fab2_lib.baseboard_fab2(sch_1):page77_i171:vdd(5)" )
			)
			( pin "J1G1.220"
				( objectStatus "@baseboard_fab2_lib.baseboard_fab2(sch_1):page77_i171:vdd(6)" )
			)
			( pin "J1G1.217"
				( objectStatus "@baseboard_fab2_lib.baseboard_fab2(sch_1):page77_i171:vdd(7)" )
			)
			( pin "J1G1.215"
				( objectStatus "@baseboard_fab2_lib.baseboard_fab2(sch_1):page77_i171:vdd(8)" )
			)
			( pin "J1G1.212"
				( objectStatus "@baseboard_fab2_lib.baseboard_fab2(sch_1):page77_i171:vdd(9)" )
			)
			( pin "J1G1.209"
				( objectStatus "@baseboard_fab2_lib.baseboard_fab2(sch_1):page77_i171:vdd(10)" )
			)
			( pin "J1G1.206"
				( objectStatus "@baseboard_fab2_lib.baseboard_fab2(sch_1):page77_i171:vdd(11)" )
			)
			( pin "J1G1.204"
				( objectStatus "@baseboard_fab2_lib.baseboard_fab2(sch_1):page77_i171:vdd(12)" )
			)
			( pin "J1G1.92"
				( objectStatus "@baseboard_fab2_lib.baseboard_fab2(sch_1):page77_i171:vdd(13)" )
			)
			( pin "J1G1.90"
				( objectStatus "@baseboard_fab2_lib.baseboard_fab2(sch_1):page77_i171:vdd(14)" )
			)
			( pin "J1G1.88"
				( objectStatus "@baseboard_fab2_lib.baseboard_fab2(sch_1):page77_i171:vdd(15)" )
			)
			( pin "J1G1.85"
				( objectStatus "@baseboard_fab2_lib.baseboard_fab2(sch_1):page77_i171:vdd(16)" )
			)
			( pin "J1G1.83"
				( objectStatus "@baseboard_fab2_lib.baseboard_fab2(sch_1):page77_i171:vdd(17)" )
			)
			( pin "J1G1.80"
				( objectStatus "@baseboard_fab2_lib.baseboard_fab2(sch_1):page77_i171:vdd(18)" )
			)
			( pin "J1G1.76"
				( objectStatus "@baseboard_fab2_lib.baseboard_fab2(sch_1):page77_i171:vdd(19)" )
			)
			( pin "J1G1.73"
				( objectStatus "@baseboard_fab2_lib.baseboard_fab2(sch_1):page77_i171:vdd(20)" )
			)
			( pin "J1G1.70"
				( objectStatus "@baseboard_fab2_lib.baseboard_fab2(sch_1):page77_i171:vdd(21)" )
			)
			( pin "J1G1.67"
				( objectStatus "@baseboard_fab2_lib.baseboard_fab2(sch_1):page77_i171:vdd(22)" )
			)
			( pin "J1G1.64"
				( objectStatus "@baseboard_fab2_lib.baseboard_fab2(sch_1):page77_i171:vdd(23)" )
			)
			( pin "J1G1.61"
				( objectStatus "@baseboard_fab2_lib.baseboard_fab2(sch_1):page77_i171:vdd(24)" )
			)
			( pin "J1G1.59"
				( objectStatus "@baseboard_fab2_lib.baseboard_fab2(sch_1):page77_i171:vdd(25)" )
			)
			( pin "J1G1.287"
				( objectStatus "@baseboard_fab2_lib.baseboard_fab2(sch_1):page77_i171:vpp(0)" )
			)
			( pin "J1G1.286"
				( objectStatus "@baseboard_fab2_lib.baseboard_fab2(sch_1):page77_i171:vpp(1)" )
			)
			( pin "J1G1.288"
				( objectStatus "@baseboard_fab2_lib.baseboard_fab2(sch_1):page77_i171:vpp(2)" )
			)
			( pin "J1G1.143"
				( objectStatus "@baseboard_fab2_lib.baseboard_fab2(sch_1):page77_i171:vpp(3)" )
			)
			( pin "J1G1.142"
				( objectStatus "@baseboard_fab2_lib.baseboard_fab2(sch_1):page77_i171:vpp(4)" )
			)
			( pin "J1G1.221"
				( objectStatus "@baseboard_fab2_lib.baseboard_fab2(sch_1):page77_i171:vtt(0)" )
			)
			( pin "J1G1.77"
				( objectStatus "@baseboard_fab2_lib.baseboard_fab2(sch_1):page77_i171:vtt(1)" )
			)
			( pin "C1F22.1"
				( objectStatus "@baseboard_fab2_lib.baseboard_fab2(sch_1):page77_i181:a" )
			)
			( pin "C1F22.2"
				( objectStatus "@baseboard_fab2_lib.baseboard_fab2(sch_1):page77_i181:b" )
			)
			( pin "C9T7.1"
				( objectStatus "@baseboard_fab2_lib.baseboard_fab2(sch_1):page78_i2:a" )
			)
			( pin "C9T7.2"
				( objectStatus "@baseboard_fab2_lib.baseboard_fab2(sch_1):page78_i2:b" )
			)
			( pin "J9T1.79"
				( objectStatus "@baseboard_fab2_lib.baseboard_fab2(sch_1):page78_i13:a0" )
			)
			( pin "J9T1.72"
				( objectStatus "@baseboard_fab2_lib.baseboard_fab2(sch_1):page78_i13:a1" )
			)
			( pin "J9T1.216"
				( objectStatus "@baseboard_fab2_lib.baseboard_fab2(sch_1):page78_i13:a2" )
			)
			( pin "J9T1.71"
				( objectStatus "@baseboard_fab2_lib.baseboard_fab2(sch_1):page78_i13:a3" )
			)
			( pin "J9T1.214"
				( objectStatus "@baseboard_fab2_lib.baseboard_fab2(sch_1):page78_i13:a4" )
			)
			( pin "J9T1.213"
				( objectStatus "@baseboard_fab2_lib.baseboard_fab2(sch_1):page78_i13:a5" )
			)
			( pin "J9T1.69"
				( objectStatus "@baseboard_fab2_lib.baseboard_fab2(sch_1):page78_i13:a6" )
			)
			( pin "J9T1.211"
				( objectStatus "@baseboard_fab2_lib.baseboard_fab2(sch_1):page78_i13:a7" )
			)
			( pin "J9T1.68"
				( objectStatus "@baseboard_fab2_lib.baseboard_fab2(sch_1):page78_i13:a8" )
			)
			( pin "J9T1.66"
				( objectStatus "@baseboard_fab2_lib.baseboard_fab2(sch_1):page78_i13:a9" )
			)
			( pin "J9T1.225"
				( objectStatus "@baseboard_fab2_lib.baseboard_fab2(sch_1):page78_i13:a10" )
			)
			( pin "J9T1.210"
				( objectStatus "@baseboard_fab2_lib.baseboard_fab2(sch_1):page78_i13:a11" )
			)
			( pin "J9T1.65"
				( objectStatus "@baseboard_fab2_lib.baseboard_fab2(sch_1):page78_i13:a12" )
			)
			( pin "J9T1.232"
				( objectStatus "@baseboard_fab2_lib.baseboard_fab2(sch_1):page78_i13:a13" )
			)
			( pin "J9T1.228"
				( objectStatus "@baseboard_fab2_lib.baseboard_fab2(sch_1):page78_i13:a14_we_n" )
			)
			( pin "J9T1.86"
				( objectStatus "@baseboard_fab2_lib.baseboard_fab2(sch_1):page78_i13:a15_cas_n" )
			)
			( pin "J9T1.82"
				( objectStatus "@baseboard_fab2_lib.baseboard_fab2(sch_1):page78_i13:a16_ras_n" )
			)
			( pin "J9T1.234"
				( objectStatus "@baseboard_fab2_lib.baseboard_fab2(sch_1):page78_i13:a17" )
			)
			( pin "J9T1.62"
				( objectStatus "@baseboard_fab2_lib.baseboard_fab2(sch_1):page78_i13:act_n" )
			)
			( pin "J9T1.208"
				( objectStatus "@baseboard_fab2_lib.baseboard_fab2(sch_1):page78_i13:alert_n" )
			)
			( pin "J9T1.81"
				( objectStatus "@baseboard_fab2_lib.baseboard_fab2(sch_1):page78_i13:ba(0)" )
			)
			( pin "J9T1.224"
				( objectStatus "@baseboard_fab2_lib.baseboard_fab2(sch_1):page78_i13:ba(1)" )
			)
			( pin "J9T1.63"
				( objectStatus "@baseboard_fab2_lib.baseboard_fab2(sch_1):page78_i13:bg(0)" )
			)
			( pin "J9T1.207"
				( objectStatus "@baseboard_fab2_lib.baseboard_fab2(sch_1):page78_i13:bg(1)" )
			)
			( pin "J9T1.235"
				( objectStatus "@baseboard_fab2_lib.baseboard_fab2(sch_1):page78_i13:c(2)" )
			)
			( pin "J9T1.49"
				( objectStatus "@baseboard_fab2_lib.baseboard_fab2(sch_1):page78_i13:cb(0)" )
			)
			( pin "J9T1.194"
				( objectStatus "@baseboard_fab2_lib.baseboard_fab2(sch_1):page78_i13:cb(1)" )
			)
			( pin "J9T1.56"
				( objectStatus "@baseboard_fab2_lib.baseboard_fab2(sch_1):page78_i13:cb(2)" )
			)
			( pin "J9T1.201"
				( objectStatus "@baseboard_fab2_lib.baseboard_fab2(sch_1):page78_i13:cb(3)" )
			)
			( pin "J9T1.47"
				( objectStatus "@baseboard_fab2_lib.baseboard_fab2(sch_1):page78_i13:cb(4)" )
			)
			( pin "J9T1.192"
				( objectStatus "@baseboard_fab2_lib.baseboard_fab2(sch_1):page78_i13:cb(5)" )
			)
			( pin "J9T1.54"
				( objectStatus "@baseboard_fab2_lib.baseboard_fab2(sch_1):page78_i13:cb(6)" )
			)
			( pin "J9T1.199"
				( objectStatus "@baseboard_fab2_lib.baseboard_fab2(sch_1):page78_i13:cb(7)" )
			)
			( pin "J9T1.75"
				( objectStatus "@baseboard_fab2_lib.baseboard_fab2(sch_1):page78_i13:ck0n" )
			)
			( pin "J9T1.74"
				( objectStatus "@baseboard_fab2_lib.baseboard_fab2(sch_1):page78_i13:ck0p" )
			)
			( pin "J9T1.219"
				( objectStatus "@baseboard_fab2_lib.baseboard_fab2(sch_1):page78_i13:ck1n" )
			)
			( pin "J9T1.218"
				( objectStatus "@baseboard_fab2_lib.baseboard_fab2(sch_1):page78_i13:ck1p" )
			)
			( pin "J9T1.60"
				( objectStatus "@baseboard_fab2_lib.baseboard_fab2(sch_1):page78_i13:cke(0)" )
			)
			( pin "J9T1.203"
				( objectStatus "@baseboard_fab2_lib.baseboard_fab2(sch_1):page78_i13:cke(1)" )
			)
			( pin "J9T1.5"
				( objectStatus "@baseboard_fab2_lib.baseboard_fab2(sch_1):page78_i13:dq(0)" )
			)
			( pin "J9T1.150"
				( objectStatus "@baseboard_fab2_lib.baseboard_fab2(sch_1):page78_i13:dq(1)" )
			)
			( pin "J9T1.12"
				( objectStatus "@baseboard_fab2_lib.baseboard_fab2(sch_1):page78_i13:dq(2)" )
			)
			( pin "J9T1.157"
				( objectStatus "@baseboard_fab2_lib.baseboard_fab2(sch_1):page78_i13:dq(3)" )
			)
			( pin "J9T1.3"
				( objectStatus "@baseboard_fab2_lib.baseboard_fab2(sch_1):page78_i13:dq(4)" )
			)
			( pin "J9T1.148"
				( objectStatus "@baseboard_fab2_lib.baseboard_fab2(sch_1):page78_i13:dq(5)" )
			)
			( pin "J9T1.10"
				( objectStatus "@baseboard_fab2_lib.baseboard_fab2(sch_1):page78_i13:dq(6)" )
			)
			( pin "J9T1.155"
				( objectStatus "@baseboard_fab2_lib.baseboard_fab2(sch_1):page78_i13:dq(7)" )
			)
			( pin "J9T1.16"
				( objectStatus "@baseboard_fab2_lib.baseboard_fab2(sch_1):page78_i13:dq(8)" )
			)
			( pin "J9T1.161"
				( objectStatus "@baseboard_fab2_lib.baseboard_fab2(sch_1):page78_i13:dq(9)" )
			)
			( pin "J9T1.23"
				( objectStatus "@baseboard_fab2_lib.baseboard_fab2(sch_1):page78_i13:dq(10)" )
			)
			( pin "J9T1.168"
				( objectStatus "@baseboard_fab2_lib.baseboard_fab2(sch_1):page78_i13:dq(11)" )
			)
			( pin "J9T1.14"
				( objectStatus "@baseboard_fab2_lib.baseboard_fab2(sch_1):page78_i13:dq(12)" )
			)
			( pin "J9T1.159"
				( objectStatus "@baseboard_fab2_lib.baseboard_fab2(sch_1):page78_i13:dq(13)" )
			)
			( pin "J9T1.21"
				( objectStatus "@baseboard_fab2_lib.baseboard_fab2(sch_1):page78_i13:dq(14)" )
			)
			( pin "J9T1.166"
				( objectStatus "@baseboard_fab2_lib.baseboard_fab2(sch_1):page78_i13:dq(15)" )
			)
			( pin "J9T1.27"
				( objectStatus "@baseboard_fab2_lib.baseboard_fab2(sch_1):page78_i13:dq(16)" )
			)
			( pin "J9T1.172"
				( objectStatus "@baseboard_fab2_lib.baseboard_fab2(sch_1):page78_i13:dq(17)" )
			)
			( pin "J9T1.34"
				( objectStatus "@baseboard_fab2_lib.baseboard_fab2(sch_1):page78_i13:dq(18)" )
			)
			( pin "J9T1.179"
				( objectStatus "@baseboard_fab2_lib.baseboard_fab2(sch_1):page78_i13:dq(19)" )
			)
			( pin "J9T1.25"
				( objectStatus "@baseboard_fab2_lib.baseboard_fab2(sch_1):page78_i13:dq(20)" )
			)
			( pin "J9T1.170"
				( objectStatus "@baseboard_fab2_lib.baseboard_fab2(sch_1):page78_i13:dq(21)" )
			)
			( pin "J9T1.32"
				( objectStatus "@baseboard_fab2_lib.baseboard_fab2(sch_1):page78_i13:dq(22)" )
			)
			( pin "J9T1.177"
				( objectStatus "@baseboard_fab2_lib.baseboard_fab2(sch_1):page78_i13:dq(23)" )
			)
			( pin "J9T1.38"
				( objectStatus "@baseboard_fab2_lib.baseboard_fab2(sch_1):page78_i13:dq(24)" )
			)
			( pin "J9T1.183"
				( objectStatus "@baseboard_fab2_lib.baseboard_fab2(sch_1):page78_i13:dq(25)" )
			)
			( pin "J9T1.45"
				( objectStatus "@baseboard_fab2_lib.baseboard_fab2(sch_1):page78_i13:dq(26)" )
			)
			( pin "J9T1.190"
				( objectStatus "@baseboard_fab2_lib.baseboard_fab2(sch_1):page78_i13:dq(27)" )
			)
			( pin "J9T1.36"
				( objectStatus "@baseboard_fab2_lib.baseboard_fab2(sch_1):page78_i13:dq(28)" )
			)
			( pin "J9T1.181"
				( objectStatus "@baseboard_fab2_lib.baseboard_fab2(sch_1):page78_i13:dq(29)" )
			)
			( pin "J9T1.43"
				( objectStatus "@baseboard_fab2_lib.baseboard_fab2(sch_1):page78_i13:dq(30)" )
			)
			( pin "J9T1.188"
				( objectStatus "@baseboard_fab2_lib.baseboard_fab2(sch_1):page78_i13:dq(31)" )
			)
			( pin "J9T1.97"
				( objectStatus "@baseboard_fab2_lib.baseboard_fab2(sch_1):page78_i13:dq(32)" )
			)
			( pin "J9T1.242"
				( objectStatus "@baseboard_fab2_lib.baseboard_fab2(sch_1):page78_i13:dq(33)" )
			)
			( pin "J9T1.104"
				( objectStatus "@baseboard_fab2_lib.baseboard_fab2(sch_1):page78_i13:dq(34)" )
			)
			( pin "J9T1.249"
				( objectStatus "@baseboard_fab2_lib.baseboard_fab2(sch_1):page78_i13:dq(35)" )
			)
			( pin "J9T1.95"
				( objectStatus "@baseboard_fab2_lib.baseboard_fab2(sch_1):page78_i13:dq(36)" )
			)
			( pin "J9T1.240"
				( objectStatus "@baseboard_fab2_lib.baseboard_fab2(sch_1):page78_i13:dq(37)" )
			)
			( pin "J9T1.102"
				( objectStatus "@baseboard_fab2_lib.baseboard_fab2(sch_1):page78_i13:dq(38)" )
			)
			( pin "J9T1.247"
				( objectStatus "@baseboard_fab2_lib.baseboard_fab2(sch_1):page78_i13:dq(39)" )
			)
			( pin "J9T1.108"
				( objectStatus "@baseboard_fab2_lib.baseboard_fab2(sch_1):page78_i13:dq(40)" )
			)
			( pin "J9T1.253"
				( objectStatus "@baseboard_fab2_lib.baseboard_fab2(sch_1):page78_i13:dq(41)" )
			)
			( pin "J9T1.115"
				( objectStatus "@baseboard_fab2_lib.baseboard_fab2(sch_1):page78_i13:dq(42)" )
			)
			( pin "J9T1.260"
				( objectStatus "@baseboard_fab2_lib.baseboard_fab2(sch_1):page78_i13:dq(43)" )
			)
			( pin "J9T1.106"
				( objectStatus "@baseboard_fab2_lib.baseboard_fab2(sch_1):page78_i13:dq(44)" )
			)
			( pin "J9T1.251"
				( objectStatus "@baseboard_fab2_lib.baseboard_fab2(sch_1):page78_i13:dq(45)" )
			)
			( pin "J9T1.113"
				( objectStatus "@baseboard_fab2_lib.baseboard_fab2(sch_1):page78_i13:dq(46)" )
			)
			( pin "J9T1.258"
				( objectStatus "@baseboard_fab2_lib.baseboard_fab2(sch_1):page78_i13:dq(47)" )
			)
			( pin "J9T1.119"
				( objectStatus "@baseboard_fab2_lib.baseboard_fab2(sch_1):page78_i13:dq(48)" )
			)
			( pin "J9T1.264"
				( objectStatus "@baseboard_fab2_lib.baseboard_fab2(sch_1):page78_i13:dq(49)" )
			)
			( pin "J9T1.126"
				( objectStatus "@baseboard_fab2_lib.baseboard_fab2(sch_1):page78_i13:dq(50)" )
			)
			( pin "J9T1.271"
				( objectStatus "@baseboard_fab2_lib.baseboard_fab2(sch_1):page78_i13:dq(51)" )
			)
			( pin "J9T1.117"
				( objectStatus "@baseboard_fab2_lib.baseboard_fab2(sch_1):page78_i13:dq(52)" )
			)
			( pin "J9T1.262"
				( objectStatus "@baseboard_fab2_lib.baseboard_fab2(sch_1):page78_i13:dq(53)" )
			)
			( pin "J9T1.124"
				( objectStatus "@baseboard_fab2_lib.baseboard_fab2(sch_1):page78_i13:dq(54)" )
			)
			( pin "J9T1.269"
				( objectStatus "@baseboard_fab2_lib.baseboard_fab2(sch_1):page78_i13:dq(55)" )
			)
			( pin "J9T1.130"
				( objectStatus "@baseboard_fab2_lib.baseboard_fab2(sch_1):page78_i13:dq(56)" )
			)
			( pin "J9T1.275"
				( objectStatus "@baseboard_fab2_lib.baseboard_fab2(sch_1):page78_i13:dq(57)" )
			)
			( pin "J9T1.137"
				( objectStatus "@baseboard_fab2_lib.baseboard_fab2(sch_1):page78_i13:dq(58)" )
			)
			( pin "J9T1.282"
				( objectStatus "@baseboard_fab2_lib.baseboard_fab2(sch_1):page78_i13:dq(59)" )
			)
			( pin "J9T1.128"
				( objectStatus "@baseboard_fab2_lib.baseboard_fab2(sch_1):page78_i13:dq(60)" )
			)
			( pin "J9T1.273"
				( objectStatus "@baseboard_fab2_lib.baseboard_fab2(sch_1):page78_i13:dq(61)" )
			)
			( pin "J9T1.135"
				( objectStatus "@baseboard_fab2_lib.baseboard_fab2(sch_1):page78_i13:dq(62)" )
			)
			( pin "J9T1.280"
				( objectStatus "@baseboard_fab2_lib.baseboard_fab2(sch_1):page78_i13:dq(63)" )
			)
			( pin "J9T1.78"
				( objectStatus "@baseboard_fab2_lib.baseboard_fab2(sch_1):page78_i13:event_n" )
			)
			( pin "J9T1.87"
				( objectStatus "@baseboard_fab2_lib.baseboard_fab2(sch_1):page78_i13:odt(0)" )
			)
			( pin "J9T1.91"
				( objectStatus "@baseboard_fab2_lib.baseboard_fab2(sch_1):page78_i13:odt(1)" )
			)
			( pin "J9T1.222"
				( objectStatus "@baseboard_fab2_lib.baseboard_fab2(sch_1):page78_i13:par" )
			)
			( pin "J9T1.58"
				( objectStatus "@baseboard_fab2_lib.baseboard_fab2(sch_1):page78_i13:reset_n" )
			)
			( pin "J9T1.205"
				( objectStatus "@baseboard_fab2_lib.baseboard_fab2(sch_1):page78_i13:rfu(0)" )
			)
			( pin "J9T1.227"
				( objectStatus "@baseboard_fab2_lib.baseboard_fab2(sch_1):page78_i13:rfu(1)" )
			)
			( pin "J9T1.144"
				( objectStatus "@baseboard_fab2_lib.baseboard_fab2(sch_1):page78_i13:rfu(2)" )
			)
			( pin "J9T1.84"
				( objectStatus "@baseboard_fab2_lib.baseboard_fab2(sch_1):page78_i13:s0_n" )
			)
			( pin "J9T1.89"
				( objectStatus "@baseboard_fab2_lib.baseboard_fab2(sch_1):page78_i13:s1_n" )
			)
			( pin "J9T1.93"
				( objectStatus "@baseboard_fab2_lib.baseboard_fab2(sch_1):page78_i13:s2_n_c(0)" )
			)
			( pin "J9T1.237"
				( objectStatus "@baseboard_fab2_lib.baseboard_fab2(sch_1):page78_i13:s3_n_c(1)" )
			)
			( pin "J9T1.139"
				( objectStatus "@baseboard_fab2_lib.baseboard_fab2(sch_1):page78_i13:sa(0)" )
			)
			( pin "J9T1.140"
				( objectStatus "@baseboard_fab2_lib.baseboard_fab2(sch_1):page78_i13:sa(1)" )
			)
			( pin "J9T1.238"
				( objectStatus "@baseboard_fab2_lib.baseboard_fab2(sch_1):page78_i13:sa(2)" )
			)
			( pin "J9T1.230"
				( objectStatus "@baseboard_fab2_lib.baseboard_fab2(sch_1):page78_i13:save_n_nc" )
			)
			( pin "J9T1.141"
				( objectStatus "@baseboard_fab2_lib.baseboard_fab2(sch_1):page78_i13:scl" )
			)
			( pin "J9T1.285"
				( objectStatus "@baseboard_fab2_lib.baseboard_fab2(sch_1):page78_i13:sda" )
			)
			( pin "J9T1.284"
				( objectStatus "@baseboard_fab2_lib.baseboard_fab2(sch_1):page78_i13:vddspd" )
			)
			( pin "J9T1.146"
				( objectStatus "@baseboard_fab2_lib.baseboard_fab2(sch_1):page78_i13:vrefca" )
			)
			( pin "J9T1.145"
				( objectStatus "@baseboard_fab2_lib.baseboard_fab2(sch_1):page78_i75:\12v\(0)" )
			)
			( pin "J9T1.1"
				( objectStatus "@baseboard_fab2_lib.baseboard_fab2(sch_1):page78_i75:\12v\(1)" )
			)
			( pin "J9T1.236"
				( objectStatus "@baseboard_fab2_lib.baseboard_fab2(sch_1):page78_i75:vdd(0)" )
			)
			( pin "J9T1.233"
				( objectStatus "@baseboard_fab2_lib.baseboard_fab2(sch_1):page78_i75:vdd(1)" )
			)
			( pin "J9T1.231"
				( objectStatus "@baseboard_fab2_lib.baseboard_fab2(sch_1):page78_i75:vdd(2)" )
			)
			( pin "J9T1.229"
				( objectStatus "@baseboard_fab2_lib.baseboard_fab2(sch_1):page78_i75:vdd(3)" )
			)
			( pin "J9T1.226"
				( objectStatus "@baseboard_fab2_lib.baseboard_fab2(sch_1):page78_i75:vdd(4)" )
			)
			( pin "J9T1.223"
				( objectStatus "@baseboard_fab2_lib.baseboard_fab2(sch_1):page78_i75:vdd(5)" )
			)
			( pin "J9T1.220"
				( objectStatus "@baseboard_fab2_lib.baseboard_fab2(sch_1):page78_i75:vdd(6)" )
			)
			( pin "J9T1.217"
				( objectStatus "@baseboard_fab2_lib.baseboard_fab2(sch_1):page78_i75:vdd(7)" )
			)
			( pin "J9T1.215"
				( objectStatus "@baseboard_fab2_lib.baseboard_fab2(sch_1):page78_i75:vdd(8)" )
			)
			( pin "J9T1.212"
				( objectStatus "@baseboard_fab2_lib.baseboard_fab2(sch_1):page78_i75:vdd(9)" )
			)
			( pin "J9T1.209"
				( objectStatus "@baseboard_fab2_lib.baseboard_fab2(sch_1):page78_i75:vdd(10)" )
			)
			( pin "J9T1.206"
				( objectStatus "@baseboard_fab2_lib.baseboard_fab2(sch_1):page78_i75:vdd(11)" )
			)
			( pin "J9T1.204"
				( objectStatus "@baseboard_fab2_lib.baseboard_fab2(sch_1):page78_i75:vdd(12)" )
			)
			( pin "J9T1.92"
				( objectStatus "@baseboard_fab2_lib.baseboard_fab2(sch_1):page78_i75:vdd(13)" )
			)
			( pin "J9T1.90"
				( objectStatus "@baseboard_fab2_lib.baseboard_fab2(sch_1):page78_i75:vdd(14)" )
			)
			( pin "J9T1.88"
				( objectStatus "@baseboard_fab2_lib.baseboard_fab2(sch_1):page78_i75:vdd(15)" )
			)
			( pin "J9T1.85"
				( objectStatus "@baseboard_fab2_lib.baseboard_fab2(sch_1):page78_i75:vdd(16)" )
			)
			( pin "J9T1.83"
				( objectStatus "@baseboard_fab2_lib.baseboard_fab2(sch_1):page78_i75:vdd(17)" )
			)
			( pin "J9T1.80"
				( objectStatus "@baseboard_fab2_lib.baseboard_fab2(sch_1):page78_i75:vdd(18)" )
			)
			( pin "J9T1.76"
				( objectStatus "@baseboard_fab2_lib.baseboard_fab2(sch_1):page78_i75:vdd(19)" )
			)
			( pin "J9T1.73"
				( objectStatus "@baseboard_fab2_lib.baseboard_fab2(sch_1):page78_i75:vdd(20)" )
			)
			( pin "J9T1.70"
				( objectStatus "@baseboard_fab2_lib.baseboard_fab2(sch_1):page78_i75:vdd(21)" )
			)
			( pin "J9T1.67"
				( objectStatus "@baseboard_fab2_lib.baseboard_fab2(sch_1):page78_i75:vdd(22)" )
			)
			( pin "J9T1.64"
				( objectStatus "@baseboard_fab2_lib.baseboard_fab2(sch_1):page78_i75:vdd(23)" )
			)
			( pin "J9T1.61"
				( objectStatus "@baseboard_fab2_lib.baseboard_fab2(sch_1):page78_i75:vdd(24)" )
			)
			( pin "J9T1.59"
				( objectStatus "@baseboard_fab2_lib.baseboard_fab2(sch_1):page78_i75:vdd(25)" )
			)
			( pin "J9T1.287"
				( objectStatus "@baseboard_fab2_lib.baseboard_fab2(sch_1):page78_i75:vpp(0)" )
			)
			( pin "J9T1.286"
				( objectStatus "@baseboard_fab2_lib.baseboard_fab2(sch_1):page78_i75:vpp(1)" )
			)
			( pin "J9T1.288"
				( objectStatus "@baseboard_fab2_lib.baseboard_fab2(sch_1):page78_i75:vpp(2)" )
			)
			( pin "J9T1.143"
				( objectStatus "@baseboard_fab2_lib.baseboard_fab2(sch_1):page78_i75:vpp(3)" )
			)
			( pin "J9T1.142"
				( objectStatus "@baseboard_fab2_lib.baseboard_fab2(sch_1):page78_i75:vpp(4)" )
			)
			( pin "J9T1.221"
				( objectStatus "@baseboard_fab2_lib.baseboard_fab2(sch_1):page78_i75:vtt(0)" )
			)
			( pin "J9T1.77"
				( objectStatus "@baseboard_fab2_lib.baseboard_fab2(sch_1):page78_i75:vtt(1)" )
			)
			( pin "J9T1.152"
				( objectStatus "@baseboard_fab2_lib.baseboard_fab2(sch_1):page78_i120:dqs0n" )
			)
			( pin "J9T1.153"
				( objectStatus "@baseboard_fab2_lib.baseboard_fab2(sch_1):page78_i120:dqs0p" )
			)
			( pin "J9T1.163"
				( objectStatus "@baseboard_fab2_lib.baseboard_fab2(sch_1):page78_i120:dqs1n" )
			)
			( pin "J9T1.164"
				( objectStatus "@baseboard_fab2_lib.baseboard_fab2(sch_1):page78_i120:dqs1p" )
			)
			( pin "J9T1.174"
				( objectStatus "@baseboard_fab2_lib.baseboard_fab2(sch_1):page78_i120:dqs2n" )
			)
			( pin "J9T1.175"
				( objectStatus "@baseboard_fab2_lib.baseboard_fab2(sch_1):page78_i120:dqs2p" )
			)
			( pin "J9T1.185"
				( objectStatus "@baseboard_fab2_lib.baseboard_fab2(sch_1):page78_i120:dqs3n" )
			)
			( pin "J9T1.186"
				( objectStatus "@baseboard_fab2_lib.baseboard_fab2(sch_1):page78_i120:dqs3p" )
			)
			( pin "J9T1.244"
				( objectStatus "@baseboard_fab2_lib.baseboard_fab2(sch_1):page78_i120:dqs4n" )
			)
			( pin "J9T1.245"
				( objectStatus "@baseboard_fab2_lib.baseboard_fab2(sch_1):page78_i120:dqs4p" )
			)
			( pin "J9T1.255"
				( objectStatus "@baseboard_fab2_lib.baseboard_fab2(sch_1):page78_i120:dqs5n" )
			)
			( pin "J9T1.256"
				( objectStatus "@baseboard_fab2_lib.baseboard_fab2(sch_1):page78_i120:dqs5p" )
			)
			( pin "J9T1.266"
				( objectStatus "@baseboard_fab2_lib.baseboard_fab2(sch_1):page78_i120:dqs6n" )
			)
			( pin "J9T1.267"
				( objectStatus "@baseboard_fab2_lib.baseboard_fab2(sch_1):page78_i120:dqs6p" )
			)
			( pin "J9T1.277"
				( objectStatus "@baseboard_fab2_lib.baseboard_fab2(sch_1):page78_i120:dqs7n" )
			)
			( pin "J9T1.278"
				( objectStatus "@baseboard_fab2_lib.baseboard_fab2(sch_1):page78_i120:dqs7p" )
			)
			( pin "J9T1.196"
				( objectStatus "@baseboard_fab2_lib.baseboard_fab2(sch_1):page78_i120:dqs8n" )
			)
			( pin "J9T1.197"
				( objectStatus "@baseboard_fab2_lib.baseboard_fab2(sch_1):page78_i120:dqs8p" )
			)
			( pin "J9T1.8"
				( objectStatus "@baseboard_fab2_lib.baseboard_fab2(sch_1):page78_i120:dqs9n" )
			)
			( pin "J9T1.7"
				( objectStatus "@baseboard_fab2_lib.baseboard_fab2(sch_1):page78_i120:dqs9p" )
			)
			( pin "J9T1.19"
				( objectStatus "@baseboard_fab2_lib.baseboard_fab2(sch_1):page78_i120:dqs10n" )
			)
			( pin "J9T1.18"
				( objectStatus "@baseboard_fab2_lib.baseboard_fab2(sch_1):page78_i120:dqs10p" )
			)
			( pin "J9T1.30"
				( objectStatus "@baseboard_fab2_lib.baseboard_fab2(sch_1):page78_i120:dqs11n" )
			)
			( pin "J9T1.29"
				( objectStatus "@baseboard_fab2_lib.baseboard_fab2(sch_1):page78_i120:dqs11p" )
			)
			( pin "J9T1.41"
				( objectStatus "@baseboard_fab2_lib.baseboard_fab2(sch_1):page78_i120:dqs12n" )
			)
			( pin "J9T1.40"
				( objectStatus "@baseboard_fab2_lib.baseboard_fab2(sch_1):page78_i120:dqs12p" )
			)
			( pin "J9T1.100"
				( objectStatus "@baseboard_fab2_lib.baseboard_fab2(sch_1):page78_i120:dqs13n" )
			)
			( pin "J9T1.99"
				( objectStatus "@baseboard_fab2_lib.baseboard_fab2(sch_1):page78_i120:dqs13p" )
			)
			( pin "J9T1.111"
				( objectStatus "@baseboard_fab2_lib.baseboard_fab2(sch_1):page78_i120:dqs14n" )
			)
			( pin "J9T1.110"
				( objectStatus "@baseboard_fab2_lib.baseboard_fab2(sch_1):page78_i120:dqs14p" )
			)
			( pin "J9T1.122"
				( objectStatus "@baseboard_fab2_lib.baseboard_fab2(sch_1):page78_i120:dqs15n" )
			)
			( pin "J9T1.121"
				( objectStatus "@baseboard_fab2_lib.baseboard_fab2(sch_1):page78_i120:dqs15p" )
			)
			( pin "J9T1.133"
				( objectStatus "@baseboard_fab2_lib.baseboard_fab2(sch_1):page78_i120:dqs16n" )
			)
			( pin "J9T1.132"
				( objectStatus "@baseboard_fab2_lib.baseboard_fab2(sch_1):page78_i120:dqs16p" )
			)
			( pin "J9T1.52"
				( objectStatus "@baseboard_fab2_lib.baseboard_fab2(sch_1):page78_i120:dqs17n" )
			)
			( pin "J9T1.51"
				( objectStatus "@baseboard_fab2_lib.baseboard_fab2(sch_1):page78_i120:dqs17p" )
			)
			( pin "J9T1.283"
				( objectStatus "@baseboard_fab2_lib.baseboard_fab2(sch_1):page78_i144:vss(0)" )
			)
			( pin "J9T1.281"
				( objectStatus "@baseboard_fab2_lib.baseboard_fab2(sch_1):page78_i144:vss(1)" )
			)
			( pin "J9T1.279"
				( objectStatus "@baseboard_fab2_lib.baseboard_fab2(sch_1):page78_i144:vss(2)" )
			)
			( pin "J9T1.276"
				( objectStatus "@baseboard_fab2_lib.baseboard_fab2(sch_1):page78_i144:vss(3)" )
			)
			( pin "J9T1.274"
				( objectStatus "@baseboard_fab2_lib.baseboard_fab2(sch_1):page78_i144:vss(4)" )
			)
			( pin "J9T1.272"
				( objectStatus "@baseboard_fab2_lib.baseboard_fab2(sch_1):page78_i144:vss(5)" )
			)
			( pin "J9T1.270"
				( objectStatus "@baseboard_fab2_lib.baseboard_fab2(sch_1):page78_i144:vss(6)" )
			)
			( pin "J9T1.268"
				( objectStatus "@baseboard_fab2_lib.baseboard_fab2(sch_1):page78_i144:vss(7)" )
			)
			( pin "J9T1.265"
				( objectStatus "@baseboard_fab2_lib.baseboard_fab2(sch_1):page78_i144:vss(8)" )
			)
			( pin "J9T1.263"
				( objectStatus "@baseboard_fab2_lib.baseboard_fab2(sch_1):page78_i144:vss(9)" )
			)
			( pin "J9T1.261"
				( objectStatus "@baseboard_fab2_lib.baseboard_fab2(sch_1):page78_i144:vss(10)" )
			)
			( pin "J9T1.259"
				( objectStatus "@baseboard_fab2_lib.baseboard_fab2(sch_1):page78_i144:vss(11)" )
			)
			( pin "J9T1.257"
				( objectStatus "@baseboard_fab2_lib.baseboard_fab2(sch_1):page78_i144:vss(12)" )
			)
			( pin "J9T1.254"
				( objectStatus "@baseboard_fab2_lib.baseboard_fab2(sch_1):page78_i144:vss(13)" )
			)
			( pin "J9T1.252"
				( objectStatus "@baseboard_fab2_lib.baseboard_fab2(sch_1):page78_i144:vss(14)" )
			)
			( pin "J9T1.250"
				( objectStatus "@baseboard_fab2_lib.baseboard_fab2(sch_1):page78_i144:vss(15)" )
			)
			( pin "J9T1.248"
				( objectStatus "@baseboard_fab2_lib.baseboard_fab2(sch_1):page78_i144:vss(16)" )
			)
			( pin "J9T1.246"
				( objectStatus "@baseboard_fab2_lib.baseboard_fab2(sch_1):page78_i144:vss(17)" )
			)
			( pin "J9T1.243"
				( objectStatus "@baseboard_fab2_lib.baseboard_fab2(sch_1):page78_i144:vss(18)" )
			)
			( pin "J9T1.241"
				( objectStatus "@baseboard_fab2_lib.baseboard_fab2(sch_1):page78_i144:vss(19)" )
			)
			( pin "J9T1.239"
				( objectStatus "@baseboard_fab2_lib.baseboard_fab2(sch_1):page78_i144:vss(20)" )
			)
			( pin "J9T1.202"
				( objectStatus "@baseboard_fab2_lib.baseboard_fab2(sch_1):page78_i144:vss(21)" )
			)
			( pin "J9T1.200"
				( objectStatus "@baseboard_fab2_lib.baseboard_fab2(sch_1):page78_i144:vss(22)" )
			)
			( pin "J9T1.198"
				( objectStatus "@baseboard_fab2_lib.baseboard_fab2(sch_1):page78_i144:vss(23)" )
			)
			( pin "J9T1.195"
				( objectStatus "@baseboard_fab2_lib.baseboard_fab2(sch_1):page78_i144:vss(24)" )
			)
			( pin "J9T1.193"
				( objectStatus "@baseboard_fab2_lib.baseboard_fab2(sch_1):page78_i144:vss(25)" )
			)
			( pin "J9T1.191"
				( objectStatus "@baseboard_fab2_lib.baseboard_fab2(sch_1):page78_i144:vss(26)" )
			)
			( pin "J9T1.189"
				( objectStatus "@baseboard_fab2_lib.baseboard_fab2(sch_1):page78_i144:vss(27)" )
			)
			( pin "J9T1.187"
				( objectStatus "@baseboard_fab2_lib.baseboard_fab2(sch_1):page78_i144:vss(28)" )
			)
			( pin "J9T1.184"
				( objectStatus "@baseboard_fab2_lib.baseboard_fab2(sch_1):page78_i144:vss(29)" )
			)
			( pin "J9T1.182"
				( objectStatus "@baseboard_fab2_lib.baseboard_fab2(sch_1):page78_i144:vss(30)" )
			)
			( pin "J9T1.180"
				( objectStatus "@baseboard_fab2_lib.baseboard_fab2(sch_1):page78_i144:vss(31)" )
			)
			( pin "J9T1.178"
				( objectStatus "@baseboard_fab2_lib.baseboard_fab2(sch_1):page78_i144:vss(32)" )
			)
			( pin "J9T1.176"
				( objectStatus "@baseboard_fab2_lib.baseboard_fab2(sch_1):page78_i144:vss(33)" )
			)
			( pin "J9T1.173"
				( objectStatus "@baseboard_fab2_lib.baseboard_fab2(sch_1):page78_i144:vss(34)" )
			)
			( pin "J9T1.171"
				( objectStatus "@baseboard_fab2_lib.baseboard_fab2(sch_1):page78_i144:vss(35)" )
			)
			( pin "J9T1.169"
				( objectStatus "@baseboard_fab2_lib.baseboard_fab2(sch_1):page78_i144:vss(36)" )
			)
			( pin "J9T1.167"
				( objectStatus "@baseboard_fab2_lib.baseboard_fab2(sch_1):page78_i144:vss(37)" )
			)
			( pin "J9T1.165"
				( objectStatus "@baseboard_fab2_lib.baseboard_fab2(sch_1):page78_i144:vss(38)" )
			)
			( pin "J9T1.162"
				( objectStatus "@baseboard_fab2_lib.baseboard_fab2(sch_1):page78_i144:vss(39)" )
			)
			( pin "J9T1.160"
				( objectStatus "@baseboard_fab2_lib.baseboard_fab2(sch_1):page78_i144:vss(40)" )
			)
			( pin "J9T1.158"
				( objectStatus "@baseboard_fab2_lib.baseboard_fab2(sch_1):page78_i144:vss(41)" )
			)
			( pin "J9T1.156"
				( objectStatus "@baseboard_fab2_lib.baseboard_fab2(sch_1):page78_i144:vss(42)" )
			)
			( pin "J9T1.154"
				( objectStatus "@baseboard_fab2_lib.baseboard_fab2(sch_1):page78_i144:vss(43)" )
			)
			( pin "J9T1.151"
				( objectStatus "@baseboard_fab2_lib.baseboard_fab2(sch_1):page78_i144:vss(44)" )
			)
			( pin "J9T1.149"
				( objectStatus "@baseboard_fab2_lib.baseboard_fab2(sch_1):page78_i144:vss(45)" )
			)
			( pin "J9T1.147"
				( objectStatus "@baseboard_fab2_lib.baseboard_fab2(sch_1):page78_i144:vss(46)" )
			)
			( pin "J9T1.138"
				( objectStatus "@baseboard_fab2_lib.baseboard_fab2(sch_1):page78_i144:vss(47)" )
			)
			( pin "J9T1.136"
				( objectStatus "@baseboard_fab2_lib.baseboard_fab2(sch_1):page78_i144:vss(48)" )
			)
			( pin "J9T1.134"
				( objectStatus "@baseboard_fab2_lib.baseboard_fab2(sch_1):page78_i144:vss(49)" )
			)
			( pin "J9T1.131"
				( objectStatus "@baseboard_fab2_lib.baseboard_fab2(sch_1):page78_i144:vss(50)" )
			)
			( pin "J9T1.129"
				( objectStatus "@baseboard_fab2_lib.baseboard_fab2(sch_1):page78_i144:vss(51)" )
			)
			( pin "J9T1.127"
				( objectStatus "@baseboard_fab2_lib.baseboard_fab2(sch_1):page78_i144:vss(52)" )
			)
			( pin "J9T1.125"
				( objectStatus "@baseboard_fab2_lib.baseboard_fab2(sch_1):page78_i144:vss(53)" )
			)
			( pin "J9T1.123"
				( objectStatus "@baseboard_fab2_lib.baseboard_fab2(sch_1):page78_i144:vss(54)" )
			)
			( pin "J9T1.120"
				( objectStatus "@baseboard_fab2_lib.baseboard_fab2(sch_1):page78_i144:vss(55)" )
			)
			( pin "J9T1.118"
				( objectStatus "@baseboard_fab2_lib.baseboard_fab2(sch_1):page78_i144:vss(56)" )
			)
			( pin "J9T1.116"
				( objectStatus "@baseboard_fab2_lib.baseboard_fab2(sch_1):page78_i144:vss(57)" )
			)
			( pin "J9T1.114"
				( objectStatus "@baseboard_fab2_lib.baseboard_fab2(sch_1):page78_i144:vss(58)" )
			)
			( pin "J9T1.112"
				( objectStatus "@baseboard_fab2_lib.baseboard_fab2(sch_1):page78_i144:vss(59)" )
			)
			( pin "J9T1.109"
				( objectStatus "@baseboard_fab2_lib.baseboard_fab2(sch_1):page78_i144:vss(60)" )
			)
			( pin "J9T1.107"
				( objectStatus "@baseboard_fab2_lib.baseboard_fab2(sch_1):page78_i144:vss(61)" )
			)
			( pin "J9T1.105"
				( objectStatus "@baseboard_fab2_lib.baseboard_fab2(sch_1):page78_i144:vss(62)" )
			)
			( pin "J9T1.103"
				( objectStatus "@baseboard_fab2_lib.baseboard_fab2(sch_1):page78_i144:vss(63)" )
			)
			( pin "J9T1.101"
				( objectStatus "@baseboard_fab2_lib.baseboard_fab2(sch_1):page78_i144:vss(64)" )
			)
			( pin "J9T1.98"
				( objectStatus "@baseboard_fab2_lib.baseboard_fab2(sch_1):page78_i144:vss(65)" )
			)
			( pin "J9T1.96"
				( objectStatus "@baseboard_fab2_lib.baseboard_fab2(sch_1):page78_i144:vss(66)" )
			)
			( pin "J9T1.94"
				( objectStatus "@baseboard_fab2_lib.baseboard_fab2(sch_1):page78_i144:vss(67)" )
			)
			( pin "J9T1.57"
				( objectStatus "@baseboard_fab2_lib.baseboard_fab2(sch_1):page78_i144:vss(68)" )
			)
			( pin "J9T1.55"
				( objectStatus "@baseboard_fab2_lib.baseboard_fab2(sch_1):page78_i144:vss(69)" )
			)
			( pin "J9T1.53"
				( objectStatus "@baseboard_fab2_lib.baseboard_fab2(sch_1):page78_i144:vss(70)" )
			)
			( pin "J9T1.50"
				( objectStatus "@baseboard_fab2_lib.baseboard_fab2(sch_1):page78_i144:vss(71)" )
			)
			( pin "J9T1.48"
				( objectStatus "@baseboard_fab2_lib.baseboard_fab2(sch_1):page78_i144:vss(72)" )
			)
			( pin "J9T1.46"
				( objectStatus "@baseboard_fab2_lib.baseboard_fab2(sch_1):page78_i144:vss(73)" )
			)
			( pin "J9T1.44"
				( objectStatus "@baseboard_fab2_lib.baseboard_fab2(sch_1):page78_i144:vss(74)" )
			)
			( pin "J9T1.42"
				( objectStatus "@baseboard_fab2_lib.baseboard_fab2(sch_1):page78_i144:vss(75)" )
			)
			( pin "J9T1.39"
				( objectStatus "@baseboard_fab2_lib.baseboard_fab2(sch_1):page78_i144:vss(76)" )
			)
			( pin "J9T1.37"
				( objectStatus "@baseboard_fab2_lib.baseboard_fab2(sch_1):page78_i144:vss(77)" )
			)
			( pin "J9T1.35"
				( objectStatus "@baseboard_fab2_lib.baseboard_fab2(sch_1):page78_i144:vss(78)" )
			)
			( pin "J9T1.33"
				( objectStatus "@baseboard_fab2_lib.baseboard_fab2(sch_1):page78_i144:vss(79)" )
			)
			( pin "J9T1.31"
				( objectStatus "@baseboard_fab2_lib.baseboard_fab2(sch_1):page78_i144:vss(80)" )
			)
			( pin "J9T1.28"
				( objectStatus "@baseboard_fab2_lib.baseboard_fab2(sch_1):page78_i144:vss(81)" )
			)
			( pin "J9T1.26"
				( objectStatus "@baseboard_fab2_lib.baseboard_fab2(sch_1):page78_i144:vss(82)" )
			)
			( pin "J9T1.24"
				( objectStatus "@baseboard_fab2_lib.baseboard_fab2(sch_1):page78_i144:vss(83)" )
			)
			( pin "J9T1.22"
				( objectStatus "@baseboard_fab2_lib.baseboard_fab2(sch_1):page78_i144:vss(84)" )
			)
			( pin "J9T1.20"
				( objectStatus "@baseboard_fab2_lib.baseboard_fab2(sch_1):page78_i144:vss(85)" )
			)
			( pin "J9T1.17"
				( objectStatus "@baseboard_fab2_lib.baseboard_fab2(sch_1):page78_i144:vss(86)" )
			)
			( pin "J9T1.15"
				( objectStatus "@baseboard_fab2_lib.baseboard_fab2(sch_1):page78_i144:vss(87)" )
			)
			( pin "J9T1.13"
				( objectStatus "@baseboard_fab2_lib.baseboard_fab2(sch_1):page78_i144:vss(88)" )
			)
			( pin "J9T1.11"
				( objectStatus "@baseboard_fab2_lib.baseboard_fab2(sch_1):page78_i144:vss(89)" )
			)
			( pin "J9T1.9"
				( objectStatus "@baseboard_fab2_lib.baseboard_fab2(sch_1):page78_i144:vss(90)" )
			)
			( pin "J9T1.6"
				( objectStatus "@baseboard_fab2_lib.baseboard_fab2(sch_1):page78_i144:vss(91)" )
			)
			( pin "J9T1.4"
				( objectStatus "@baseboard_fab2_lib.baseboard_fab2(sch_1):page78_i144:vss(92)" )
			)
			( pin "J9T1.2"
				( objectStatus "@baseboard_fab2_lib.baseboard_fab2(sch_1):page78_i144:vss(93)" )
			)
			( pin "J1G2.283"
				( objectStatus "@baseboard_fab2_lib.baseboard_fab2(sch_1):page79_i43:vss(0)" )
			)
			( pin "J1G2.281"
				( objectStatus "@baseboard_fab2_lib.baseboard_fab2(sch_1):page79_i43:vss(1)" )
			)
			( pin "J1G2.279"
				( objectStatus "@baseboard_fab2_lib.baseboard_fab2(sch_1):page79_i43:vss(2)" )
			)
			( pin "J1G2.276"
				( objectStatus "@baseboard_fab2_lib.baseboard_fab2(sch_1):page79_i43:vss(3)" )
			)
			( pin "J1G2.274"
				( objectStatus "@baseboard_fab2_lib.baseboard_fab2(sch_1):page79_i43:vss(4)" )
			)
			( pin "J1G2.272"
				( objectStatus "@baseboard_fab2_lib.baseboard_fab2(sch_1):page79_i43:vss(5)" )
			)
			( pin "J1G2.270"
				( objectStatus "@baseboard_fab2_lib.baseboard_fab2(sch_1):page79_i43:vss(6)" )
			)
			( pin "J1G2.268"
				( objectStatus "@baseboard_fab2_lib.baseboard_fab2(sch_1):page79_i43:vss(7)" )
			)
			( pin "J1G2.265"
				( objectStatus "@baseboard_fab2_lib.baseboard_fab2(sch_1):page79_i43:vss(8)" )
			)
			( pin "J1G2.263"
				( objectStatus "@baseboard_fab2_lib.baseboard_fab2(sch_1):page79_i43:vss(9)" )
			)
			( pin "J1G2.261"
				( objectStatus "@baseboard_fab2_lib.baseboard_fab2(sch_1):page79_i43:vss(10)" )
			)
			( pin "J1G2.259"
				( objectStatus "@baseboard_fab2_lib.baseboard_fab2(sch_1):page79_i43:vss(11)" )
			)
			( pin "J1G2.257"
				( objectStatus "@baseboard_fab2_lib.baseboard_fab2(sch_1):page79_i43:vss(12)" )
			)
			( pin "J1G2.254"
				( objectStatus "@baseboard_fab2_lib.baseboard_fab2(sch_1):page79_i43:vss(13)" )
			)
			( pin "J1G2.252"
				( objectStatus "@baseboard_fab2_lib.baseboard_fab2(sch_1):page79_i43:vss(14)" )
			)
			( pin "J1G2.250"
				( objectStatus "@baseboard_fab2_lib.baseboard_fab2(sch_1):page79_i43:vss(15)" )
			)
			( pin "J1G2.248"
				( objectStatus "@baseboard_fab2_lib.baseboard_fab2(sch_1):page79_i43:vss(16)" )
			)
			( pin "J1G2.246"
				( objectStatus "@baseboard_fab2_lib.baseboard_fab2(sch_1):page79_i43:vss(17)" )
			)
			( pin "J1G2.243"
				( objectStatus "@baseboard_fab2_lib.baseboard_fab2(sch_1):page79_i43:vss(18)" )
			)
			( pin "J1G2.241"
				( objectStatus "@baseboard_fab2_lib.baseboard_fab2(sch_1):page79_i43:vss(19)" )
			)
			( pin "J1G2.239"
				( objectStatus "@baseboard_fab2_lib.baseboard_fab2(sch_1):page79_i43:vss(20)" )
			)
			( pin "J1G2.202"
				( objectStatus "@baseboard_fab2_lib.baseboard_fab2(sch_1):page79_i43:vss(21)" )
			)
			( pin "J1G2.200"
				( objectStatus "@baseboard_fab2_lib.baseboard_fab2(sch_1):page79_i43:vss(22)" )
			)
			( pin "J1G2.198"
				( objectStatus "@baseboard_fab2_lib.baseboard_fab2(sch_1):page79_i43:vss(23)" )
			)
			( pin "J1G2.195"
				( objectStatus "@baseboard_fab2_lib.baseboard_fab2(sch_1):page79_i43:vss(24)" )
			)
			( pin "J1G2.193"
				( objectStatus "@baseboard_fab2_lib.baseboard_fab2(sch_1):page79_i43:vss(25)" )
			)
			( pin "J1G2.191"
				( objectStatus "@baseboard_fab2_lib.baseboard_fab2(sch_1):page79_i43:vss(26)" )
			)
			( pin "J1G2.189"
				( objectStatus "@baseboard_fab2_lib.baseboard_fab2(sch_1):page79_i43:vss(27)" )
			)
			( pin "J1G2.187"
				( objectStatus "@baseboard_fab2_lib.baseboard_fab2(sch_1):page79_i43:vss(28)" )
			)
			( pin "J1G2.184"
				( objectStatus "@baseboard_fab2_lib.baseboard_fab2(sch_1):page79_i43:vss(29)" )
			)
			( pin "J1G2.182"
				( objectStatus "@baseboard_fab2_lib.baseboard_fab2(sch_1):page79_i43:vss(30)" )
			)
			( pin "J1G2.180"
				( objectStatus "@baseboard_fab2_lib.baseboard_fab2(sch_1):page79_i43:vss(31)" )
			)
			( pin "J1G2.178"
				( objectStatus "@baseboard_fab2_lib.baseboard_fab2(sch_1):page79_i43:vss(32)" )
			)
			( pin "J1G2.176"
				( objectStatus "@baseboard_fab2_lib.baseboard_fab2(sch_1):page79_i43:vss(33)" )
			)
			( pin "J1G2.173"
				( objectStatus "@baseboard_fab2_lib.baseboard_fab2(sch_1):page79_i43:vss(34)" )
			)
			( pin "J1G2.171"
				( objectStatus "@baseboard_fab2_lib.baseboard_fab2(sch_1):page79_i43:vss(35)" )
			)
			( pin "J1G2.169"
				( objectStatus "@baseboard_fab2_lib.baseboard_fab2(sch_1):page79_i43:vss(36)" )
			)
			( pin "J1G2.167"
				( objectStatus "@baseboard_fab2_lib.baseboard_fab2(sch_1):page79_i43:vss(37)" )
			)
			( pin "J1G2.165"
				( objectStatus "@baseboard_fab2_lib.baseboard_fab2(sch_1):page79_i43:vss(38)" )
			)
			( pin "J1G2.162"
				( objectStatus "@baseboard_fab2_lib.baseboard_fab2(sch_1):page79_i43:vss(39)" )
			)
			( pin "J1G2.160"
				( objectStatus "@baseboard_fab2_lib.baseboard_fab2(sch_1):page79_i43:vss(40)" )
			)
			( pin "J1G2.158"
				( objectStatus "@baseboard_fab2_lib.baseboard_fab2(sch_1):page79_i43:vss(41)" )
			)
			( pin "J1G2.156"
				( objectStatus "@baseboard_fab2_lib.baseboard_fab2(sch_1):page79_i43:vss(42)" )
			)
			( pin "J1G2.154"
				( objectStatus "@baseboard_fab2_lib.baseboard_fab2(sch_1):page79_i43:vss(43)" )
			)
			( pin "J1G2.151"
				( objectStatus "@baseboard_fab2_lib.baseboard_fab2(sch_1):page79_i43:vss(44)" )
			)
			( pin "J1G2.149"
				( objectStatus "@baseboard_fab2_lib.baseboard_fab2(sch_1):page79_i43:vss(45)" )
			)
			( pin "J1G2.147"
				( objectStatus "@baseboard_fab2_lib.baseboard_fab2(sch_1):page79_i43:vss(46)" )
			)
			( pin "J1G2.138"
				( objectStatus "@baseboard_fab2_lib.baseboard_fab2(sch_1):page79_i43:vss(47)" )
			)
			( pin "J1G2.136"
				( objectStatus "@baseboard_fab2_lib.baseboard_fab2(sch_1):page79_i43:vss(48)" )
			)
			( pin "J1G2.134"
				( objectStatus "@baseboard_fab2_lib.baseboard_fab2(sch_1):page79_i43:vss(49)" )
			)
			( pin "J1G2.131"
				( objectStatus "@baseboard_fab2_lib.baseboard_fab2(sch_1):page79_i43:vss(50)" )
			)
			( pin "J1G2.129"
				( objectStatus "@baseboard_fab2_lib.baseboard_fab2(sch_1):page79_i43:vss(51)" )
			)
			( pin "J1G2.127"
				( objectStatus "@baseboard_fab2_lib.baseboard_fab2(sch_1):page79_i43:vss(52)" )
			)
			( pin "J1G2.125"
				( objectStatus "@baseboard_fab2_lib.baseboard_fab2(sch_1):page79_i43:vss(53)" )
			)
			( pin "J1G2.123"
				( objectStatus "@baseboard_fab2_lib.baseboard_fab2(sch_1):page79_i43:vss(54)" )
			)
			( pin "J1G2.120"
				( objectStatus "@baseboard_fab2_lib.baseboard_fab2(sch_1):page79_i43:vss(55)" )
			)
			( pin "J1G2.118"
				( objectStatus "@baseboard_fab2_lib.baseboard_fab2(sch_1):page79_i43:vss(56)" )
			)
			( pin "J1G2.116"
				( objectStatus "@baseboard_fab2_lib.baseboard_fab2(sch_1):page79_i43:vss(57)" )
			)
			( pin "J1G2.114"
				( objectStatus "@baseboard_fab2_lib.baseboard_fab2(sch_1):page79_i43:vss(58)" )
			)
			( pin "J1G2.112"
				( objectStatus "@baseboard_fab2_lib.baseboard_fab2(sch_1):page79_i43:vss(59)" )
			)
			( pin "J1G2.109"
				( objectStatus "@baseboard_fab2_lib.baseboard_fab2(sch_1):page79_i43:vss(60)" )
			)
			( pin "J1G2.107"
				( objectStatus "@baseboard_fab2_lib.baseboard_fab2(sch_1):page79_i43:vss(61)" )
			)
			( pin "J1G2.105"
				( objectStatus "@baseboard_fab2_lib.baseboard_fab2(sch_1):page79_i43:vss(62)" )
			)
			( pin "J1G2.103"
				( objectStatus "@baseboard_fab2_lib.baseboard_fab2(sch_1):page79_i43:vss(63)" )
			)
			( pin "J1G2.101"
				( objectStatus "@baseboard_fab2_lib.baseboard_fab2(sch_1):page79_i43:vss(64)" )
			)
			( pin "J1G2.98"
				( objectStatus "@baseboard_fab2_lib.baseboard_fab2(sch_1):page79_i43:vss(65)" )
			)
			( pin "J1G2.96"
				( objectStatus "@baseboard_fab2_lib.baseboard_fab2(sch_1):page79_i43:vss(66)" )
			)
			( pin "J1G2.94"
				( objectStatus "@baseboard_fab2_lib.baseboard_fab2(sch_1):page79_i43:vss(67)" )
			)
			( pin "J1G2.57"
				( objectStatus "@baseboard_fab2_lib.baseboard_fab2(sch_1):page79_i43:vss(68)" )
			)
			( pin "J1G2.55"
				( objectStatus "@baseboard_fab2_lib.baseboard_fab2(sch_1):page79_i43:vss(69)" )
			)
			( pin "J1G2.53"
				( objectStatus "@baseboard_fab2_lib.baseboard_fab2(sch_1):page79_i43:vss(70)" )
			)
			( pin "J1G2.50"
				( objectStatus "@baseboard_fab2_lib.baseboard_fab2(sch_1):page79_i43:vss(71)" )
			)
			( pin "J1G2.48"
				( objectStatus "@baseboard_fab2_lib.baseboard_fab2(sch_1):page79_i43:vss(72)" )
			)
			( pin "J1G2.46"
				( objectStatus "@baseboard_fab2_lib.baseboard_fab2(sch_1):page79_i43:vss(73)" )
			)
			( pin "J1G2.44"
				( objectStatus "@baseboard_fab2_lib.baseboard_fab2(sch_1):page79_i43:vss(74)" )
			)
			( pin "J1G2.42"
				( objectStatus "@baseboard_fab2_lib.baseboard_fab2(sch_1):page79_i43:vss(75)" )
			)
			( pin "J1G2.39"
				( objectStatus "@baseboard_fab2_lib.baseboard_fab2(sch_1):page79_i43:vss(76)" )
			)
			( pin "J1G2.37"
				( objectStatus "@baseboard_fab2_lib.baseboard_fab2(sch_1):page79_i43:vss(77)" )
			)
			( pin "J1G2.35"
				( objectStatus "@baseboard_fab2_lib.baseboard_fab2(sch_1):page79_i43:vss(78)" )
			)
			( pin "J1G2.33"
				( objectStatus "@baseboard_fab2_lib.baseboard_fab2(sch_1):page79_i43:vss(79)" )
			)
			( pin "J1G2.31"
				( objectStatus "@baseboard_fab2_lib.baseboard_fab2(sch_1):page79_i43:vss(80)" )
			)
			( pin "J1G2.28"
				( objectStatus "@baseboard_fab2_lib.baseboard_fab2(sch_1):page79_i43:vss(81)" )
			)
			( pin "J1G2.26"
				( objectStatus "@baseboard_fab2_lib.baseboard_fab2(sch_1):page79_i43:vss(82)" )
			)
			( pin "J1G2.24"
				( objectStatus "@baseboard_fab2_lib.baseboard_fab2(sch_1):page79_i43:vss(83)" )
			)
			( pin "J1G2.22"
				( objectStatus "@baseboard_fab2_lib.baseboard_fab2(sch_1):page79_i43:vss(84)" )
			)
			( pin "J1G2.20"
				( objectStatus "@baseboard_fab2_lib.baseboard_fab2(sch_1):page79_i43:vss(85)" )
			)
			( pin "J1G2.17"
				( objectStatus "@baseboard_fab2_lib.baseboard_fab2(sch_1):page79_i43:vss(86)" )
			)
			( pin "J1G2.15"
				( objectStatus "@baseboard_fab2_lib.baseboard_fab2(sch_1):page79_i43:vss(87)" )
			)
			( pin "J1G2.13"
				( objectStatus "@baseboard_fab2_lib.baseboard_fab2(sch_1):page79_i43:vss(88)" )
			)
			( pin "J1G2.11"
				( objectStatus "@baseboard_fab2_lib.baseboard_fab2(sch_1):page79_i43:vss(89)" )
			)
			( pin "J1G2.9"
				( objectStatus "@baseboard_fab2_lib.baseboard_fab2(sch_1):page79_i43:vss(90)" )
			)
			( pin "J1G2.6"
				( objectStatus "@baseboard_fab2_lib.baseboard_fab2(sch_1):page79_i43:vss(91)" )
			)
			( pin "J1G2.4"
				( objectStatus "@baseboard_fab2_lib.baseboard_fab2(sch_1):page79_i43:vss(92)" )
			)
			( pin "J1G2.2"
				( objectStatus "@baseboard_fab2_lib.baseboard_fab2(sch_1):page79_i43:vss(93)" )
			)
			( pin "J1G2.152"
				( objectStatus "@baseboard_fab2_lib.baseboard_fab2(sch_1):page79_i64:dqs0n" )
			)
			( pin "J1G2.153"
				( objectStatus "@baseboard_fab2_lib.baseboard_fab2(sch_1):page79_i64:dqs0p" )
			)
			( pin "J1G2.163"
				( objectStatus "@baseboard_fab2_lib.baseboard_fab2(sch_1):page79_i64:dqs1n" )
			)
			( pin "J1G2.164"
				( objectStatus "@baseboard_fab2_lib.baseboard_fab2(sch_1):page79_i64:dqs1p" )
			)
			( pin "J1G2.174"
				( objectStatus "@baseboard_fab2_lib.baseboard_fab2(sch_1):page79_i64:dqs2n" )
			)
			( pin "J1G2.175"
				( objectStatus "@baseboard_fab2_lib.baseboard_fab2(sch_1):page79_i64:dqs2p" )
			)
			( pin "J1G2.185"
				( objectStatus "@baseboard_fab2_lib.baseboard_fab2(sch_1):page79_i64:dqs3n" )
			)
			( pin "J1G2.186"
				( objectStatus "@baseboard_fab2_lib.baseboard_fab2(sch_1):page79_i64:dqs3p" )
			)
			( pin "J1G2.244"
				( objectStatus "@baseboard_fab2_lib.baseboard_fab2(sch_1):page79_i64:dqs4n" )
			)
			( pin "J1G2.245"
				( objectStatus "@baseboard_fab2_lib.baseboard_fab2(sch_1):page79_i64:dqs4p" )
			)
			( pin "J1G2.255"
				( objectStatus "@baseboard_fab2_lib.baseboard_fab2(sch_1):page79_i64:dqs5n" )
			)
			( pin "J1G2.256"
				( objectStatus "@baseboard_fab2_lib.baseboard_fab2(sch_1):page79_i64:dqs5p" )
			)
			( pin "J1G2.266"
				( objectStatus "@baseboard_fab2_lib.baseboard_fab2(sch_1):page79_i64:dqs6n" )
			)
			( pin "J1G2.267"
				( objectStatus "@baseboard_fab2_lib.baseboard_fab2(sch_1):page79_i64:dqs6p" )
			)
			( pin "J1G2.277"
				( objectStatus "@baseboard_fab2_lib.baseboard_fab2(sch_1):page79_i64:dqs7n" )
			)
			( pin "J1G2.278"
				( objectStatus "@baseboard_fab2_lib.baseboard_fab2(sch_1):page79_i64:dqs7p" )
			)
			( pin "J1G2.196"
				( objectStatus "@baseboard_fab2_lib.baseboard_fab2(sch_1):page79_i64:dqs8n" )
			)
			( pin "J1G2.197"
				( objectStatus "@baseboard_fab2_lib.baseboard_fab2(sch_1):page79_i64:dqs8p" )
			)
			( pin "J1G2.8"
				( objectStatus "@baseboard_fab2_lib.baseboard_fab2(sch_1):page79_i64:dqs9n" )
			)
			( pin "J1G2.7"
				( objectStatus "@baseboard_fab2_lib.baseboard_fab2(sch_1):page79_i64:dqs9p" )
			)
			( pin "J1G2.19"
				( objectStatus "@baseboard_fab2_lib.baseboard_fab2(sch_1):page79_i64:dqs10n" )
			)
			( pin "J1G2.18"
				( objectStatus "@baseboard_fab2_lib.baseboard_fab2(sch_1):page79_i64:dqs10p" )
			)
			( pin "J1G2.30"
				( objectStatus "@baseboard_fab2_lib.baseboard_fab2(sch_1):page79_i64:dqs11n" )
			)
			( pin "J1G2.29"
				( objectStatus "@baseboard_fab2_lib.baseboard_fab2(sch_1):page79_i64:dqs11p" )
			)
			( pin "J1G2.41"
				( objectStatus "@baseboard_fab2_lib.baseboard_fab2(sch_1):page79_i64:dqs12n" )
			)
			( pin "J1G2.40"
				( objectStatus "@baseboard_fab2_lib.baseboard_fab2(sch_1):page79_i64:dqs12p" )
			)
			( pin "J1G2.100"
				( objectStatus "@baseboard_fab2_lib.baseboard_fab2(sch_1):page79_i64:dqs13n" )
			)
			( pin "J1G2.99"
				( objectStatus "@baseboard_fab2_lib.baseboard_fab2(sch_1):page79_i64:dqs13p" )
			)
			( pin "J1G2.111"
				( objectStatus "@baseboard_fab2_lib.baseboard_fab2(sch_1):page79_i64:dqs14n" )
			)
			( pin "J1G2.110"
				( objectStatus "@baseboard_fab2_lib.baseboard_fab2(sch_1):page79_i64:dqs14p" )
			)
			( pin "J1G2.122"
				( objectStatus "@baseboard_fab2_lib.baseboard_fab2(sch_1):page79_i64:dqs15n" )
			)
			( pin "J1G2.121"
				( objectStatus "@baseboard_fab2_lib.baseboard_fab2(sch_1):page79_i64:dqs15p" )
			)
			( pin "J1G2.133"
				( objectStatus "@baseboard_fab2_lib.baseboard_fab2(sch_1):page79_i64:dqs16n" )
			)
			( pin "J1G2.132"
				( objectStatus "@baseboard_fab2_lib.baseboard_fab2(sch_1):page79_i64:dqs16p" )
			)
			( pin "J1G2.52"
				( objectStatus "@baseboard_fab2_lib.baseboard_fab2(sch_1):page79_i64:dqs17n" )
			)
			( pin "J1G2.51"
				( objectStatus "@baseboard_fab2_lib.baseboard_fab2(sch_1):page79_i64:dqs17p" )
			)
			( pin "J1G2.79"
				( objectStatus "@baseboard_fab2_lib.baseboard_fab2(sch_1):page79_i111:a0" )
			)
			( pin "J1G2.72"
				( objectStatus "@baseboard_fab2_lib.baseboard_fab2(sch_1):page79_i111:a1" )
			)
			( pin "J1G2.216"
				( objectStatus "@baseboard_fab2_lib.baseboard_fab2(sch_1):page79_i111:a2" )
			)
			( pin "J1G2.71"
				( objectStatus "@baseboard_fab2_lib.baseboard_fab2(sch_1):page79_i111:a3" )
			)
			( pin "J1G2.214"
				( objectStatus "@baseboard_fab2_lib.baseboard_fab2(sch_1):page79_i111:a4" )
			)
			( pin "J1G2.213"
				( objectStatus "@baseboard_fab2_lib.baseboard_fab2(sch_1):page79_i111:a5" )
			)
			( pin "J1G2.69"
				( objectStatus "@baseboard_fab2_lib.baseboard_fab2(sch_1):page79_i111:a6" )
			)
			( pin "J1G2.211"
				( objectStatus "@baseboard_fab2_lib.baseboard_fab2(sch_1):page79_i111:a7" )
			)
			( pin "J1G2.68"
				( objectStatus "@baseboard_fab2_lib.baseboard_fab2(sch_1):page79_i111:a8" )
			)
			( pin "J1G2.66"
				( objectStatus "@baseboard_fab2_lib.baseboard_fab2(sch_1):page79_i111:a9" )
			)
			( pin "J1G2.225"
				( objectStatus "@baseboard_fab2_lib.baseboard_fab2(sch_1):page79_i111:a10" )
			)
			( pin "J1G2.210"
				( objectStatus "@baseboard_fab2_lib.baseboard_fab2(sch_1):page79_i111:a11" )
			)
			( pin "J1G2.65"
				( objectStatus "@baseboard_fab2_lib.baseboard_fab2(sch_1):page79_i111:a12" )
			)
			( pin "J1G2.232"
				( objectStatus "@baseboard_fab2_lib.baseboard_fab2(sch_1):page79_i111:a13" )
			)
			( pin "J1G2.228"
				( objectStatus "@baseboard_fab2_lib.baseboard_fab2(sch_1):page79_i111:a14_we_n" )
			)
			( pin "J1G2.86"
				( objectStatus "@baseboard_fab2_lib.baseboard_fab2(sch_1):page79_i111:a15_cas_n" )
			)
			( pin "J1G2.82"
				( objectStatus "@baseboard_fab2_lib.baseboard_fab2(sch_1):page79_i111:a16_ras_n" )
			)
			( pin "J1G2.234"
				( objectStatus "@baseboard_fab2_lib.baseboard_fab2(sch_1):page79_i111:a17" )
			)
			( pin "J1G2.62"
				( objectStatus "@baseboard_fab2_lib.baseboard_fab2(sch_1):page79_i111:act_n" )
			)
			( pin "J1G2.208"
				( objectStatus "@baseboard_fab2_lib.baseboard_fab2(sch_1):page79_i111:alert_n" )
			)
			( pin "J1G2.81"
				( objectStatus "@baseboard_fab2_lib.baseboard_fab2(sch_1):page79_i111:ba(0)" )
			)
			( pin "J1G2.224"
				( objectStatus "@baseboard_fab2_lib.baseboard_fab2(sch_1):page79_i111:ba(1)" )
			)
			( pin "J1G2.63"
				( objectStatus "@baseboard_fab2_lib.baseboard_fab2(sch_1):page79_i111:bg(0)" )
			)
			( pin "J1G2.207"
				( objectStatus "@baseboard_fab2_lib.baseboard_fab2(sch_1):page79_i111:bg(1)" )
			)
			( pin "J1G2.235"
				( objectStatus "@baseboard_fab2_lib.baseboard_fab2(sch_1):page79_i111:c(2)" )
			)
			( pin "J1G2.49"
				( objectStatus "@baseboard_fab2_lib.baseboard_fab2(sch_1):page79_i111:cb(0)" )
			)
			( pin "J1G2.194"
				( objectStatus "@baseboard_fab2_lib.baseboard_fab2(sch_1):page79_i111:cb(1)" )
			)
			( pin "J1G2.56"
				( objectStatus "@baseboard_fab2_lib.baseboard_fab2(sch_1):page79_i111:cb(2)" )
			)
			( pin "J1G2.201"
				( objectStatus "@baseboard_fab2_lib.baseboard_fab2(sch_1):page79_i111:cb(3)" )
			)
			( pin "J1G2.47"
				( objectStatus "@baseboard_fab2_lib.baseboard_fab2(sch_1):page79_i111:cb(4)" )
			)
			( pin "J1G2.192"
				( objectStatus "@baseboard_fab2_lib.baseboard_fab2(sch_1):page79_i111:cb(5)" )
			)
			( pin "J1G2.54"
				( objectStatus "@baseboard_fab2_lib.baseboard_fab2(sch_1):page79_i111:cb(6)" )
			)
			( pin "J1G2.199"
				( objectStatus "@baseboard_fab2_lib.baseboard_fab2(sch_1):page79_i111:cb(7)" )
			)
			( pin "J1G2.75"
				( objectStatus "@baseboard_fab2_lib.baseboard_fab2(sch_1):page79_i111:ck0n" )
			)
			( pin "J1G2.74"
				( objectStatus "@baseboard_fab2_lib.baseboard_fab2(sch_1):page79_i111:ck0p" )
			)
			( pin "J1G2.219"
				( objectStatus "@baseboard_fab2_lib.baseboard_fab2(sch_1):page79_i111:ck1n" )
			)
			( pin "J1G2.218"
				( objectStatus "@baseboard_fab2_lib.baseboard_fab2(sch_1):page79_i111:ck1p" )
			)
			( pin "J1G2.60"
				( objectStatus "@baseboard_fab2_lib.baseboard_fab2(sch_1):page79_i111:cke(0)" )
			)
			( pin "J1G2.203"
				( objectStatus "@baseboard_fab2_lib.baseboard_fab2(sch_1):page79_i111:cke(1)" )
			)
			( pin "J1G2.5"
				( objectStatus "@baseboard_fab2_lib.baseboard_fab2(sch_1):page79_i111:dq(0)" )
			)
			( pin "J1G2.150"
				( objectStatus "@baseboard_fab2_lib.baseboard_fab2(sch_1):page79_i111:dq(1)" )
			)
			( pin "J1G2.12"
				( objectStatus "@baseboard_fab2_lib.baseboard_fab2(sch_1):page79_i111:dq(2)" )
			)
			( pin "J1G2.157"
				( objectStatus "@baseboard_fab2_lib.baseboard_fab2(sch_1):page79_i111:dq(3)" )
			)
			( pin "J1G2.3"
				( objectStatus "@baseboard_fab2_lib.baseboard_fab2(sch_1):page79_i111:dq(4)" )
			)
			( pin "J1G2.148"
				( objectStatus "@baseboard_fab2_lib.baseboard_fab2(sch_1):page79_i111:dq(5)" )
			)
			( pin "J1G2.10"
				( objectStatus "@baseboard_fab2_lib.baseboard_fab2(sch_1):page79_i111:dq(6)" )
			)
			( pin "J1G2.155"
				( objectStatus "@baseboard_fab2_lib.baseboard_fab2(sch_1):page79_i111:dq(7)" )
			)
			( pin "J1G2.16"
				( objectStatus "@baseboard_fab2_lib.baseboard_fab2(sch_1):page79_i111:dq(8)" )
			)
			( pin "J1G2.161"
				( objectStatus "@baseboard_fab2_lib.baseboard_fab2(sch_1):page79_i111:dq(9)" )
			)
			( pin "J1G2.23"
				( objectStatus "@baseboard_fab2_lib.baseboard_fab2(sch_1):page79_i111:dq(10)" )
			)
			( pin "J1G2.168"
				( objectStatus "@baseboard_fab2_lib.baseboard_fab2(sch_1):page79_i111:dq(11)" )
			)
			( pin "J1G2.14"
				( objectStatus "@baseboard_fab2_lib.baseboard_fab2(sch_1):page79_i111:dq(12)" )
			)
			( pin "J1G2.159"
				( objectStatus "@baseboard_fab2_lib.baseboard_fab2(sch_1):page79_i111:dq(13)" )
			)
			( pin "J1G2.21"
				( objectStatus "@baseboard_fab2_lib.baseboard_fab2(sch_1):page79_i111:dq(14)" )
			)
			( pin "J1G2.166"
				( objectStatus "@baseboard_fab2_lib.baseboard_fab2(sch_1):page79_i111:dq(15)" )
			)
			( pin "J1G2.27"
				( objectStatus "@baseboard_fab2_lib.baseboard_fab2(sch_1):page79_i111:dq(16)" )
			)
			( pin "J1G2.172"
				( objectStatus "@baseboard_fab2_lib.baseboard_fab2(sch_1):page79_i111:dq(17)" )
			)
			( pin "J1G2.34"
				( objectStatus "@baseboard_fab2_lib.baseboard_fab2(sch_1):page79_i111:dq(18)" )
			)
			( pin "J1G2.179"
				( objectStatus "@baseboard_fab2_lib.baseboard_fab2(sch_1):page79_i111:dq(19)" )
			)
			( pin "J1G2.25"
				( objectStatus "@baseboard_fab2_lib.baseboard_fab2(sch_1):page79_i111:dq(20)" )
			)
			( pin "J1G2.170"
				( objectStatus "@baseboard_fab2_lib.baseboard_fab2(sch_1):page79_i111:dq(21)" )
			)
			( pin "J1G2.32"
				( objectStatus "@baseboard_fab2_lib.baseboard_fab2(sch_1):page79_i111:dq(22)" )
			)
			( pin "J1G2.177"
				( objectStatus "@baseboard_fab2_lib.baseboard_fab2(sch_1):page79_i111:dq(23)" )
			)
			( pin "J1G2.38"
				( objectStatus "@baseboard_fab2_lib.baseboard_fab2(sch_1):page79_i111:dq(24)" )
			)
			( pin "J1G2.183"
				( objectStatus "@baseboard_fab2_lib.baseboard_fab2(sch_1):page79_i111:dq(25)" )
			)
			( pin "J1G2.45"
				( objectStatus "@baseboard_fab2_lib.baseboard_fab2(sch_1):page79_i111:dq(26)" )
			)
			( pin "J1G2.190"
				( objectStatus "@baseboard_fab2_lib.baseboard_fab2(sch_1):page79_i111:dq(27)" )
			)
			( pin "J1G2.36"
				( objectStatus "@baseboard_fab2_lib.baseboard_fab2(sch_1):page79_i111:dq(28)" )
			)
			( pin "J1G2.181"
				( objectStatus "@baseboard_fab2_lib.baseboard_fab2(sch_1):page79_i111:dq(29)" )
			)
			( pin "J1G2.43"
				( objectStatus "@baseboard_fab2_lib.baseboard_fab2(sch_1):page79_i111:dq(30)" )
			)
			( pin "J1G2.188"
				( objectStatus "@baseboard_fab2_lib.baseboard_fab2(sch_1):page79_i111:dq(31)" )
			)
			( pin "J1G2.97"
				( objectStatus "@baseboard_fab2_lib.baseboard_fab2(sch_1):page79_i111:dq(32)" )
			)
			( pin "J1G2.242"
				( objectStatus "@baseboard_fab2_lib.baseboard_fab2(sch_1):page79_i111:dq(33)" )
			)
			( pin "J1G2.104"
				( objectStatus "@baseboard_fab2_lib.baseboard_fab2(sch_1):page79_i111:dq(34)" )
			)
			( pin "J1G2.249"
				( objectStatus "@baseboard_fab2_lib.baseboard_fab2(sch_1):page79_i111:dq(35)" )
			)
			( pin "J1G2.95"
				( objectStatus "@baseboard_fab2_lib.baseboard_fab2(sch_1):page79_i111:dq(36)" )
			)
			( pin "J1G2.240"
				( objectStatus "@baseboard_fab2_lib.baseboard_fab2(sch_1):page79_i111:dq(37)" )
			)
			( pin "J1G2.102"
				( objectStatus "@baseboard_fab2_lib.baseboard_fab2(sch_1):page79_i111:dq(38)" )
			)
			( pin "J1G2.247"
				( objectStatus "@baseboard_fab2_lib.baseboard_fab2(sch_1):page79_i111:dq(39)" )
			)
			( pin "J1G2.108"
				( objectStatus "@baseboard_fab2_lib.baseboard_fab2(sch_1):page79_i111:dq(40)" )
			)
			( pin "J1G2.253"
				( objectStatus "@baseboard_fab2_lib.baseboard_fab2(sch_1):page79_i111:dq(41)" )
			)
			( pin "J1G2.115"
				( objectStatus "@baseboard_fab2_lib.baseboard_fab2(sch_1):page79_i111:dq(42)" )
			)
			( pin "J1G2.260"
				( objectStatus "@baseboard_fab2_lib.baseboard_fab2(sch_1):page79_i111:dq(43)" )
			)
			( pin "J1G2.106"
				( objectStatus "@baseboard_fab2_lib.baseboard_fab2(sch_1):page79_i111:dq(44)" )
			)
			( pin "J1G2.251"
				( objectStatus "@baseboard_fab2_lib.baseboard_fab2(sch_1):page79_i111:dq(45)" )
			)
			( pin "J1G2.113"
				( objectStatus "@baseboard_fab2_lib.baseboard_fab2(sch_1):page79_i111:dq(46)" )
			)
			( pin "J1G2.258"
				( objectStatus "@baseboard_fab2_lib.baseboard_fab2(sch_1):page79_i111:dq(47)" )
			)
			( pin "J1G2.119"
				( objectStatus "@baseboard_fab2_lib.baseboard_fab2(sch_1):page79_i111:dq(48)" )
			)
			( pin "J1G2.264"
				( objectStatus "@baseboard_fab2_lib.baseboard_fab2(sch_1):page79_i111:dq(49)" )
			)
			( pin "J1G2.126"
				( objectStatus "@baseboard_fab2_lib.baseboard_fab2(sch_1):page79_i111:dq(50)" )
			)
			( pin "J1G2.271"
				( objectStatus "@baseboard_fab2_lib.baseboard_fab2(sch_1):page79_i111:dq(51)" )
			)
			( pin "J1G2.117"
				( objectStatus "@baseboard_fab2_lib.baseboard_fab2(sch_1):page79_i111:dq(52)" )
			)
			( pin "J1G2.262"
				( objectStatus "@baseboard_fab2_lib.baseboard_fab2(sch_1):page79_i111:dq(53)" )
			)
			( pin "J1G2.124"
				( objectStatus "@baseboard_fab2_lib.baseboard_fab2(sch_1):page79_i111:dq(54)" )
			)
			( pin "J1G2.269"
				( objectStatus "@baseboard_fab2_lib.baseboard_fab2(sch_1):page79_i111:dq(55)" )
			)
			( pin "J1G2.130"
				( objectStatus "@baseboard_fab2_lib.baseboard_fab2(sch_1):page79_i111:dq(56)" )
			)
			( pin "J1G2.275"
				( objectStatus "@baseboard_fab2_lib.baseboard_fab2(sch_1):page79_i111:dq(57)" )
			)
			( pin "J1G2.137"
				( objectStatus "@baseboard_fab2_lib.baseboard_fab2(sch_1):page79_i111:dq(58)" )
			)
			( pin "J1G2.282"
				( objectStatus "@baseboard_fab2_lib.baseboard_fab2(sch_1):page79_i111:dq(59)" )
			)
			( pin "J1G2.128"
				( objectStatus "@baseboard_fab2_lib.baseboard_fab2(sch_1):page79_i111:dq(60)" )
			)
			( pin "J1G2.273"
				( objectStatus "@baseboard_fab2_lib.baseboard_fab2(sch_1):page79_i111:dq(61)" )
			)
			( pin "J1G2.135"
				( objectStatus "@baseboard_fab2_lib.baseboard_fab2(sch_1):page79_i111:dq(62)" )
			)
			( pin "J1G2.280"
				( objectStatus "@baseboard_fab2_lib.baseboard_fab2(sch_1):page79_i111:dq(63)" )
			)
			( pin "J1G2.78"
				( objectStatus "@baseboard_fab2_lib.baseboard_fab2(sch_1):page79_i111:event_n" )
			)
			( pin "J1G2.87"
				( objectStatus "@baseboard_fab2_lib.baseboard_fab2(sch_1):page79_i111:odt(0)" )
			)
			( pin "J1G2.91"
				( objectStatus "@baseboard_fab2_lib.baseboard_fab2(sch_1):page79_i111:odt(1)" )
			)
			( pin "J1G2.222"
				( objectStatus "@baseboard_fab2_lib.baseboard_fab2(sch_1):page79_i111:par" )
			)
			( pin "J1G2.58"
				( objectStatus "@baseboard_fab2_lib.baseboard_fab2(sch_1):page79_i111:reset_n" )
			)
			( pin "J1G2.205"
				( objectStatus "@baseboard_fab2_lib.baseboard_fab2(sch_1):page79_i111:rfu(0)" )
			)
			( pin "J1G2.227"
				( objectStatus "@baseboard_fab2_lib.baseboard_fab2(sch_1):page79_i111:rfu(1)" )
			)
			( pin "J1G2.144"
				( objectStatus "@baseboard_fab2_lib.baseboard_fab2(sch_1):page79_i111:rfu(2)" )
			)
			( pin "J1G2.84"
				( objectStatus "@baseboard_fab2_lib.baseboard_fab2(sch_1):page79_i111:s0_n" )
			)
			( pin "J1G2.89"
				( objectStatus "@baseboard_fab2_lib.baseboard_fab2(sch_1):page79_i111:s1_n" )
			)
			( pin "J1G2.93"
				( objectStatus "@baseboard_fab2_lib.baseboard_fab2(sch_1):page79_i111:s2_n_c(0)" )
			)
			( pin "J1G2.237"
				( objectStatus "@baseboard_fab2_lib.baseboard_fab2(sch_1):page79_i111:s3_n_c(1)" )
			)
			( pin "J1G2.139"
				( objectStatus "@baseboard_fab2_lib.baseboard_fab2(sch_1):page79_i111:sa(0)" )
			)
			( pin "J1G2.140"
				( objectStatus "@baseboard_fab2_lib.baseboard_fab2(sch_1):page79_i111:sa(1)" )
			)
			( pin "J1G2.238"
				( objectStatus "@baseboard_fab2_lib.baseboard_fab2(sch_1):page79_i111:sa(2)" )
			)
			( pin "J1G2.230"
				( objectStatus "@baseboard_fab2_lib.baseboard_fab2(sch_1):page79_i111:save_n_nc" )
			)
			( pin "J1G2.141"
				( objectStatus "@baseboard_fab2_lib.baseboard_fab2(sch_1):page79_i111:scl" )
			)
			( pin "J1G2.285"
				( objectStatus "@baseboard_fab2_lib.baseboard_fab2(sch_1):page79_i111:sda" )
			)
			( pin "J1G2.284"
				( objectStatus "@baseboard_fab2_lib.baseboard_fab2(sch_1):page79_i111:vddspd" )
			)
			( pin "J1G2.146"
				( objectStatus "@baseboard_fab2_lib.baseboard_fab2(sch_1):page79_i111:vrefca" )
			)
			( pin "J1G2.145"
				( objectStatus "@baseboard_fab2_lib.baseboard_fab2(sch_1):page79_i169:\12v\(0)" )
			)
			( pin "J1G2.1"
				( objectStatus "@baseboard_fab2_lib.baseboard_fab2(sch_1):page79_i169:\12v\(1)" )
			)
			( pin "J1G2.236"
				( objectStatus "@baseboard_fab2_lib.baseboard_fab2(sch_1):page79_i169:vdd(0)" )
			)
			( pin "J1G2.233"
				( objectStatus "@baseboard_fab2_lib.baseboard_fab2(sch_1):page79_i169:vdd(1)" )
			)
			( pin "J1G2.231"
				( objectStatus "@baseboard_fab2_lib.baseboard_fab2(sch_1):page79_i169:vdd(2)" )
			)
			( pin "J1G2.229"
				( objectStatus "@baseboard_fab2_lib.baseboard_fab2(sch_1):page79_i169:vdd(3)" )
			)
			( pin "J1G2.226"
				( objectStatus "@baseboard_fab2_lib.baseboard_fab2(sch_1):page79_i169:vdd(4)" )
			)
			( pin "J1G2.223"
				( objectStatus "@baseboard_fab2_lib.baseboard_fab2(sch_1):page79_i169:vdd(5)" )
			)
			( pin "J1G2.220"
				( objectStatus "@baseboard_fab2_lib.baseboard_fab2(sch_1):page79_i169:vdd(6)" )
			)
			( pin "J1G2.217"
				( objectStatus "@baseboard_fab2_lib.baseboard_fab2(sch_1):page79_i169:vdd(7)" )
			)
			( pin "J1G2.215"
				( objectStatus "@baseboard_fab2_lib.baseboard_fab2(sch_1):page79_i169:vdd(8)" )
			)
			( pin "J1G2.212"
				( objectStatus "@baseboard_fab2_lib.baseboard_fab2(sch_1):page79_i169:vdd(9)" )
			)
			( pin "J1G2.209"
				( objectStatus "@baseboard_fab2_lib.baseboard_fab2(sch_1):page79_i169:vdd(10)" )
			)
			( pin "J1G2.206"
				( objectStatus "@baseboard_fab2_lib.baseboard_fab2(sch_1):page79_i169:vdd(11)" )
			)
			( pin "J1G2.204"
				( objectStatus "@baseboard_fab2_lib.baseboard_fab2(sch_1):page79_i169:vdd(12)" )
			)
			( pin "J1G2.92"
				( objectStatus "@baseboard_fab2_lib.baseboard_fab2(sch_1):page79_i169:vdd(13)" )
			)
			( pin "J1G2.90"
				( objectStatus "@baseboard_fab2_lib.baseboard_fab2(sch_1):page79_i169:vdd(14)" )
			)
			( pin "J1G2.88"
				( objectStatus "@baseboard_fab2_lib.baseboard_fab2(sch_1):page79_i169:vdd(15)" )
			)
			( pin "J1G2.85"
				( objectStatus "@baseboard_fab2_lib.baseboard_fab2(sch_1):page79_i169:vdd(16)" )
			)
			( pin "J1G2.83"
				( objectStatus "@baseboard_fab2_lib.baseboard_fab2(sch_1):page79_i169:vdd(17)" )
			)
			( pin "J1G2.80"
				( objectStatus "@baseboard_fab2_lib.baseboard_fab2(sch_1):page79_i169:vdd(18)" )
			)
			( pin "J1G2.76"
				( objectStatus "@baseboard_fab2_lib.baseboard_fab2(sch_1):page79_i169:vdd(19)" )
			)
			( pin "J1G2.73"
				( objectStatus "@baseboard_fab2_lib.baseboard_fab2(sch_1):page79_i169:vdd(20)" )
			)
			( pin "J1G2.70"
				( objectStatus "@baseboard_fab2_lib.baseboard_fab2(sch_1):page79_i169:vdd(21)" )
			)
			( pin "J1G2.67"
				( objectStatus "@baseboard_fab2_lib.baseboard_fab2(sch_1):page79_i169:vdd(22)" )
			)
			( pin "J1G2.64"
				( objectStatus "@baseboard_fab2_lib.baseboard_fab2(sch_1):page79_i169:vdd(23)" )
			)
			( pin "J1G2.61"
				( objectStatus "@baseboard_fab2_lib.baseboard_fab2(sch_1):page79_i169:vdd(24)" )
			)
			( pin "J1G2.59"
				( objectStatus "@baseboard_fab2_lib.baseboard_fab2(sch_1):page79_i169:vdd(25)" )
			)
			( pin "J1G2.287"
				( objectStatus "@baseboard_fab2_lib.baseboard_fab2(sch_1):page79_i169:vpp(0)" )
			)
			( pin "J1G2.286"
				( objectStatus "@baseboard_fab2_lib.baseboard_fab2(sch_1):page79_i169:vpp(1)" )
			)
			( pin "J1G2.288"
				( objectStatus "@baseboard_fab2_lib.baseboard_fab2(sch_1):page79_i169:vpp(2)" )
			)
			( pin "J1G2.143"
				( objectStatus "@baseboard_fab2_lib.baseboard_fab2(sch_1):page79_i169:vpp(3)" )
			)
			( pin "J1G2.142"
				( objectStatus "@baseboard_fab2_lib.baseboard_fab2(sch_1):page79_i169:vpp(4)" )
			)
			( pin "J1G2.221"
				( objectStatus "@baseboard_fab2_lib.baseboard_fab2(sch_1):page79_i169:vtt(0)" )
			)
			( pin "J1G2.77"
				( objectStatus "@baseboard_fab2_lib.baseboard_fab2(sch_1):page79_i169:vtt(1)" )
			)
			( pin "C9U7.1"
				( objectStatus "@baseboard_fab2_lib.baseboard_fab2(sch_1):page79_i178:a" )
			)
			( pin "C9U7.2"
				( objectStatus "@baseboard_fab2_lib.baseboard_fab2(sch_1):page79_i178:b" )
			)
			( pin "C1G10.1"
				( objectStatus "@baseboard_fab2_lib.baseboard_fab2(sch_1):page80_i3:a" )
			)
			( pin "C1G10.2"
				( objectStatus "@baseboard_fab2_lib.baseboard_fab2(sch_1):page80_i3:b" )
			)
			( pin "J9U1.79"
				( objectStatus "@baseboard_fab2_lib.baseboard_fab2(sch_1):page80_i24:a0" )
			)
			( pin "J9U1.72"
				( objectStatus "@baseboard_fab2_lib.baseboard_fab2(sch_1):page80_i24:a1" )
			)
			( pin "J9U1.216"
				( objectStatus "@baseboard_fab2_lib.baseboard_fab2(sch_1):page80_i24:a2" )
			)
			( pin "J9U1.71"
				( objectStatus "@baseboard_fab2_lib.baseboard_fab2(sch_1):page80_i24:a3" )
			)
			( pin "J9U1.214"
				( objectStatus "@baseboard_fab2_lib.baseboard_fab2(sch_1):page80_i24:a4" )
			)
			( pin "J9U1.213"
				( objectStatus "@baseboard_fab2_lib.baseboard_fab2(sch_1):page80_i24:a5" )
			)
			( pin "J9U1.69"
				( objectStatus "@baseboard_fab2_lib.baseboard_fab2(sch_1):page80_i24:a6" )
			)
			( pin "J9U1.211"
				( objectStatus "@baseboard_fab2_lib.baseboard_fab2(sch_1):page80_i24:a7" )
			)
			( pin "J9U1.68"
				( objectStatus "@baseboard_fab2_lib.baseboard_fab2(sch_1):page80_i24:a8" )
			)
			( pin "J9U1.66"
				( objectStatus "@baseboard_fab2_lib.baseboard_fab2(sch_1):page80_i24:a9" )
			)
			( pin "J9U1.225"
				( objectStatus "@baseboard_fab2_lib.baseboard_fab2(sch_1):page80_i24:a10" )
			)
			( pin "J9U1.210"
				( objectStatus "@baseboard_fab2_lib.baseboard_fab2(sch_1):page80_i24:a11" )
			)
			( pin "J9U1.65"
				( objectStatus "@baseboard_fab2_lib.baseboard_fab2(sch_1):page80_i24:a12" )
			)
			( pin "J9U1.232"
				( objectStatus "@baseboard_fab2_lib.baseboard_fab2(sch_1):page80_i24:a13" )
			)
			( pin "J9U1.228"
				( objectStatus "@baseboard_fab2_lib.baseboard_fab2(sch_1):page80_i24:a14_we_n" )
			)
			( pin "J9U1.86"
				( objectStatus "@baseboard_fab2_lib.baseboard_fab2(sch_1):page80_i24:a15_cas_n" )
			)
			( pin "J9U1.82"
				( objectStatus "@baseboard_fab2_lib.baseboard_fab2(sch_1):page80_i24:a16_ras_n" )
			)
			( pin "J9U1.234"
				( objectStatus "@baseboard_fab2_lib.baseboard_fab2(sch_1):page80_i24:a17" )
			)
			( pin "J9U1.62"
				( objectStatus "@baseboard_fab2_lib.baseboard_fab2(sch_1):page80_i24:act_n" )
			)
			( pin "J9U1.208"
				( objectStatus "@baseboard_fab2_lib.baseboard_fab2(sch_1):page80_i24:alert_n" )
			)
			( pin "J9U1.81"
				( objectStatus "@baseboard_fab2_lib.baseboard_fab2(sch_1):page80_i24:ba(0)" )
			)
			( pin "J9U1.224"
				( objectStatus "@baseboard_fab2_lib.baseboard_fab2(sch_1):page80_i24:ba(1)" )
			)
			( pin "J9U1.63"
				( objectStatus "@baseboard_fab2_lib.baseboard_fab2(sch_1):page80_i24:bg(0)" )
			)
			( pin "J9U1.207"
				( objectStatus "@baseboard_fab2_lib.baseboard_fab2(sch_1):page80_i24:bg(1)" )
			)
			( pin "J9U1.235"
				( objectStatus "@baseboard_fab2_lib.baseboard_fab2(sch_1):page80_i24:c(2)" )
			)
			( pin "J9U1.49"
				( objectStatus "@baseboard_fab2_lib.baseboard_fab2(sch_1):page80_i24:cb(0)" )
			)
			( pin "J9U1.194"
				( objectStatus "@baseboard_fab2_lib.baseboard_fab2(sch_1):page80_i24:cb(1)" )
			)
			( pin "J9U1.56"
				( objectStatus "@baseboard_fab2_lib.baseboard_fab2(sch_1):page80_i24:cb(2)" )
			)
			( pin "J9U1.201"
				( objectStatus "@baseboard_fab2_lib.baseboard_fab2(sch_1):page80_i24:cb(3)" )
			)
			( pin "J9U1.47"
				( objectStatus "@baseboard_fab2_lib.baseboard_fab2(sch_1):page80_i24:cb(4)" )
			)
			( pin "J9U1.192"
				( objectStatus "@baseboard_fab2_lib.baseboard_fab2(sch_1):page80_i24:cb(5)" )
			)
			( pin "J9U1.54"
				( objectStatus "@baseboard_fab2_lib.baseboard_fab2(sch_1):page80_i24:cb(6)" )
			)
			( pin "J9U1.199"
				( objectStatus "@baseboard_fab2_lib.baseboard_fab2(sch_1):page80_i24:cb(7)" )
			)
			( pin "J9U1.75"
				( objectStatus "@baseboard_fab2_lib.baseboard_fab2(sch_1):page80_i24:ck0n" )
			)
			( pin "J9U1.74"
				( objectStatus "@baseboard_fab2_lib.baseboard_fab2(sch_1):page80_i24:ck0p" )
			)
			( pin "J9U1.219"
				( objectStatus "@baseboard_fab2_lib.baseboard_fab2(sch_1):page80_i24:ck1n" )
			)
			( pin "J9U1.218"
				( objectStatus "@baseboard_fab2_lib.baseboard_fab2(sch_1):page80_i24:ck1p" )
			)
			( pin "J9U1.60"
				( objectStatus "@baseboard_fab2_lib.baseboard_fab2(sch_1):page80_i24:cke(0)" )
			)
			( pin "J9U1.203"
				( objectStatus "@baseboard_fab2_lib.baseboard_fab2(sch_1):page80_i24:cke(1)" )
			)
			( pin "J9U1.5"
				( objectStatus "@baseboard_fab2_lib.baseboard_fab2(sch_1):page80_i24:dq(0)" )
			)
			( pin "J9U1.150"
				( objectStatus "@baseboard_fab2_lib.baseboard_fab2(sch_1):page80_i24:dq(1)" )
			)
			( pin "J9U1.12"
				( objectStatus "@baseboard_fab2_lib.baseboard_fab2(sch_1):page80_i24:dq(2)" )
			)
			( pin "J9U1.157"
				( objectStatus "@baseboard_fab2_lib.baseboard_fab2(sch_1):page80_i24:dq(3)" )
			)
			( pin "J9U1.3"
				( objectStatus "@baseboard_fab2_lib.baseboard_fab2(sch_1):page80_i24:dq(4)" )
			)
			( pin "J9U1.148"
				( objectStatus "@baseboard_fab2_lib.baseboard_fab2(sch_1):page80_i24:dq(5)" )
			)
			( pin "J9U1.10"
				( objectStatus "@baseboard_fab2_lib.baseboard_fab2(sch_1):page80_i24:dq(6)" )
			)
			( pin "J9U1.155"
				( objectStatus "@baseboard_fab2_lib.baseboard_fab2(sch_1):page80_i24:dq(7)" )
			)
			( pin "J9U1.16"
				( objectStatus "@baseboard_fab2_lib.baseboard_fab2(sch_1):page80_i24:dq(8)" )
			)
			( pin "J9U1.161"
				( objectStatus "@baseboard_fab2_lib.baseboard_fab2(sch_1):page80_i24:dq(9)" )
			)
			( pin "J9U1.23"
				( objectStatus "@baseboard_fab2_lib.baseboard_fab2(sch_1):page80_i24:dq(10)" )
			)
			( pin "J9U1.168"
				( objectStatus "@baseboard_fab2_lib.baseboard_fab2(sch_1):page80_i24:dq(11)" )
			)
			( pin "J9U1.14"
				( objectStatus "@baseboard_fab2_lib.baseboard_fab2(sch_1):page80_i24:dq(12)" )
			)
			( pin "J9U1.159"
				( objectStatus "@baseboard_fab2_lib.baseboard_fab2(sch_1):page80_i24:dq(13)" )
			)
			( pin "J9U1.21"
				( objectStatus "@baseboard_fab2_lib.baseboard_fab2(sch_1):page80_i24:dq(14)" )
			)
			( pin "J9U1.166"
				( objectStatus "@baseboard_fab2_lib.baseboard_fab2(sch_1):page80_i24:dq(15)" )
			)
			( pin "J9U1.27"
				( objectStatus "@baseboard_fab2_lib.baseboard_fab2(sch_1):page80_i24:dq(16)" )
			)
			( pin "J9U1.172"
				( objectStatus "@baseboard_fab2_lib.baseboard_fab2(sch_1):page80_i24:dq(17)" )
			)
			( pin "J9U1.34"
				( objectStatus "@baseboard_fab2_lib.baseboard_fab2(sch_1):page80_i24:dq(18)" )
			)
			( pin "J9U1.179"
				( objectStatus "@baseboard_fab2_lib.baseboard_fab2(sch_1):page80_i24:dq(19)" )
			)
			( pin "J9U1.25"
				( objectStatus "@baseboard_fab2_lib.baseboard_fab2(sch_1):page80_i24:dq(20)" )
			)
			( pin "J9U1.170"
				( objectStatus "@baseboard_fab2_lib.baseboard_fab2(sch_1):page80_i24:dq(21)" )
			)
			( pin "J9U1.32"
				( objectStatus "@baseboard_fab2_lib.baseboard_fab2(sch_1):page80_i24:dq(22)" )
			)
			( pin "J9U1.177"
				( objectStatus "@baseboard_fab2_lib.baseboard_fab2(sch_1):page80_i24:dq(23)" )
			)
			( pin "J9U1.38"
				( objectStatus "@baseboard_fab2_lib.baseboard_fab2(sch_1):page80_i24:dq(24)" )
			)
			( pin "J9U1.183"
				( objectStatus "@baseboard_fab2_lib.baseboard_fab2(sch_1):page80_i24:dq(25)" )
			)
			( pin "J9U1.45"
				( objectStatus "@baseboard_fab2_lib.baseboard_fab2(sch_1):page80_i24:dq(26)" )
			)
			( pin "J9U1.190"
				( objectStatus "@baseboard_fab2_lib.baseboard_fab2(sch_1):page80_i24:dq(27)" )
			)
			( pin "J9U1.36"
				( objectStatus "@baseboard_fab2_lib.baseboard_fab2(sch_1):page80_i24:dq(28)" )
			)
			( pin "J9U1.181"
				( objectStatus "@baseboard_fab2_lib.baseboard_fab2(sch_1):page80_i24:dq(29)" )
			)
			( pin "J9U1.43"
				( objectStatus "@baseboard_fab2_lib.baseboard_fab2(sch_1):page80_i24:dq(30)" )
			)
			( pin "J9U1.188"
				( objectStatus "@baseboard_fab2_lib.baseboard_fab2(sch_1):page80_i24:dq(31)" )
			)
			( pin "J9U1.97"
				( objectStatus "@baseboard_fab2_lib.baseboard_fab2(sch_1):page80_i24:dq(32)" )
			)
			( pin "J9U1.242"
				( objectStatus "@baseboard_fab2_lib.baseboard_fab2(sch_1):page80_i24:dq(33)" )
			)
			( pin "J9U1.104"
				( objectStatus "@baseboard_fab2_lib.baseboard_fab2(sch_1):page80_i24:dq(34)" )
			)
			( pin "J9U1.249"
				( objectStatus "@baseboard_fab2_lib.baseboard_fab2(sch_1):page80_i24:dq(35)" )
			)
			( pin "J9U1.95"
				( objectStatus "@baseboard_fab2_lib.baseboard_fab2(sch_1):page80_i24:dq(36)" )
			)
			( pin "J9U1.240"
				( objectStatus "@baseboard_fab2_lib.baseboard_fab2(sch_1):page80_i24:dq(37)" )
			)
			( pin "J9U1.102"
				( objectStatus "@baseboard_fab2_lib.baseboard_fab2(sch_1):page80_i24:dq(38)" )
			)
			( pin "J9U1.247"
				( objectStatus "@baseboard_fab2_lib.baseboard_fab2(sch_1):page80_i24:dq(39)" )
			)
			( pin "J9U1.108"
				( objectStatus "@baseboard_fab2_lib.baseboard_fab2(sch_1):page80_i24:dq(40)" )
			)
			( pin "J9U1.253"
				( objectStatus "@baseboard_fab2_lib.baseboard_fab2(sch_1):page80_i24:dq(41)" )
			)
			( pin "J9U1.115"
				( objectStatus "@baseboard_fab2_lib.baseboard_fab2(sch_1):page80_i24:dq(42)" )
			)
			( pin "J9U1.260"
				( objectStatus "@baseboard_fab2_lib.baseboard_fab2(sch_1):page80_i24:dq(43)" )
			)
			( pin "J9U1.106"
				( objectStatus "@baseboard_fab2_lib.baseboard_fab2(sch_1):page80_i24:dq(44)" )
			)
			( pin "J9U1.251"
				( objectStatus "@baseboard_fab2_lib.baseboard_fab2(sch_1):page80_i24:dq(45)" )
			)
			( pin "J9U1.113"
				( objectStatus "@baseboard_fab2_lib.baseboard_fab2(sch_1):page80_i24:dq(46)" )
			)
			( pin "J9U1.258"
				( objectStatus "@baseboard_fab2_lib.baseboard_fab2(sch_1):page80_i24:dq(47)" )
			)
			( pin "J9U1.119"
				( objectStatus "@baseboard_fab2_lib.baseboard_fab2(sch_1):page80_i24:dq(48)" )
			)
			( pin "J9U1.264"
				( objectStatus "@baseboard_fab2_lib.baseboard_fab2(sch_1):page80_i24:dq(49)" )
			)
			( pin "J9U1.126"
				( objectStatus "@baseboard_fab2_lib.baseboard_fab2(sch_1):page80_i24:dq(50)" )
			)
			( pin "J9U1.271"
				( objectStatus "@baseboard_fab2_lib.baseboard_fab2(sch_1):page80_i24:dq(51)" )
			)
			( pin "J9U1.117"
				( objectStatus "@baseboard_fab2_lib.baseboard_fab2(sch_1):page80_i24:dq(52)" )
			)
			( pin "J9U1.262"
				( objectStatus "@baseboard_fab2_lib.baseboard_fab2(sch_1):page80_i24:dq(53)" )
			)
			( pin "J9U1.124"
				( objectStatus "@baseboard_fab2_lib.baseboard_fab2(sch_1):page80_i24:dq(54)" )
			)
			( pin "J9U1.269"
				( objectStatus "@baseboard_fab2_lib.baseboard_fab2(sch_1):page80_i24:dq(55)" )
			)
			( pin "J9U1.130"
				( objectStatus "@baseboard_fab2_lib.baseboard_fab2(sch_1):page80_i24:dq(56)" )
			)
			( pin "J9U1.275"
				( objectStatus "@baseboard_fab2_lib.baseboard_fab2(sch_1):page80_i24:dq(57)" )
			)
			( pin "J9U1.137"
				( objectStatus "@baseboard_fab2_lib.baseboard_fab2(sch_1):page80_i24:dq(58)" )
			)
			( pin "J9U1.282"
				( objectStatus "@baseboard_fab2_lib.baseboard_fab2(sch_1):page80_i24:dq(59)" )
			)
			( pin "J9U1.128"
				( objectStatus "@baseboard_fab2_lib.baseboard_fab2(sch_1):page80_i24:dq(60)" )
			)
			( pin "J9U1.273"
				( objectStatus "@baseboard_fab2_lib.baseboard_fab2(sch_1):page80_i24:dq(61)" )
			)
			( pin "J9U1.135"
				( objectStatus "@baseboard_fab2_lib.baseboard_fab2(sch_1):page80_i24:dq(62)" )
			)
			( pin "J9U1.280"
				( objectStatus "@baseboard_fab2_lib.baseboard_fab2(sch_1):page80_i24:dq(63)" )
			)
			( pin "J9U1.78"
				( objectStatus "@baseboard_fab2_lib.baseboard_fab2(sch_1):page80_i24:event_n" )
			)
			( pin "J9U1.87"
				( objectStatus "@baseboard_fab2_lib.baseboard_fab2(sch_1):page80_i24:odt(0)" )
			)
			( pin "J9U1.91"
				( objectStatus "@baseboard_fab2_lib.baseboard_fab2(sch_1):page80_i24:odt(1)" )
			)
			( pin "J9U1.222"
				( objectStatus "@baseboard_fab2_lib.baseboard_fab2(sch_1):page80_i24:par" )
			)
			( pin "J9U1.58"
				( objectStatus "@baseboard_fab2_lib.baseboard_fab2(sch_1):page80_i24:reset_n" )
			)
			( pin "J9U1.205"
				( objectStatus "@baseboard_fab2_lib.baseboard_fab2(sch_1):page80_i24:rfu(0)" )
			)
			( pin "J9U1.227"
				( objectStatus "@baseboard_fab2_lib.baseboard_fab2(sch_1):page80_i24:rfu(1)" )
			)
			( pin "J9U1.144"
				( objectStatus "@baseboard_fab2_lib.baseboard_fab2(sch_1):page80_i24:rfu(2)" )
			)
			( pin "J9U1.84"
				( objectStatus "@baseboard_fab2_lib.baseboard_fab2(sch_1):page80_i24:s0_n" )
			)
			( pin "J9U1.89"
				( objectStatus "@baseboard_fab2_lib.baseboard_fab2(sch_1):page80_i24:s1_n" )
			)
			( pin "J9U1.93"
				( objectStatus "@baseboard_fab2_lib.baseboard_fab2(sch_1):page80_i24:s2_n_c(0)" )
			)
			( pin "J9U1.237"
				( objectStatus "@baseboard_fab2_lib.baseboard_fab2(sch_1):page80_i24:s3_n_c(1)" )
			)
			( pin "J9U1.139"
				( objectStatus "@baseboard_fab2_lib.baseboard_fab2(sch_1):page80_i24:sa(0)" )
			)
			( pin "J9U1.140"
				( objectStatus "@baseboard_fab2_lib.baseboard_fab2(sch_1):page80_i24:sa(1)" )
			)
			( pin "J9U1.238"
				( objectStatus "@baseboard_fab2_lib.baseboard_fab2(sch_1):page80_i24:sa(2)" )
			)
			( pin "J9U1.230"
				( objectStatus "@baseboard_fab2_lib.baseboard_fab2(sch_1):page80_i24:save_n_nc" )
			)
			( pin "J9U1.141"
				( objectStatus "@baseboard_fab2_lib.baseboard_fab2(sch_1):page80_i24:scl" )
			)
			( pin "J9U1.285"
				( objectStatus "@baseboard_fab2_lib.baseboard_fab2(sch_1):page80_i24:sda" )
			)
			( pin "J9U1.284"
				( objectStatus "@baseboard_fab2_lib.baseboard_fab2(sch_1):page80_i24:vddspd" )
			)
			( pin "J9U1.146"
				( objectStatus "@baseboard_fab2_lib.baseboard_fab2(sch_1):page80_i24:vrefca" )
			)
			( pin "J9U1.145"
				( objectStatus "@baseboard_fab2_lib.baseboard_fab2(sch_1):page80_i56:\12v\(0)" )
			)
			( pin "J9U1.1"
				( objectStatus "@baseboard_fab2_lib.baseboard_fab2(sch_1):page80_i56:\12v\(1)" )
			)
			( pin "J9U1.236"
				( objectStatus "@baseboard_fab2_lib.baseboard_fab2(sch_1):page80_i56:vdd(0)" )
			)
			( pin "J9U1.233"
				( objectStatus "@baseboard_fab2_lib.baseboard_fab2(sch_1):page80_i56:vdd(1)" )
			)
			( pin "J9U1.231"
				( objectStatus "@baseboard_fab2_lib.baseboard_fab2(sch_1):page80_i56:vdd(2)" )
			)
			( pin "J9U1.229"
				( objectStatus "@baseboard_fab2_lib.baseboard_fab2(sch_1):page80_i56:vdd(3)" )
			)
			( pin "J9U1.226"
				( objectStatus "@baseboard_fab2_lib.baseboard_fab2(sch_1):page80_i56:vdd(4)" )
			)
			( pin "J9U1.223"
				( objectStatus "@baseboard_fab2_lib.baseboard_fab2(sch_1):page80_i56:vdd(5)" )
			)
			( pin "J9U1.220"
				( objectStatus "@baseboard_fab2_lib.baseboard_fab2(sch_1):page80_i56:vdd(6)" )
			)
			( pin "J9U1.217"
				( objectStatus "@baseboard_fab2_lib.baseboard_fab2(sch_1):page80_i56:vdd(7)" )
			)
			( pin "J9U1.215"
				( objectStatus "@baseboard_fab2_lib.baseboard_fab2(sch_1):page80_i56:vdd(8)" )
			)
			( pin "J9U1.212"
				( objectStatus "@baseboard_fab2_lib.baseboard_fab2(sch_1):page80_i56:vdd(9)" )
			)
			( pin "J9U1.209"
				( objectStatus "@baseboard_fab2_lib.baseboard_fab2(sch_1):page80_i56:vdd(10)" )
			)
			( pin "J9U1.206"
				( objectStatus "@baseboard_fab2_lib.baseboard_fab2(sch_1):page80_i56:vdd(11)" )
			)
			( pin "J9U1.204"
				( objectStatus "@baseboard_fab2_lib.baseboard_fab2(sch_1):page80_i56:vdd(12)" )
			)
			( pin "J9U1.92"
				( objectStatus "@baseboard_fab2_lib.baseboard_fab2(sch_1):page80_i56:vdd(13)" )
			)
			( pin "J9U1.90"
				( objectStatus "@baseboard_fab2_lib.baseboard_fab2(sch_1):page80_i56:vdd(14)" )
			)
			( pin "J9U1.88"
				( objectStatus "@baseboard_fab2_lib.baseboard_fab2(sch_1):page80_i56:vdd(15)" )
			)
			( pin "J9U1.85"
				( objectStatus "@baseboard_fab2_lib.baseboard_fab2(sch_1):page80_i56:vdd(16)" )
			)
			( pin "J9U1.83"
				( objectStatus "@baseboard_fab2_lib.baseboard_fab2(sch_1):page80_i56:vdd(17)" )
			)
			( pin "J9U1.80"
				( objectStatus "@baseboard_fab2_lib.baseboard_fab2(sch_1):page80_i56:vdd(18)" )
			)
			( pin "J9U1.76"
				( objectStatus "@baseboard_fab2_lib.baseboard_fab2(sch_1):page80_i56:vdd(19)" )
			)
			( pin "J9U1.73"
				( objectStatus "@baseboard_fab2_lib.baseboard_fab2(sch_1):page80_i56:vdd(20)" )
			)
			( pin "J9U1.70"
				( objectStatus "@baseboard_fab2_lib.baseboard_fab2(sch_1):page80_i56:vdd(21)" )
			)
			( pin "J9U1.67"
				( objectStatus "@baseboard_fab2_lib.baseboard_fab2(sch_1):page80_i56:vdd(22)" )
			)
			( pin "J9U1.64"
				( objectStatus "@baseboard_fab2_lib.baseboard_fab2(sch_1):page80_i56:vdd(23)" )
			)
			( pin "J9U1.61"
				( objectStatus "@baseboard_fab2_lib.baseboard_fab2(sch_1):page80_i56:vdd(24)" )
			)
			( pin "J9U1.59"
				( objectStatus "@baseboard_fab2_lib.baseboard_fab2(sch_1):page80_i56:vdd(25)" )
			)
			( pin "J9U1.287"
				( objectStatus "@baseboard_fab2_lib.baseboard_fab2(sch_1):page80_i56:vpp(0)" )
			)
			( pin "J9U1.286"
				( objectStatus "@baseboard_fab2_lib.baseboard_fab2(sch_1):page80_i56:vpp(1)" )
			)
			( pin "J9U1.288"
				( objectStatus "@baseboard_fab2_lib.baseboard_fab2(sch_1):page80_i56:vpp(2)" )
			)
			( pin "J9U1.143"
				( objectStatus "@baseboard_fab2_lib.baseboard_fab2(sch_1):page80_i56:vpp(3)" )
			)
			( pin "J9U1.142"
				( objectStatus "@baseboard_fab2_lib.baseboard_fab2(sch_1):page80_i56:vpp(4)" )
			)
			( pin "J9U1.221"
				( objectStatus "@baseboard_fab2_lib.baseboard_fab2(sch_1):page80_i56:vtt(0)" )
			)
			( pin "J9U1.77"
				( objectStatus "@baseboard_fab2_lib.baseboard_fab2(sch_1):page80_i56:vtt(1)" )
			)
			( pin "J9U1.152"
				( objectStatus "@baseboard_fab2_lib.baseboard_fab2(sch_1):page80_i101:dqs0n" )
			)
			( pin "J9U1.153"
				( objectStatus "@baseboard_fab2_lib.baseboard_fab2(sch_1):page80_i101:dqs0p" )
			)
			( pin "J9U1.163"
				( objectStatus "@baseboard_fab2_lib.baseboard_fab2(sch_1):page80_i101:dqs1n" )
			)
			( pin "J9U1.164"
				( objectStatus "@baseboard_fab2_lib.baseboard_fab2(sch_1):page80_i101:dqs1p" )
			)
			( pin "J9U1.174"
				( objectStatus "@baseboard_fab2_lib.baseboard_fab2(sch_1):page80_i101:dqs2n" )
			)
			( pin "J9U1.175"
				( objectStatus "@baseboard_fab2_lib.baseboard_fab2(sch_1):page80_i101:dqs2p" )
			)
			( pin "J9U1.185"
				( objectStatus "@baseboard_fab2_lib.baseboard_fab2(sch_1):page80_i101:dqs3n" )
			)
			( pin "J9U1.186"
				( objectStatus "@baseboard_fab2_lib.baseboard_fab2(sch_1):page80_i101:dqs3p" )
			)
			( pin "J9U1.244"
				( objectStatus "@baseboard_fab2_lib.baseboard_fab2(sch_1):page80_i101:dqs4n" )
			)
			( pin "J9U1.245"
				( objectStatus "@baseboard_fab2_lib.baseboard_fab2(sch_1):page80_i101:dqs4p" )
			)
			( pin "J9U1.255"
				( objectStatus "@baseboard_fab2_lib.baseboard_fab2(sch_1):page80_i101:dqs5n" )
			)
			( pin "J9U1.256"
				( objectStatus "@baseboard_fab2_lib.baseboard_fab2(sch_1):page80_i101:dqs5p" )
			)
			( pin "J9U1.266"
				( objectStatus "@baseboard_fab2_lib.baseboard_fab2(sch_1):page80_i101:dqs6n" )
			)
			( pin "J9U1.267"
				( objectStatus "@baseboard_fab2_lib.baseboard_fab2(sch_1):page80_i101:dqs6p" )
			)
			( pin "J9U1.277"
				( objectStatus "@baseboard_fab2_lib.baseboard_fab2(sch_1):page80_i101:dqs7n" )
			)
			( pin "J9U1.278"
				( objectStatus "@baseboard_fab2_lib.baseboard_fab2(sch_1):page80_i101:dqs7p" )
			)
			( pin "J9U1.196"
				( objectStatus "@baseboard_fab2_lib.baseboard_fab2(sch_1):page80_i101:dqs8n" )
			)
			( pin "J9U1.197"
				( objectStatus "@baseboard_fab2_lib.baseboard_fab2(sch_1):page80_i101:dqs8p" )
			)
			( pin "J9U1.8"
				( objectStatus "@baseboard_fab2_lib.baseboard_fab2(sch_1):page80_i101:dqs9n" )
			)
			( pin "J9U1.7"
				( objectStatus "@baseboard_fab2_lib.baseboard_fab2(sch_1):page80_i101:dqs9p" )
			)
			( pin "J9U1.19"
				( objectStatus "@baseboard_fab2_lib.baseboard_fab2(sch_1):page80_i101:dqs10n" )
			)
			( pin "J9U1.18"
				( objectStatus "@baseboard_fab2_lib.baseboard_fab2(sch_1):page80_i101:dqs10p" )
			)
			( pin "J9U1.30"
				( objectStatus "@baseboard_fab2_lib.baseboard_fab2(sch_1):page80_i101:dqs11n" )
			)
			( pin "J9U1.29"
				( objectStatus "@baseboard_fab2_lib.baseboard_fab2(sch_1):page80_i101:dqs11p" )
			)
			( pin "J9U1.41"
				( objectStatus "@baseboard_fab2_lib.baseboard_fab2(sch_1):page80_i101:dqs12n" )
			)
			( pin "J9U1.40"
				( objectStatus "@baseboard_fab2_lib.baseboard_fab2(sch_1):page80_i101:dqs12p" )
			)
			( pin "J9U1.100"
				( objectStatus "@baseboard_fab2_lib.baseboard_fab2(sch_1):page80_i101:dqs13n" )
			)
			( pin "J9U1.99"
				( objectStatus "@baseboard_fab2_lib.baseboard_fab2(sch_1):page80_i101:dqs13p" )
			)
			( pin "J9U1.111"
				( objectStatus "@baseboard_fab2_lib.baseboard_fab2(sch_1):page80_i101:dqs14n" )
			)
			( pin "J9U1.110"
				( objectStatus "@baseboard_fab2_lib.baseboard_fab2(sch_1):page80_i101:dqs14p" )
			)
			( pin "J9U1.122"
				( objectStatus "@baseboard_fab2_lib.baseboard_fab2(sch_1):page80_i101:dqs15n" )
			)
			( pin "J9U1.121"
				( objectStatus "@baseboard_fab2_lib.baseboard_fab2(sch_1):page80_i101:dqs15p" )
			)
			( pin "J9U1.133"
				( objectStatus "@baseboard_fab2_lib.baseboard_fab2(sch_1):page80_i101:dqs16n" )
			)
			( pin "J9U1.132"
				( objectStatus "@baseboard_fab2_lib.baseboard_fab2(sch_1):page80_i101:dqs16p" )
			)
			( pin "J9U1.52"
				( objectStatus "@baseboard_fab2_lib.baseboard_fab2(sch_1):page80_i101:dqs17n" )
			)
			( pin "J9U1.51"
				( objectStatus "@baseboard_fab2_lib.baseboard_fab2(sch_1):page80_i101:dqs17p" )
			)
			( pin "J9U1.283"
				( objectStatus "@baseboard_fab2_lib.baseboard_fab2(sch_1):page80_i138:vss(0)" )
			)
			( pin "J9U1.281"
				( objectStatus "@baseboard_fab2_lib.baseboard_fab2(sch_1):page80_i138:vss(1)" )
			)
			( pin "J9U1.279"
				( objectStatus "@baseboard_fab2_lib.baseboard_fab2(sch_1):page80_i138:vss(2)" )
			)
			( pin "J9U1.276"
				( objectStatus "@baseboard_fab2_lib.baseboard_fab2(sch_1):page80_i138:vss(3)" )
			)
			( pin "J9U1.274"
				( objectStatus "@baseboard_fab2_lib.baseboard_fab2(sch_1):page80_i138:vss(4)" )
			)
			( pin "J9U1.272"
				( objectStatus "@baseboard_fab2_lib.baseboard_fab2(sch_1):page80_i138:vss(5)" )
			)
			( pin "J9U1.270"
				( objectStatus "@baseboard_fab2_lib.baseboard_fab2(sch_1):page80_i138:vss(6)" )
			)
			( pin "J9U1.268"
				( objectStatus "@baseboard_fab2_lib.baseboard_fab2(sch_1):page80_i138:vss(7)" )
			)
			( pin "J9U1.265"
				( objectStatus "@baseboard_fab2_lib.baseboard_fab2(sch_1):page80_i138:vss(8)" )
			)
			( pin "J9U1.263"
				( objectStatus "@baseboard_fab2_lib.baseboard_fab2(sch_1):page80_i138:vss(9)" )
			)
			( pin "J9U1.261"
				( objectStatus "@baseboard_fab2_lib.baseboard_fab2(sch_1):page80_i138:vss(10)" )
			)
			( pin "J9U1.259"
				( objectStatus "@baseboard_fab2_lib.baseboard_fab2(sch_1):page80_i138:vss(11)" )
			)
			( pin "J9U1.257"
				( objectStatus "@baseboard_fab2_lib.baseboard_fab2(sch_1):page80_i138:vss(12)" )
			)
			( pin "J9U1.254"
				( objectStatus "@baseboard_fab2_lib.baseboard_fab2(sch_1):page80_i138:vss(13)" )
			)
			( pin "J9U1.252"
				( objectStatus "@baseboard_fab2_lib.baseboard_fab2(sch_1):page80_i138:vss(14)" )
			)
			( pin "J9U1.250"
				( objectStatus "@baseboard_fab2_lib.baseboard_fab2(sch_1):page80_i138:vss(15)" )
			)
			( pin "J9U1.248"
				( objectStatus "@baseboard_fab2_lib.baseboard_fab2(sch_1):page80_i138:vss(16)" )
			)
			( pin "J9U1.246"
				( objectStatus "@baseboard_fab2_lib.baseboard_fab2(sch_1):page80_i138:vss(17)" )
			)
			( pin "J9U1.243"
				( objectStatus "@baseboard_fab2_lib.baseboard_fab2(sch_1):page80_i138:vss(18)" )
			)
			( pin "J9U1.241"
				( objectStatus "@baseboard_fab2_lib.baseboard_fab2(sch_1):page80_i138:vss(19)" )
			)
			( pin "J9U1.239"
				( objectStatus "@baseboard_fab2_lib.baseboard_fab2(sch_1):page80_i138:vss(20)" )
			)
			( pin "J9U1.202"
				( objectStatus "@baseboard_fab2_lib.baseboard_fab2(sch_1):page80_i138:vss(21)" )
			)
			( pin "J9U1.200"
				( objectStatus "@baseboard_fab2_lib.baseboard_fab2(sch_1):page80_i138:vss(22)" )
			)
			( pin "J9U1.198"
				( objectStatus "@baseboard_fab2_lib.baseboard_fab2(sch_1):page80_i138:vss(23)" )
			)
			( pin "J9U1.195"
				( objectStatus "@baseboard_fab2_lib.baseboard_fab2(sch_1):page80_i138:vss(24)" )
			)
			( pin "J9U1.193"
				( objectStatus "@baseboard_fab2_lib.baseboard_fab2(sch_1):page80_i138:vss(25)" )
			)
			( pin "J9U1.191"
				( objectStatus "@baseboard_fab2_lib.baseboard_fab2(sch_1):page80_i138:vss(26)" )
			)
			( pin "J9U1.189"
				( objectStatus "@baseboard_fab2_lib.baseboard_fab2(sch_1):page80_i138:vss(27)" )
			)
			( pin "J9U1.187"
				( objectStatus "@baseboard_fab2_lib.baseboard_fab2(sch_1):page80_i138:vss(28)" )
			)
			( pin "J9U1.184"
				( objectStatus "@baseboard_fab2_lib.baseboard_fab2(sch_1):page80_i138:vss(29)" )
			)
			( pin "J9U1.182"
				( objectStatus "@baseboard_fab2_lib.baseboard_fab2(sch_1):page80_i138:vss(30)" )
			)
			( pin "J9U1.180"
				( objectStatus "@baseboard_fab2_lib.baseboard_fab2(sch_1):page80_i138:vss(31)" )
			)
			( pin "J9U1.178"
				( objectStatus "@baseboard_fab2_lib.baseboard_fab2(sch_1):page80_i138:vss(32)" )
			)
			( pin "J9U1.176"
				( objectStatus "@baseboard_fab2_lib.baseboard_fab2(sch_1):page80_i138:vss(33)" )
			)
			( pin "J9U1.173"
				( objectStatus "@baseboard_fab2_lib.baseboard_fab2(sch_1):page80_i138:vss(34)" )
			)
			( pin "J9U1.171"
				( objectStatus "@baseboard_fab2_lib.baseboard_fab2(sch_1):page80_i138:vss(35)" )
			)
			( pin "J9U1.169"
				( objectStatus "@baseboard_fab2_lib.baseboard_fab2(sch_1):page80_i138:vss(36)" )
			)
			( pin "J9U1.167"
				( objectStatus "@baseboard_fab2_lib.baseboard_fab2(sch_1):page80_i138:vss(37)" )
			)
			( pin "J9U1.165"
				( objectStatus "@baseboard_fab2_lib.baseboard_fab2(sch_1):page80_i138:vss(38)" )
			)
			( pin "J9U1.162"
				( objectStatus "@baseboard_fab2_lib.baseboard_fab2(sch_1):page80_i138:vss(39)" )
			)
			( pin "J9U1.160"
				( objectStatus "@baseboard_fab2_lib.baseboard_fab2(sch_1):page80_i138:vss(40)" )
			)
			( pin "J9U1.158"
				( objectStatus "@baseboard_fab2_lib.baseboard_fab2(sch_1):page80_i138:vss(41)" )
			)
			( pin "J9U1.156"
				( objectStatus "@baseboard_fab2_lib.baseboard_fab2(sch_1):page80_i138:vss(42)" )
			)
			( pin "J9U1.154"
				( objectStatus "@baseboard_fab2_lib.baseboard_fab2(sch_1):page80_i138:vss(43)" )
			)
			( pin "J9U1.151"
				( objectStatus "@baseboard_fab2_lib.baseboard_fab2(sch_1):page80_i138:vss(44)" )
			)
			( pin "J9U1.149"
				( objectStatus "@baseboard_fab2_lib.baseboard_fab2(sch_1):page80_i138:vss(45)" )
			)
			( pin "J9U1.147"
				( objectStatus "@baseboard_fab2_lib.baseboard_fab2(sch_1):page80_i138:vss(46)" )
			)
			( pin "J9U1.138"
				( objectStatus "@baseboard_fab2_lib.baseboard_fab2(sch_1):page80_i138:vss(47)" )
			)
			( pin "J9U1.136"
				( objectStatus "@baseboard_fab2_lib.baseboard_fab2(sch_1):page80_i138:vss(48)" )
			)
			( pin "J9U1.134"
				( objectStatus "@baseboard_fab2_lib.baseboard_fab2(sch_1):page80_i138:vss(49)" )
			)
			( pin "J9U1.131"
				( objectStatus "@baseboard_fab2_lib.baseboard_fab2(sch_1):page80_i138:vss(50)" )
			)
			( pin "J9U1.129"
				( objectStatus "@baseboard_fab2_lib.baseboard_fab2(sch_1):page80_i138:vss(51)" )
			)
			( pin "J9U1.127"
				( objectStatus "@baseboard_fab2_lib.baseboard_fab2(sch_1):page80_i138:vss(52)" )
			)
			( pin "J9U1.125"
				( objectStatus "@baseboard_fab2_lib.baseboard_fab2(sch_1):page80_i138:vss(53)" )
			)
			( pin "J9U1.123"
				( objectStatus "@baseboard_fab2_lib.baseboard_fab2(sch_1):page80_i138:vss(54)" )
			)
			( pin "J9U1.120"
				( objectStatus "@baseboard_fab2_lib.baseboard_fab2(sch_1):page80_i138:vss(55)" )
			)
			( pin "J9U1.118"
				( objectStatus "@baseboard_fab2_lib.baseboard_fab2(sch_1):page80_i138:vss(56)" )
			)
			( pin "J9U1.116"
				( objectStatus "@baseboard_fab2_lib.baseboard_fab2(sch_1):page80_i138:vss(57)" )
			)
			( pin "J9U1.114"
				( objectStatus "@baseboard_fab2_lib.baseboard_fab2(sch_1):page80_i138:vss(58)" )
			)
			( pin "J9U1.112"
				( objectStatus "@baseboard_fab2_lib.baseboard_fab2(sch_1):page80_i138:vss(59)" )
			)
			( pin "J9U1.109"
				( objectStatus "@baseboard_fab2_lib.baseboard_fab2(sch_1):page80_i138:vss(60)" )
			)
			( pin "J9U1.107"
				( objectStatus "@baseboard_fab2_lib.baseboard_fab2(sch_1):page80_i138:vss(61)" )
			)
			( pin "J9U1.105"
				( objectStatus "@baseboard_fab2_lib.baseboard_fab2(sch_1):page80_i138:vss(62)" )
			)
			( pin "J9U1.103"
				( objectStatus "@baseboard_fab2_lib.baseboard_fab2(sch_1):page80_i138:vss(63)" )
			)
			( pin "J9U1.101"
				( objectStatus "@baseboard_fab2_lib.baseboard_fab2(sch_1):page80_i138:vss(64)" )
			)
			( pin "J9U1.98"
				( objectStatus "@baseboard_fab2_lib.baseboard_fab2(sch_1):page80_i138:vss(65)" )
			)
			( pin "J9U1.96"
				( objectStatus "@baseboard_fab2_lib.baseboard_fab2(sch_1):page80_i138:vss(66)" )
			)
			( pin "J9U1.94"
				( objectStatus "@baseboard_fab2_lib.baseboard_fab2(sch_1):page80_i138:vss(67)" )
			)
			( pin "J9U1.57"
				( objectStatus "@baseboard_fab2_lib.baseboard_fab2(sch_1):page80_i138:vss(68)" )
			)
			( pin "J9U1.55"
				( objectStatus "@baseboard_fab2_lib.baseboard_fab2(sch_1):page80_i138:vss(69)" )
			)
			( pin "J9U1.53"
				( objectStatus "@baseboard_fab2_lib.baseboard_fab2(sch_1):page80_i138:vss(70)" )
			)
			( pin "J9U1.50"
				( objectStatus "@baseboard_fab2_lib.baseboard_fab2(sch_1):page80_i138:vss(71)" )
			)
			( pin "J9U1.48"
				( objectStatus "@baseboard_fab2_lib.baseboard_fab2(sch_1):page80_i138:vss(72)" )
			)
			( pin "J9U1.46"
				( objectStatus "@baseboard_fab2_lib.baseboard_fab2(sch_1):page80_i138:vss(73)" )
			)
			( pin "J9U1.44"
				( objectStatus "@baseboard_fab2_lib.baseboard_fab2(sch_1):page80_i138:vss(74)" )
			)
			( pin "J9U1.42"
				( objectStatus "@baseboard_fab2_lib.baseboard_fab2(sch_1):page80_i138:vss(75)" )
			)
			( pin "J9U1.39"
				( objectStatus "@baseboard_fab2_lib.baseboard_fab2(sch_1):page80_i138:vss(76)" )
			)
			( pin "J9U1.37"
				( objectStatus "@baseboard_fab2_lib.baseboard_fab2(sch_1):page80_i138:vss(77)" )
			)
			( pin "J9U1.35"
				( objectStatus "@baseboard_fab2_lib.baseboard_fab2(sch_1):page80_i138:vss(78)" )
			)
			( pin "J9U1.33"
				( objectStatus "@baseboard_fab2_lib.baseboard_fab2(sch_1):page80_i138:vss(79)" )
			)
			( pin "J9U1.31"
				( objectStatus "@baseboard_fab2_lib.baseboard_fab2(sch_1):page80_i138:vss(80)" )
			)
			( pin "J9U1.28"
				( objectStatus "@baseboard_fab2_lib.baseboard_fab2(sch_1):page80_i138:vss(81)" )
			)
			( pin "J9U1.26"
				( objectStatus "@baseboard_fab2_lib.baseboard_fab2(sch_1):page80_i138:vss(82)" )
			)
			( pin "J9U1.24"
				( objectStatus "@baseboard_fab2_lib.baseboard_fab2(sch_1):page80_i138:vss(83)" )
			)
			( pin "J9U1.22"
				( objectStatus "@baseboard_fab2_lib.baseboard_fab2(sch_1):page80_i138:vss(84)" )
			)
			( pin "J9U1.20"
				( objectStatus "@baseboard_fab2_lib.baseboard_fab2(sch_1):page80_i138:vss(85)" )
			)
			( pin "J9U1.17"
				( objectStatus "@baseboard_fab2_lib.baseboard_fab2(sch_1):page80_i138:vss(86)" )
			)
			( pin "J9U1.15"
				( objectStatus "@baseboard_fab2_lib.baseboard_fab2(sch_1):page80_i138:vss(87)" )
			)
			( pin "J9U1.13"
				( objectStatus "@baseboard_fab2_lib.baseboard_fab2(sch_1):page80_i138:vss(88)" )
			)
			( pin "J9U1.11"
				( objectStatus "@baseboard_fab2_lib.baseboard_fab2(sch_1):page80_i138:vss(89)" )
			)
			( pin "J9U1.9"
				( objectStatus "@baseboard_fab2_lib.baseboard_fab2(sch_1):page80_i138:vss(90)" )
			)
			( pin "J9U1.6"
				( objectStatus "@baseboard_fab2_lib.baseboard_fab2(sch_1):page80_i138:vss(91)" )
			)
			( pin "J9U1.4"
				( objectStatus "@baseboard_fab2_lib.baseboard_fab2(sch_1):page80_i138:vss(92)" )
			)
			( pin "J9U1.2"
				( objectStatus "@baseboard_fab2_lib.baseboard_fab2(sch_1):page80_i138:vss(93)" )
			)
			( pin "J1G3.152"
				( objectStatus "@baseboard_fab2_lib.baseboard_fab2(sch_1):page81_i67:dqs0n" )
			)
			( pin "J1G3.153"
				( objectStatus "@baseboard_fab2_lib.baseboard_fab2(sch_1):page81_i67:dqs0p" )
			)
			( pin "J1G3.163"
				( objectStatus "@baseboard_fab2_lib.baseboard_fab2(sch_1):page81_i67:dqs1n" )
			)
			( pin "J1G3.164"
				( objectStatus "@baseboard_fab2_lib.baseboard_fab2(sch_1):page81_i67:dqs1p" )
			)
			( pin "J1G3.174"
				( objectStatus "@baseboard_fab2_lib.baseboard_fab2(sch_1):page81_i67:dqs2n" )
			)
			( pin "J1G3.175"
				( objectStatus "@baseboard_fab2_lib.baseboard_fab2(sch_1):page81_i67:dqs2p" )
			)
			( pin "J1G3.185"
				( objectStatus "@baseboard_fab2_lib.baseboard_fab2(sch_1):page81_i67:dqs3n" )
			)
			( pin "J1G3.186"
				( objectStatus "@baseboard_fab2_lib.baseboard_fab2(sch_1):page81_i67:dqs3p" )
			)
			( pin "J1G3.244"
				( objectStatus "@baseboard_fab2_lib.baseboard_fab2(sch_1):page81_i67:dqs4n" )
			)
			( pin "J1G3.245"
				( objectStatus "@baseboard_fab2_lib.baseboard_fab2(sch_1):page81_i67:dqs4p" )
			)
			( pin "J1G3.255"
				( objectStatus "@baseboard_fab2_lib.baseboard_fab2(sch_1):page81_i67:dqs5n" )
			)
			( pin "J1G3.256"
				( objectStatus "@baseboard_fab2_lib.baseboard_fab2(sch_1):page81_i67:dqs5p" )
			)
			( pin "J1G3.266"
				( objectStatus "@baseboard_fab2_lib.baseboard_fab2(sch_1):page81_i67:dqs6n" )
			)
			( pin "J1G3.267"
				( objectStatus "@baseboard_fab2_lib.baseboard_fab2(sch_1):page81_i67:dqs6p" )
			)
			( pin "J1G3.277"
				( objectStatus "@baseboard_fab2_lib.baseboard_fab2(sch_1):page81_i67:dqs7n" )
			)
			( pin "J1G3.278"
				( objectStatus "@baseboard_fab2_lib.baseboard_fab2(sch_1):page81_i67:dqs7p" )
			)
			( pin "J1G3.196"
				( objectStatus "@baseboard_fab2_lib.baseboard_fab2(sch_1):page81_i67:dqs8n" )
			)
			( pin "J1G3.197"
				( objectStatus "@baseboard_fab2_lib.baseboard_fab2(sch_1):page81_i67:dqs8p" )
			)
			( pin "J1G3.8"
				( objectStatus "@baseboard_fab2_lib.baseboard_fab2(sch_1):page81_i67:dqs9n" )
			)
			( pin "J1G3.7"
				( objectStatus "@baseboard_fab2_lib.baseboard_fab2(sch_1):page81_i67:dqs9p" )
			)
			( pin "J1G3.19"
				( objectStatus "@baseboard_fab2_lib.baseboard_fab2(sch_1):page81_i67:dqs10n" )
			)
			( pin "J1G3.18"
				( objectStatus "@baseboard_fab2_lib.baseboard_fab2(sch_1):page81_i67:dqs10p" )
			)
			( pin "J1G3.30"
				( objectStatus "@baseboard_fab2_lib.baseboard_fab2(sch_1):page81_i67:dqs11n" )
			)
			( pin "J1G3.29"
				( objectStatus "@baseboard_fab2_lib.baseboard_fab2(sch_1):page81_i67:dqs11p" )
			)
			( pin "J1G3.41"
				( objectStatus "@baseboard_fab2_lib.baseboard_fab2(sch_1):page81_i67:dqs12n" )
			)
			( pin "J1G3.40"
				( objectStatus "@baseboard_fab2_lib.baseboard_fab2(sch_1):page81_i67:dqs12p" )
			)
			( pin "J1G3.100"
				( objectStatus "@baseboard_fab2_lib.baseboard_fab2(sch_1):page81_i67:dqs13n" )
			)
			( pin "J1G3.99"
				( objectStatus "@baseboard_fab2_lib.baseboard_fab2(sch_1):page81_i67:dqs13p" )
			)
			( pin "J1G3.111"
				( objectStatus "@baseboard_fab2_lib.baseboard_fab2(sch_1):page81_i67:dqs14n" )
			)
			( pin "J1G3.110"
				( objectStatus "@baseboard_fab2_lib.baseboard_fab2(sch_1):page81_i67:dqs14p" )
			)
			( pin "J1G3.122"
				( objectStatus "@baseboard_fab2_lib.baseboard_fab2(sch_1):page81_i67:dqs15n" )
			)
			( pin "J1G3.121"
				( objectStatus "@baseboard_fab2_lib.baseboard_fab2(sch_1):page81_i67:dqs15p" )
			)
			( pin "J1G3.133"
				( objectStatus "@baseboard_fab2_lib.baseboard_fab2(sch_1):page81_i67:dqs16n" )
			)
			( pin "J1G3.132"
				( objectStatus "@baseboard_fab2_lib.baseboard_fab2(sch_1):page81_i67:dqs16p" )
			)
			( pin "J1G3.52"
				( objectStatus "@baseboard_fab2_lib.baseboard_fab2(sch_1):page81_i67:dqs17n" )
			)
			( pin "J1G3.51"
				( objectStatus "@baseboard_fab2_lib.baseboard_fab2(sch_1):page81_i67:dqs17p" )
			)
			( pin "J1G3.145"
				( objectStatus "@baseboard_fab2_lib.baseboard_fab2(sch_1):page81_i169:\12v\(0)" )
			)
			( pin "J1G3.1"
				( objectStatus "@baseboard_fab2_lib.baseboard_fab2(sch_1):page81_i169:\12v\(1)" )
			)
			( pin "J1G3.236"
				( objectStatus "@baseboard_fab2_lib.baseboard_fab2(sch_1):page81_i169:vdd(0)" )
			)
			( pin "J1G3.233"
				( objectStatus "@baseboard_fab2_lib.baseboard_fab2(sch_1):page81_i169:vdd(1)" )
			)
			( pin "J1G3.231"
				( objectStatus "@baseboard_fab2_lib.baseboard_fab2(sch_1):page81_i169:vdd(2)" )
			)
			( pin "J1G3.229"
				( objectStatus "@baseboard_fab2_lib.baseboard_fab2(sch_1):page81_i169:vdd(3)" )
			)
			( pin "J1G3.226"
				( objectStatus "@baseboard_fab2_lib.baseboard_fab2(sch_1):page81_i169:vdd(4)" )
			)
			( pin "J1G3.223"
				( objectStatus "@baseboard_fab2_lib.baseboard_fab2(sch_1):page81_i169:vdd(5)" )
			)
			( pin "J1G3.220"
				( objectStatus "@baseboard_fab2_lib.baseboard_fab2(sch_1):page81_i169:vdd(6)" )
			)
			( pin "J1G3.217"
				( objectStatus "@baseboard_fab2_lib.baseboard_fab2(sch_1):page81_i169:vdd(7)" )
			)
			( pin "J1G3.215"
				( objectStatus "@baseboard_fab2_lib.baseboard_fab2(sch_1):page81_i169:vdd(8)" )
			)
			( pin "J1G3.212"
				( objectStatus "@baseboard_fab2_lib.baseboard_fab2(sch_1):page81_i169:vdd(9)" )
			)
			( pin "J1G3.209"
				( objectStatus "@baseboard_fab2_lib.baseboard_fab2(sch_1):page81_i169:vdd(10)" )
			)
			( pin "J1G3.206"
				( objectStatus "@baseboard_fab2_lib.baseboard_fab2(sch_1):page81_i169:vdd(11)" )
			)
			( pin "J1G3.204"
				( objectStatus "@baseboard_fab2_lib.baseboard_fab2(sch_1):page81_i169:vdd(12)" )
			)
			( pin "J1G3.92"
				( objectStatus "@baseboard_fab2_lib.baseboard_fab2(sch_1):page81_i169:vdd(13)" )
			)
			( pin "J1G3.90"
				( objectStatus "@baseboard_fab2_lib.baseboard_fab2(sch_1):page81_i169:vdd(14)" )
			)
			( pin "J1G3.88"
				( objectStatus "@baseboard_fab2_lib.baseboard_fab2(sch_1):page81_i169:vdd(15)" )
			)
			( pin "J1G3.85"
				( objectStatus "@baseboard_fab2_lib.baseboard_fab2(sch_1):page81_i169:vdd(16)" )
			)
			( pin "J1G3.83"
				( objectStatus "@baseboard_fab2_lib.baseboard_fab2(sch_1):page81_i169:vdd(17)" )
			)
			( pin "J1G3.80"
				( objectStatus "@baseboard_fab2_lib.baseboard_fab2(sch_1):page81_i169:vdd(18)" )
			)
			( pin "J1G3.76"
				( objectStatus "@baseboard_fab2_lib.baseboard_fab2(sch_1):page81_i169:vdd(19)" )
			)
			( pin "J1G3.73"
				( objectStatus "@baseboard_fab2_lib.baseboard_fab2(sch_1):page81_i169:vdd(20)" )
			)
			( pin "J1G3.70"
				( objectStatus "@baseboard_fab2_lib.baseboard_fab2(sch_1):page81_i169:vdd(21)" )
			)
			( pin "J1G3.67"
				( objectStatus "@baseboard_fab2_lib.baseboard_fab2(sch_1):page81_i169:vdd(22)" )
			)
			( pin "J1G3.64"
				( objectStatus "@baseboard_fab2_lib.baseboard_fab2(sch_1):page81_i169:vdd(23)" )
			)
			( pin "J1G3.61"
				( objectStatus "@baseboard_fab2_lib.baseboard_fab2(sch_1):page81_i169:vdd(24)" )
			)
			( pin "J1G3.59"
				( objectStatus "@baseboard_fab2_lib.baseboard_fab2(sch_1):page81_i169:vdd(25)" )
			)
			( pin "J1G3.287"
				( objectStatus "@baseboard_fab2_lib.baseboard_fab2(sch_1):page81_i169:vpp(0)" )
			)
			( pin "J1G3.286"
				( objectStatus "@baseboard_fab2_lib.baseboard_fab2(sch_1):page81_i169:vpp(1)" )
			)
			( pin "J1G3.288"
				( objectStatus "@baseboard_fab2_lib.baseboard_fab2(sch_1):page81_i169:vpp(2)" )
			)
			( pin "J1G3.143"
				( objectStatus "@baseboard_fab2_lib.baseboard_fab2(sch_1):page81_i169:vpp(3)" )
			)
			( pin "J1G3.142"
				( objectStatus "@baseboard_fab2_lib.baseboard_fab2(sch_1):page81_i169:vpp(4)" )
			)
			( pin "J1G3.221"
				( objectStatus "@baseboard_fab2_lib.baseboard_fab2(sch_1):page81_i169:vtt(0)" )
			)
			( pin "J1G3.77"
				( objectStatus "@baseboard_fab2_lib.baseboard_fab2(sch_1):page81_i169:vtt(1)" )
			)
			( pin "C9U10.1"
				( objectStatus "@baseboard_fab2_lib.baseboard_fab2(sch_1):page81_i178:a" )
			)
			( pin "C9U10.2"
				( objectStatus "@baseboard_fab2_lib.baseboard_fab2(sch_1):page81_i178:b" )
			)
			( pin "J1G3.283"
				( objectStatus "@baseboard_fab2_lib.baseboard_fab2(sch_1):page81_i185:vss(0)" )
			)
			( pin "J1G3.281"
				( objectStatus "@baseboard_fab2_lib.baseboard_fab2(sch_1):page81_i185:vss(1)" )
			)
			( pin "J1G3.279"
				( objectStatus "@baseboard_fab2_lib.baseboard_fab2(sch_1):page81_i185:vss(2)" )
			)
			( pin "J1G3.276"
				( objectStatus "@baseboard_fab2_lib.baseboard_fab2(sch_1):page81_i185:vss(3)" )
			)
			( pin "J1G3.274"
				( objectStatus "@baseboard_fab2_lib.baseboard_fab2(sch_1):page81_i185:vss(4)" )
			)
			( pin "J1G3.272"
				( objectStatus "@baseboard_fab2_lib.baseboard_fab2(sch_1):page81_i185:vss(5)" )
			)
			( pin "J1G3.270"
				( objectStatus "@baseboard_fab2_lib.baseboard_fab2(sch_1):page81_i185:vss(6)" )
			)
			( pin "J1G3.268"
				( objectStatus "@baseboard_fab2_lib.baseboard_fab2(sch_1):page81_i185:vss(7)" )
			)
			( pin "J1G3.265"
				( objectStatus "@baseboard_fab2_lib.baseboard_fab2(sch_1):page81_i185:vss(8)" )
			)
			( pin "J1G3.263"
				( objectStatus "@baseboard_fab2_lib.baseboard_fab2(sch_1):page81_i185:vss(9)" )
			)
			( pin "J1G3.261"
				( objectStatus "@baseboard_fab2_lib.baseboard_fab2(sch_1):page81_i185:vss(10)" )
			)
			( pin "J1G3.259"
				( objectStatus "@baseboard_fab2_lib.baseboard_fab2(sch_1):page81_i185:vss(11)" )
			)
			( pin "J1G3.257"
				( objectStatus "@baseboard_fab2_lib.baseboard_fab2(sch_1):page81_i185:vss(12)" )
			)
			( pin "J1G3.254"
				( objectStatus "@baseboard_fab2_lib.baseboard_fab2(sch_1):page81_i185:vss(13)" )
			)
			( pin "J1G3.252"
				( objectStatus "@baseboard_fab2_lib.baseboard_fab2(sch_1):page81_i185:vss(14)" )
			)
			( pin "J1G3.250"
				( objectStatus "@baseboard_fab2_lib.baseboard_fab2(sch_1):page81_i185:vss(15)" )
			)
			( pin "J1G3.248"
				( objectStatus "@baseboard_fab2_lib.baseboard_fab2(sch_1):page81_i185:vss(16)" )
			)
			( pin "J1G3.246"
				( objectStatus "@baseboard_fab2_lib.baseboard_fab2(sch_1):page81_i185:vss(17)" )
			)
			( pin "J1G3.243"
				( objectStatus "@baseboard_fab2_lib.baseboard_fab2(sch_1):page81_i185:vss(18)" )
			)
			( pin "J1G3.241"
				( objectStatus "@baseboard_fab2_lib.baseboard_fab2(sch_1):page81_i185:vss(19)" )
			)
			( pin "J1G3.239"
				( objectStatus "@baseboard_fab2_lib.baseboard_fab2(sch_1):page81_i185:vss(20)" )
			)
			( pin "J1G3.202"
				( objectStatus "@baseboard_fab2_lib.baseboard_fab2(sch_1):page81_i185:vss(21)" )
			)
			( pin "J1G3.200"
				( objectStatus "@baseboard_fab2_lib.baseboard_fab2(sch_1):page81_i185:vss(22)" )
			)
			( pin "J1G3.198"
				( objectStatus "@baseboard_fab2_lib.baseboard_fab2(sch_1):page81_i185:vss(23)" )
			)
			( pin "J1G3.195"
				( objectStatus "@baseboard_fab2_lib.baseboard_fab2(sch_1):page81_i185:vss(24)" )
			)
			( pin "J1G3.193"
				( objectStatus "@baseboard_fab2_lib.baseboard_fab2(sch_1):page81_i185:vss(25)" )
			)
			( pin "J1G3.191"
				( objectStatus "@baseboard_fab2_lib.baseboard_fab2(sch_1):page81_i185:vss(26)" )
			)
			( pin "J1G3.189"
				( objectStatus "@baseboard_fab2_lib.baseboard_fab2(sch_1):page81_i185:vss(27)" )
			)
			( pin "J1G3.187"
				( objectStatus "@baseboard_fab2_lib.baseboard_fab2(sch_1):page81_i185:vss(28)" )
			)
			( pin "J1G3.184"
				( objectStatus "@baseboard_fab2_lib.baseboard_fab2(sch_1):page81_i185:vss(29)" )
			)
			( pin "J1G3.182"
				( objectStatus "@baseboard_fab2_lib.baseboard_fab2(sch_1):page81_i185:vss(30)" )
			)
			( pin "J1G3.180"
				( objectStatus "@baseboard_fab2_lib.baseboard_fab2(sch_1):page81_i185:vss(31)" )
			)
			( pin "J1G3.178"
				( objectStatus "@baseboard_fab2_lib.baseboard_fab2(sch_1):page81_i185:vss(32)" )
			)
			( pin "J1G3.176"
				( objectStatus "@baseboard_fab2_lib.baseboard_fab2(sch_1):page81_i185:vss(33)" )
			)
			( pin "J1G3.173"
				( objectStatus "@baseboard_fab2_lib.baseboard_fab2(sch_1):page81_i185:vss(34)" )
			)
			( pin "J1G3.171"
				( objectStatus "@baseboard_fab2_lib.baseboard_fab2(sch_1):page81_i185:vss(35)" )
			)
			( pin "J1G3.169"
				( objectStatus "@baseboard_fab2_lib.baseboard_fab2(sch_1):page81_i185:vss(36)" )
			)
			( pin "J1G3.167"
				( objectStatus "@baseboard_fab2_lib.baseboard_fab2(sch_1):page81_i185:vss(37)" )
			)
			( pin "J1G3.165"
				( objectStatus "@baseboard_fab2_lib.baseboard_fab2(sch_1):page81_i185:vss(38)" )
			)
			( pin "J1G3.162"
				( objectStatus "@baseboard_fab2_lib.baseboard_fab2(sch_1):page81_i185:vss(39)" )
			)
			( pin "J1G3.160"
				( objectStatus "@baseboard_fab2_lib.baseboard_fab2(sch_1):page81_i185:vss(40)" )
			)
			( pin "J1G3.158"
				( objectStatus "@baseboard_fab2_lib.baseboard_fab2(sch_1):page81_i185:vss(41)" )
			)
			( pin "J1G3.156"
				( objectStatus "@baseboard_fab2_lib.baseboard_fab2(sch_1):page81_i185:vss(42)" )
			)
			( pin "J1G3.154"
				( objectStatus "@baseboard_fab2_lib.baseboard_fab2(sch_1):page81_i185:vss(43)" )
			)
			( pin "J1G3.151"
				( objectStatus "@baseboard_fab2_lib.baseboard_fab2(sch_1):page81_i185:vss(44)" )
			)
			( pin "J1G3.149"
				( objectStatus "@baseboard_fab2_lib.baseboard_fab2(sch_1):page81_i185:vss(45)" )
			)
			( pin "J1G3.147"
				( objectStatus "@baseboard_fab2_lib.baseboard_fab2(sch_1):page81_i185:vss(46)" )
			)
			( pin "J1G3.138"
				( objectStatus "@baseboard_fab2_lib.baseboard_fab2(sch_1):page81_i185:vss(47)" )
			)
			( pin "J1G3.136"
				( objectStatus "@baseboard_fab2_lib.baseboard_fab2(sch_1):page81_i185:vss(48)" )
			)
			( pin "J1G3.134"
				( objectStatus "@baseboard_fab2_lib.baseboard_fab2(sch_1):page81_i185:vss(49)" )
			)
			( pin "J1G3.131"
				( objectStatus "@baseboard_fab2_lib.baseboard_fab2(sch_1):page81_i185:vss(50)" )
			)
			( pin "J1G3.129"
				( objectStatus "@baseboard_fab2_lib.baseboard_fab2(sch_1):page81_i185:vss(51)" )
			)
			( pin "J1G3.127"
				( objectStatus "@baseboard_fab2_lib.baseboard_fab2(sch_1):page81_i185:vss(52)" )
			)
			( pin "J1G3.125"
				( objectStatus "@baseboard_fab2_lib.baseboard_fab2(sch_1):page81_i185:vss(53)" )
			)
			( pin "J1G3.123"
				( objectStatus "@baseboard_fab2_lib.baseboard_fab2(sch_1):page81_i185:vss(54)" )
			)
			( pin "J1G3.120"
				( objectStatus "@baseboard_fab2_lib.baseboard_fab2(sch_1):page81_i185:vss(55)" )
			)
			( pin "J1G3.118"
				( objectStatus "@baseboard_fab2_lib.baseboard_fab2(sch_1):page81_i185:vss(56)" )
			)
			( pin "J1G3.116"
				( objectStatus "@baseboard_fab2_lib.baseboard_fab2(sch_1):page81_i185:vss(57)" )
			)
			( pin "J1G3.114"
				( objectStatus "@baseboard_fab2_lib.baseboard_fab2(sch_1):page81_i185:vss(58)" )
			)
			( pin "J1G3.112"
				( objectStatus "@baseboard_fab2_lib.baseboard_fab2(sch_1):page81_i185:vss(59)" )
			)
			( pin "J1G3.109"
				( objectStatus "@baseboard_fab2_lib.baseboard_fab2(sch_1):page81_i185:vss(60)" )
			)
			( pin "J1G3.107"
				( objectStatus "@baseboard_fab2_lib.baseboard_fab2(sch_1):page81_i185:vss(61)" )
			)
			( pin "J1G3.105"
				( objectStatus "@baseboard_fab2_lib.baseboard_fab2(sch_1):page81_i185:vss(62)" )
			)
			( pin "J1G3.103"
				( objectStatus "@baseboard_fab2_lib.baseboard_fab2(sch_1):page81_i185:vss(63)" )
			)
			( pin "J1G3.101"
				( objectStatus "@baseboard_fab2_lib.baseboard_fab2(sch_1):page81_i185:vss(64)" )
			)
			( pin "J1G3.98"
				( objectStatus "@baseboard_fab2_lib.baseboard_fab2(sch_1):page81_i185:vss(65)" )
			)
			( pin "J1G3.96"
				( objectStatus "@baseboard_fab2_lib.baseboard_fab2(sch_1):page81_i185:vss(66)" )
			)
			( pin "J1G3.94"
				( objectStatus "@baseboard_fab2_lib.baseboard_fab2(sch_1):page81_i185:vss(67)" )
			)
			( pin "J1G3.57"
				( objectStatus "@baseboard_fab2_lib.baseboard_fab2(sch_1):page81_i185:vss(68)" )
			)
			( pin "J1G3.55"
				( objectStatus "@baseboard_fab2_lib.baseboard_fab2(sch_1):page81_i185:vss(69)" )
			)
			( pin "J1G3.53"
				( objectStatus "@baseboard_fab2_lib.baseboard_fab2(sch_1):page81_i185:vss(70)" )
			)
			( pin "J1G3.50"
				( objectStatus "@baseboard_fab2_lib.baseboard_fab2(sch_1):page81_i185:vss(71)" )
			)
			( pin "J1G3.48"
				( objectStatus "@baseboard_fab2_lib.baseboard_fab2(sch_1):page81_i185:vss(72)" )
			)
			( pin "J1G3.46"
				( objectStatus "@baseboard_fab2_lib.baseboard_fab2(sch_1):page81_i185:vss(73)" )
			)
			( pin "J1G3.44"
				( objectStatus "@baseboard_fab2_lib.baseboard_fab2(sch_1):page81_i185:vss(74)" )
			)
			( pin "J1G3.42"
				( objectStatus "@baseboard_fab2_lib.baseboard_fab2(sch_1):page81_i185:vss(75)" )
			)
			( pin "J1G3.39"
				( objectStatus "@baseboard_fab2_lib.baseboard_fab2(sch_1):page81_i185:vss(76)" )
			)
			( pin "J1G3.37"
				( objectStatus "@baseboard_fab2_lib.baseboard_fab2(sch_1):page81_i185:vss(77)" )
			)
			( pin "J1G3.35"
				( objectStatus "@baseboard_fab2_lib.baseboard_fab2(sch_1):page81_i185:vss(78)" )
			)
			( pin "J1G3.33"
				( objectStatus "@baseboard_fab2_lib.baseboard_fab2(sch_1):page81_i185:vss(79)" )
			)
			( pin "J1G3.31"
				( objectStatus "@baseboard_fab2_lib.baseboard_fab2(sch_1):page81_i185:vss(80)" )
			)
			( pin "J1G3.28"
				( objectStatus "@baseboard_fab2_lib.baseboard_fab2(sch_1):page81_i185:vss(81)" )
			)
			( pin "J1G3.26"
				( objectStatus "@baseboard_fab2_lib.baseboard_fab2(sch_1):page81_i185:vss(82)" )
			)
			( pin "J1G3.24"
				( objectStatus "@baseboard_fab2_lib.baseboard_fab2(sch_1):page81_i185:vss(83)" )
			)
			( pin "J1G3.22"
				( objectStatus "@baseboard_fab2_lib.baseboard_fab2(sch_1):page81_i185:vss(84)" )
			)
			( pin "J1G3.20"
				( objectStatus "@baseboard_fab2_lib.baseboard_fab2(sch_1):page81_i185:vss(85)" )
			)
			( pin "J1G3.17"
				( objectStatus "@baseboard_fab2_lib.baseboard_fab2(sch_1):page81_i185:vss(86)" )
			)
			( pin "J1G3.15"
				( objectStatus "@baseboard_fab2_lib.baseboard_fab2(sch_1):page81_i185:vss(87)" )
			)
			( pin "J1G3.13"
				( objectStatus "@baseboard_fab2_lib.baseboard_fab2(sch_1):page81_i185:vss(88)" )
			)
			( pin "J1G3.11"
				( objectStatus "@baseboard_fab2_lib.baseboard_fab2(sch_1):page81_i185:vss(89)" )
			)
			( pin "J1G3.9"
				( objectStatus "@baseboard_fab2_lib.baseboard_fab2(sch_1):page81_i185:vss(90)" )
			)
			( pin "J1G3.6"
				( objectStatus "@baseboard_fab2_lib.baseboard_fab2(sch_1):page81_i185:vss(91)" )
			)
			( pin "J1G3.4"
				( objectStatus "@baseboard_fab2_lib.baseboard_fab2(sch_1):page81_i185:vss(92)" )
			)
			( pin "J1G3.2"
				( objectStatus "@baseboard_fab2_lib.baseboard_fab2(sch_1):page81_i185:vss(93)" )
			)
			( pin "J1G3.79"
				( objectStatus "@baseboard_fab2_lib.baseboard_fab2(sch_1):page81_i186:a0" )
			)
			( pin "J1G3.72"
				( objectStatus "@baseboard_fab2_lib.baseboard_fab2(sch_1):page81_i186:a1" )
			)
			( pin "J1G3.216"
				( objectStatus "@baseboard_fab2_lib.baseboard_fab2(sch_1):page81_i186:a2" )
			)
			( pin "J1G3.71"
				( objectStatus "@baseboard_fab2_lib.baseboard_fab2(sch_1):page81_i186:a3" )
			)
			( pin "J1G3.214"
				( objectStatus "@baseboard_fab2_lib.baseboard_fab2(sch_1):page81_i186:a4" )
			)
			( pin "J1G3.213"
				( objectStatus "@baseboard_fab2_lib.baseboard_fab2(sch_1):page81_i186:a5" )
			)
			( pin "J1G3.69"
				( objectStatus "@baseboard_fab2_lib.baseboard_fab2(sch_1):page81_i186:a6" )
			)
			( pin "J1G3.211"
				( objectStatus "@baseboard_fab2_lib.baseboard_fab2(sch_1):page81_i186:a7" )
			)
			( pin "J1G3.68"
				( objectStatus "@baseboard_fab2_lib.baseboard_fab2(sch_1):page81_i186:a8" )
			)
			( pin "J1G3.66"
				( objectStatus "@baseboard_fab2_lib.baseboard_fab2(sch_1):page81_i186:a9" )
			)
			( pin "J1G3.225"
				( objectStatus "@baseboard_fab2_lib.baseboard_fab2(sch_1):page81_i186:a10" )
			)
			( pin "J1G3.210"
				( objectStatus "@baseboard_fab2_lib.baseboard_fab2(sch_1):page81_i186:a11" )
			)
			( pin "J1G3.65"
				( objectStatus "@baseboard_fab2_lib.baseboard_fab2(sch_1):page81_i186:a12" )
			)
			( pin "J1G3.232"
				( objectStatus "@baseboard_fab2_lib.baseboard_fab2(sch_1):page81_i186:a13" )
			)
			( pin "J1G3.228"
				( objectStatus "@baseboard_fab2_lib.baseboard_fab2(sch_1):page81_i186:a14_we_n" )
			)
			( pin "J1G3.86"
				( objectStatus "@baseboard_fab2_lib.baseboard_fab2(sch_1):page81_i186:a15_cas_n" )
			)
			( pin "J1G3.82"
				( objectStatus "@baseboard_fab2_lib.baseboard_fab2(sch_1):page81_i186:a16_ras_n" )
			)
			( pin "J1G3.234"
				( objectStatus "@baseboard_fab2_lib.baseboard_fab2(sch_1):page81_i186:a17" )
			)
			( pin "J1G3.62"
				( objectStatus "@baseboard_fab2_lib.baseboard_fab2(sch_1):page81_i186:act_n" )
			)
			( pin "J1G3.208"
				( objectStatus "@baseboard_fab2_lib.baseboard_fab2(sch_1):page81_i186:alert_n" )
			)
			( pin "J1G3.81"
				( objectStatus "@baseboard_fab2_lib.baseboard_fab2(sch_1):page81_i186:ba(0)" )
			)
			( pin "J1G3.224"
				( objectStatus "@baseboard_fab2_lib.baseboard_fab2(sch_1):page81_i186:ba(1)" )
			)
			( pin "J1G3.63"
				( objectStatus "@baseboard_fab2_lib.baseboard_fab2(sch_1):page81_i186:bg(0)" )
			)
			( pin "J1G3.207"
				( objectStatus "@baseboard_fab2_lib.baseboard_fab2(sch_1):page81_i186:bg(1)" )
			)
			( pin "J1G3.235"
				( objectStatus "@baseboard_fab2_lib.baseboard_fab2(sch_1):page81_i186:c(2)" )
			)
			( pin "J1G3.49"
				( objectStatus "@baseboard_fab2_lib.baseboard_fab2(sch_1):page81_i186:cb(0)" )
			)
			( pin "J1G3.194"
				( objectStatus "@baseboard_fab2_lib.baseboard_fab2(sch_1):page81_i186:cb(1)" )
			)
			( pin "J1G3.56"
				( objectStatus "@baseboard_fab2_lib.baseboard_fab2(sch_1):page81_i186:cb(2)" )
			)
			( pin "J1G3.201"
				( objectStatus "@baseboard_fab2_lib.baseboard_fab2(sch_1):page81_i186:cb(3)" )
			)
			( pin "J1G3.47"
				( objectStatus "@baseboard_fab2_lib.baseboard_fab2(sch_1):page81_i186:cb(4)" )
			)
			( pin "J1G3.192"
				( objectStatus "@baseboard_fab2_lib.baseboard_fab2(sch_1):page81_i186:cb(5)" )
			)
			( pin "J1G3.54"
				( objectStatus "@baseboard_fab2_lib.baseboard_fab2(sch_1):page81_i186:cb(6)" )
			)
			( pin "J1G3.199"
				( objectStatus "@baseboard_fab2_lib.baseboard_fab2(sch_1):page81_i186:cb(7)" )
			)
			( pin "J1G3.75"
				( objectStatus "@baseboard_fab2_lib.baseboard_fab2(sch_1):page81_i186:ck0n" )
			)
			( pin "J1G3.74"
				( objectStatus "@baseboard_fab2_lib.baseboard_fab2(sch_1):page81_i186:ck0p" )
			)
			( pin "J1G3.219"
				( objectStatus "@baseboard_fab2_lib.baseboard_fab2(sch_1):page81_i186:ck1n" )
			)
			( pin "J1G3.218"
				( objectStatus "@baseboard_fab2_lib.baseboard_fab2(sch_1):page81_i186:ck1p" )
			)
			( pin "J1G3.60"
				( objectStatus "@baseboard_fab2_lib.baseboard_fab2(sch_1):page81_i186:cke(0)" )
			)
			( pin "J1G3.203"
				( objectStatus "@baseboard_fab2_lib.baseboard_fab2(sch_1):page81_i186:cke(1)" )
			)
			( pin "J1G3.5"
				( objectStatus "@baseboard_fab2_lib.baseboard_fab2(sch_1):page81_i186:dq(0)" )
			)
			( pin "J1G3.150"
				( objectStatus "@baseboard_fab2_lib.baseboard_fab2(sch_1):page81_i186:dq(1)" )
			)
			( pin "J1G3.12"
				( objectStatus "@baseboard_fab2_lib.baseboard_fab2(sch_1):page81_i186:dq(2)" )
			)
			( pin "J1G3.157"
				( objectStatus "@baseboard_fab2_lib.baseboard_fab2(sch_1):page81_i186:dq(3)" )
			)
			( pin "J1G3.3"
				( objectStatus "@baseboard_fab2_lib.baseboard_fab2(sch_1):page81_i186:dq(4)" )
			)
			( pin "J1G3.148"
				( objectStatus "@baseboard_fab2_lib.baseboard_fab2(sch_1):page81_i186:dq(5)" )
			)
			( pin "J1G3.10"
				( objectStatus "@baseboard_fab2_lib.baseboard_fab2(sch_1):page81_i186:dq(6)" )
			)
			( pin "J1G3.155"
				( objectStatus "@baseboard_fab2_lib.baseboard_fab2(sch_1):page81_i186:dq(7)" )
			)
			( pin "J1G3.16"
				( objectStatus "@baseboard_fab2_lib.baseboard_fab2(sch_1):page81_i186:dq(8)" )
			)
			( pin "J1G3.161"
				( objectStatus "@baseboard_fab2_lib.baseboard_fab2(sch_1):page81_i186:dq(9)" )
			)
			( pin "J1G3.23"
				( objectStatus "@baseboard_fab2_lib.baseboard_fab2(sch_1):page81_i186:dq(10)" )
			)
			( pin "J1G3.168"
				( objectStatus "@baseboard_fab2_lib.baseboard_fab2(sch_1):page81_i186:dq(11)" )
			)
			( pin "J1G3.14"
				( objectStatus "@baseboard_fab2_lib.baseboard_fab2(sch_1):page81_i186:dq(12)" )
			)
			( pin "J1G3.159"
				( objectStatus "@baseboard_fab2_lib.baseboard_fab2(sch_1):page81_i186:dq(13)" )
			)
			( pin "J1G3.21"
				( objectStatus "@baseboard_fab2_lib.baseboard_fab2(sch_1):page81_i186:dq(14)" )
			)
			( pin "J1G3.166"
				( objectStatus "@baseboard_fab2_lib.baseboard_fab2(sch_1):page81_i186:dq(15)" )
			)
			( pin "J1G3.27"
				( objectStatus "@baseboard_fab2_lib.baseboard_fab2(sch_1):page81_i186:dq(16)" )
			)
			( pin "J1G3.172"
				( objectStatus "@baseboard_fab2_lib.baseboard_fab2(sch_1):page81_i186:dq(17)" )
			)
			( pin "J1G3.34"
				( objectStatus "@baseboard_fab2_lib.baseboard_fab2(sch_1):page81_i186:dq(18)" )
			)
			( pin "J1G3.179"
				( objectStatus "@baseboard_fab2_lib.baseboard_fab2(sch_1):page81_i186:dq(19)" )
			)
			( pin "J1G3.25"
				( objectStatus "@baseboard_fab2_lib.baseboard_fab2(sch_1):page81_i186:dq(20)" )
			)
			( pin "J1G3.170"
				( objectStatus "@baseboard_fab2_lib.baseboard_fab2(sch_1):page81_i186:dq(21)" )
			)
			( pin "J1G3.32"
				( objectStatus "@baseboard_fab2_lib.baseboard_fab2(sch_1):page81_i186:dq(22)" )
			)
			( pin "J1G3.177"
				( objectStatus "@baseboard_fab2_lib.baseboard_fab2(sch_1):page81_i186:dq(23)" )
			)
			( pin "J1G3.38"
				( objectStatus "@baseboard_fab2_lib.baseboard_fab2(sch_1):page81_i186:dq(24)" )
			)
			( pin "J1G3.183"
				( objectStatus "@baseboard_fab2_lib.baseboard_fab2(sch_1):page81_i186:dq(25)" )
			)
			( pin "J1G3.45"
				( objectStatus "@baseboard_fab2_lib.baseboard_fab2(sch_1):page81_i186:dq(26)" )
			)
			( pin "J1G3.190"
				( objectStatus "@baseboard_fab2_lib.baseboard_fab2(sch_1):page81_i186:dq(27)" )
			)
			( pin "J1G3.36"
				( objectStatus "@baseboard_fab2_lib.baseboard_fab2(sch_1):page81_i186:dq(28)" )
			)
			( pin "J1G3.181"
				( objectStatus "@baseboard_fab2_lib.baseboard_fab2(sch_1):page81_i186:dq(29)" )
			)
			( pin "J1G3.43"
				( objectStatus "@baseboard_fab2_lib.baseboard_fab2(sch_1):page81_i186:dq(30)" )
			)
			( pin "J1G3.188"
				( objectStatus "@baseboard_fab2_lib.baseboard_fab2(sch_1):page81_i186:dq(31)" )
			)
			( pin "J1G3.97"
				( objectStatus "@baseboard_fab2_lib.baseboard_fab2(sch_1):page81_i186:dq(32)" )
			)
			( pin "J1G3.242"
				( objectStatus "@baseboard_fab2_lib.baseboard_fab2(sch_1):page81_i186:dq(33)" )
			)
			( pin "J1G3.104"
				( objectStatus "@baseboard_fab2_lib.baseboard_fab2(sch_1):page81_i186:dq(34)" )
			)
			( pin "J1G3.249"
				( objectStatus "@baseboard_fab2_lib.baseboard_fab2(sch_1):page81_i186:dq(35)" )
			)
			( pin "J1G3.95"
				( objectStatus "@baseboard_fab2_lib.baseboard_fab2(sch_1):page81_i186:dq(36)" )
			)
			( pin "J1G3.240"
				( objectStatus "@baseboard_fab2_lib.baseboard_fab2(sch_1):page81_i186:dq(37)" )
			)
			( pin "J1G3.102"
				( objectStatus "@baseboard_fab2_lib.baseboard_fab2(sch_1):page81_i186:dq(38)" )
			)
			( pin "J1G3.247"
				( objectStatus "@baseboard_fab2_lib.baseboard_fab2(sch_1):page81_i186:dq(39)" )
			)
			( pin "J1G3.108"
				( objectStatus "@baseboard_fab2_lib.baseboard_fab2(sch_1):page81_i186:dq(40)" )
			)
			( pin "J1G3.253"
				( objectStatus "@baseboard_fab2_lib.baseboard_fab2(sch_1):page81_i186:dq(41)" )
			)
			( pin "J1G3.115"
				( objectStatus "@baseboard_fab2_lib.baseboard_fab2(sch_1):page81_i186:dq(42)" )
			)
			( pin "J1G3.260"
				( objectStatus "@baseboard_fab2_lib.baseboard_fab2(sch_1):page81_i186:dq(43)" )
			)
			( pin "J1G3.106"
				( objectStatus "@baseboard_fab2_lib.baseboard_fab2(sch_1):page81_i186:dq(44)" )
			)
			( pin "J1G3.251"
				( objectStatus "@baseboard_fab2_lib.baseboard_fab2(sch_1):page81_i186:dq(45)" )
			)
			( pin "J1G3.113"
				( objectStatus "@baseboard_fab2_lib.baseboard_fab2(sch_1):page81_i186:dq(46)" )
			)
			( pin "J1G3.258"
				( objectStatus "@baseboard_fab2_lib.baseboard_fab2(sch_1):page81_i186:dq(47)" )
			)
			( pin "J1G3.119"
				( objectStatus "@baseboard_fab2_lib.baseboard_fab2(sch_1):page81_i186:dq(48)" )
			)
			( pin "J1G3.264"
				( objectStatus "@baseboard_fab2_lib.baseboard_fab2(sch_1):page81_i186:dq(49)" )
			)
			( pin "J1G3.126"
				( objectStatus "@baseboard_fab2_lib.baseboard_fab2(sch_1):page81_i186:dq(50)" )
			)
			( pin "J1G3.271"
				( objectStatus "@baseboard_fab2_lib.baseboard_fab2(sch_1):page81_i186:dq(51)" )
			)
			( pin "J1G3.117"
				( objectStatus "@baseboard_fab2_lib.baseboard_fab2(sch_1):page81_i186:dq(52)" )
			)
			( pin "J1G3.262"
				( objectStatus "@baseboard_fab2_lib.baseboard_fab2(sch_1):page81_i186:dq(53)" )
			)
			( pin "J1G3.124"
				( objectStatus "@baseboard_fab2_lib.baseboard_fab2(sch_1):page81_i186:dq(54)" )
			)
			( pin "J1G3.269"
				( objectStatus "@baseboard_fab2_lib.baseboard_fab2(sch_1):page81_i186:dq(55)" )
			)
			( pin "J1G3.130"
				( objectStatus "@baseboard_fab2_lib.baseboard_fab2(sch_1):page81_i186:dq(56)" )
			)
			( pin "J1G3.275"
				( objectStatus "@baseboard_fab2_lib.baseboard_fab2(sch_1):page81_i186:dq(57)" )
			)
			( pin "J1G3.137"
				( objectStatus "@baseboard_fab2_lib.baseboard_fab2(sch_1):page81_i186:dq(58)" )
			)
			( pin "J1G3.282"
				( objectStatus "@baseboard_fab2_lib.baseboard_fab2(sch_1):page81_i186:dq(59)" )
			)
			( pin "J1G3.128"
				( objectStatus "@baseboard_fab2_lib.baseboard_fab2(sch_1):page81_i186:dq(60)" )
			)
			( pin "J1G3.273"
				( objectStatus "@baseboard_fab2_lib.baseboard_fab2(sch_1):page81_i186:dq(61)" )
			)
			( pin "J1G3.135"
				( objectStatus "@baseboard_fab2_lib.baseboard_fab2(sch_1):page81_i186:dq(62)" )
			)
			( pin "J1G3.280"
				( objectStatus "@baseboard_fab2_lib.baseboard_fab2(sch_1):page81_i186:dq(63)" )
			)
			( pin "J1G3.78"
				( objectStatus "@baseboard_fab2_lib.baseboard_fab2(sch_1):page81_i186:event_n" )
			)
			( pin "J1G3.87"
				( objectStatus "@baseboard_fab2_lib.baseboard_fab2(sch_1):page81_i186:odt(0)" )
			)
			( pin "J1G3.91"
				( objectStatus "@baseboard_fab2_lib.baseboard_fab2(sch_1):page81_i186:odt(1)" )
			)
			( pin "J1G3.222"
				( objectStatus "@baseboard_fab2_lib.baseboard_fab2(sch_1):page81_i186:par" )
			)
			( pin "J1G3.58"
				( objectStatus "@baseboard_fab2_lib.baseboard_fab2(sch_1):page81_i186:reset_n" )
			)
			( pin "J1G3.205"
				( objectStatus "@baseboard_fab2_lib.baseboard_fab2(sch_1):page81_i186:rfu(0)" )
			)
			( pin "J1G3.227"
				( objectStatus "@baseboard_fab2_lib.baseboard_fab2(sch_1):page81_i186:rfu(1)" )
			)
			( pin "J1G3.144"
				( objectStatus "@baseboard_fab2_lib.baseboard_fab2(sch_1):page81_i186:rfu(2)" )
			)
			( pin "J1G3.84"
				( objectStatus "@baseboard_fab2_lib.baseboard_fab2(sch_1):page81_i186:s0_n" )
			)
			( pin "J1G3.89"
				( objectStatus "@baseboard_fab2_lib.baseboard_fab2(sch_1):page81_i186:s1_n" )
			)
			( pin "J1G3.93"
				( objectStatus "@baseboard_fab2_lib.baseboard_fab2(sch_1):page81_i186:s2_n_c(0)" )
			)
			( pin "J1G3.237"
				( objectStatus "@baseboard_fab2_lib.baseboard_fab2(sch_1):page81_i186:s3_n_c(1)" )
			)
			( pin "J1G3.139"
				( objectStatus "@baseboard_fab2_lib.baseboard_fab2(sch_1):page81_i186:sa(0)" )
			)
			( pin "J1G3.140"
				( objectStatus "@baseboard_fab2_lib.baseboard_fab2(sch_1):page81_i186:sa(1)" )
			)
			( pin "J1G3.238"
				( objectStatus "@baseboard_fab2_lib.baseboard_fab2(sch_1):page81_i186:sa(2)" )
			)
			( pin "J1G3.230"
				( objectStatus "@baseboard_fab2_lib.baseboard_fab2(sch_1):page81_i186:save_n_nc" )
			)
			( pin "J1G3.141"
				( objectStatus "@baseboard_fab2_lib.baseboard_fab2(sch_1):page81_i186:scl" )
			)
			( pin "J1G3.285"
				( objectStatus "@baseboard_fab2_lib.baseboard_fab2(sch_1):page81_i186:sda" )
			)
			( pin "J1G3.284"
				( objectStatus "@baseboard_fab2_lib.baseboard_fab2(sch_1):page81_i186:vddspd" )
			)
			( pin "J1G3.146"
				( objectStatus "@baseboard_fab2_lib.baseboard_fab2(sch_1):page81_i186:vrefca" )
			)
			( pin "J9U2.152"
				( objectStatus "@baseboard_fab2_lib.baseboard_fab2(sch_1):page82_i64:dqs0n" )
			)
			( pin "J9U2.153"
				( objectStatus "@baseboard_fab2_lib.baseboard_fab2(sch_1):page82_i64:dqs0p" )
			)
			( pin "J9U2.163"
				( objectStatus "@baseboard_fab2_lib.baseboard_fab2(sch_1):page82_i64:dqs1n" )
			)
			( pin "J9U2.164"
				( objectStatus "@baseboard_fab2_lib.baseboard_fab2(sch_1):page82_i64:dqs1p" )
			)
			( pin "J9U2.174"
				( objectStatus "@baseboard_fab2_lib.baseboard_fab2(sch_1):page82_i64:dqs2n" )
			)
			( pin "J9U2.175"
				( objectStatus "@baseboard_fab2_lib.baseboard_fab2(sch_1):page82_i64:dqs2p" )
			)
			( pin "J9U2.185"
				( objectStatus "@baseboard_fab2_lib.baseboard_fab2(sch_1):page82_i64:dqs3n" )
			)
			( pin "J9U2.186"
				( objectStatus "@baseboard_fab2_lib.baseboard_fab2(sch_1):page82_i64:dqs3p" )
			)
			( pin "J9U2.244"
				( objectStatus "@baseboard_fab2_lib.baseboard_fab2(sch_1):page82_i64:dqs4n" )
			)
			( pin "J9U2.245"
				( objectStatus "@baseboard_fab2_lib.baseboard_fab2(sch_1):page82_i64:dqs4p" )
			)
			( pin "J9U2.255"
				( objectStatus "@baseboard_fab2_lib.baseboard_fab2(sch_1):page82_i64:dqs5n" )
			)
			( pin "J9U2.256"
				( objectStatus "@baseboard_fab2_lib.baseboard_fab2(sch_1):page82_i64:dqs5p" )
			)
			( pin "J9U2.266"
				( objectStatus "@baseboard_fab2_lib.baseboard_fab2(sch_1):page82_i64:dqs6n" )
			)
			( pin "J9U2.267"
				( objectStatus "@baseboard_fab2_lib.baseboard_fab2(sch_1):page82_i64:dqs6p" )
			)
			( pin "J9U2.277"
				( objectStatus "@baseboard_fab2_lib.baseboard_fab2(sch_1):page82_i64:dqs7n" )
			)
			( pin "J9U2.278"
				( objectStatus "@baseboard_fab2_lib.baseboard_fab2(sch_1):page82_i64:dqs7p" )
			)
			( pin "J9U2.196"
				( objectStatus "@baseboard_fab2_lib.baseboard_fab2(sch_1):page82_i64:dqs8n" )
			)
			( pin "J9U2.197"
				( objectStatus "@baseboard_fab2_lib.baseboard_fab2(sch_1):page82_i64:dqs8p" )
			)
			( pin "J9U2.8"
				( objectStatus "@baseboard_fab2_lib.baseboard_fab2(sch_1):page82_i64:dqs9n" )
			)
			( pin "J9U2.7"
				( objectStatus "@baseboard_fab2_lib.baseboard_fab2(sch_1):page82_i64:dqs9p" )
			)
			( pin "J9U2.19"
				( objectStatus "@baseboard_fab2_lib.baseboard_fab2(sch_1):page82_i64:dqs10n" )
			)
			( pin "J9U2.18"
				( objectStatus "@baseboard_fab2_lib.baseboard_fab2(sch_1):page82_i64:dqs10p" )
			)
			( pin "J9U2.30"
				( objectStatus "@baseboard_fab2_lib.baseboard_fab2(sch_1):page82_i64:dqs11n" )
			)
			( pin "J9U2.29"
				( objectStatus "@baseboard_fab2_lib.baseboard_fab2(sch_1):page82_i64:dqs11p" )
			)
			( pin "J9U2.41"
				( objectStatus "@baseboard_fab2_lib.baseboard_fab2(sch_1):page82_i64:dqs12n" )
			)
			( pin "J9U2.40"
				( objectStatus "@baseboard_fab2_lib.baseboard_fab2(sch_1):page82_i64:dqs12p" )
			)
			( pin "J9U2.100"
				( objectStatus "@baseboard_fab2_lib.baseboard_fab2(sch_1):page82_i64:dqs13n" )
			)
			( pin "J9U2.99"
				( objectStatus "@baseboard_fab2_lib.baseboard_fab2(sch_1):page82_i64:dqs13p" )
			)
			( pin "J9U2.111"
				( objectStatus "@baseboard_fab2_lib.baseboard_fab2(sch_1):page82_i64:dqs14n" )
			)
			( pin "J9U2.110"
				( objectStatus "@baseboard_fab2_lib.baseboard_fab2(sch_1):page82_i64:dqs14p" )
			)
			( pin "J9U2.122"
				( objectStatus "@baseboard_fab2_lib.baseboard_fab2(sch_1):page82_i64:dqs15n" )
			)
			( pin "J9U2.121"
				( objectStatus "@baseboard_fab2_lib.baseboard_fab2(sch_1):page82_i64:dqs15p" )
			)
			( pin "J9U2.133"
				( objectStatus "@baseboard_fab2_lib.baseboard_fab2(sch_1):page82_i64:dqs16n" )
			)
			( pin "J9U2.132"
				( objectStatus "@baseboard_fab2_lib.baseboard_fab2(sch_1):page82_i64:dqs16p" )
			)
			( pin "J9U2.52"
				( objectStatus "@baseboard_fab2_lib.baseboard_fab2(sch_1):page82_i64:dqs17n" )
			)
			( pin "J9U2.51"
				( objectStatus "@baseboard_fab2_lib.baseboard_fab2(sch_1):page82_i64:dqs17p" )
			)
			( pin "J9U2.145"
				( objectStatus "@baseboard_fab2_lib.baseboard_fab2(sch_1):page82_i171:\12v\(0)" )
			)
			( pin "J9U2.1"
				( objectStatus "@baseboard_fab2_lib.baseboard_fab2(sch_1):page82_i171:\12v\(1)" )
			)
			( pin "J9U2.236"
				( objectStatus "@baseboard_fab2_lib.baseboard_fab2(sch_1):page82_i171:vdd(0)" )
			)
			( pin "J9U2.233"
				( objectStatus "@baseboard_fab2_lib.baseboard_fab2(sch_1):page82_i171:vdd(1)" )
			)
			( pin "J9U2.231"
				( objectStatus "@baseboard_fab2_lib.baseboard_fab2(sch_1):page82_i171:vdd(2)" )
			)
			( pin "J9U2.229"
				( objectStatus "@baseboard_fab2_lib.baseboard_fab2(sch_1):page82_i171:vdd(3)" )
			)
			( pin "J9U2.226"
				( objectStatus "@baseboard_fab2_lib.baseboard_fab2(sch_1):page82_i171:vdd(4)" )
			)
			( pin "J9U2.223"
				( objectStatus "@baseboard_fab2_lib.baseboard_fab2(sch_1):page82_i171:vdd(5)" )
			)
			( pin "J9U2.220"
				( objectStatus "@baseboard_fab2_lib.baseboard_fab2(sch_1):page82_i171:vdd(6)" )
			)
			( pin "J9U2.217"
				( objectStatus "@baseboard_fab2_lib.baseboard_fab2(sch_1):page82_i171:vdd(7)" )
			)
			( pin "J9U2.215"
				( objectStatus "@baseboard_fab2_lib.baseboard_fab2(sch_1):page82_i171:vdd(8)" )
			)
			( pin "J9U2.212"
				( objectStatus "@baseboard_fab2_lib.baseboard_fab2(sch_1):page82_i171:vdd(9)" )
			)
			( pin "J9U2.209"
				( objectStatus "@baseboard_fab2_lib.baseboard_fab2(sch_1):page82_i171:vdd(10)" )
			)
			( pin "J9U2.206"
				( objectStatus "@baseboard_fab2_lib.baseboard_fab2(sch_1):page82_i171:vdd(11)" )
			)
			( pin "J9U2.204"
				( objectStatus "@baseboard_fab2_lib.baseboard_fab2(sch_1):page82_i171:vdd(12)" )
			)
			( pin "J9U2.92"
				( objectStatus "@baseboard_fab2_lib.baseboard_fab2(sch_1):page82_i171:vdd(13)" )
			)
			( pin "J9U2.90"
				( objectStatus "@baseboard_fab2_lib.baseboard_fab2(sch_1):page82_i171:vdd(14)" )
			)
			( pin "J9U2.88"
				( objectStatus "@baseboard_fab2_lib.baseboard_fab2(sch_1):page82_i171:vdd(15)" )
			)
			( pin "J9U2.85"
				( objectStatus "@baseboard_fab2_lib.baseboard_fab2(sch_1):page82_i171:vdd(16)" )
			)
			( pin "J9U2.83"
				( objectStatus "@baseboard_fab2_lib.baseboard_fab2(sch_1):page82_i171:vdd(17)" )
			)
			( pin "J9U2.80"
				( objectStatus "@baseboard_fab2_lib.baseboard_fab2(sch_1):page82_i171:vdd(18)" )
			)
			( pin "J9U2.76"
				( objectStatus "@baseboard_fab2_lib.baseboard_fab2(sch_1):page82_i171:vdd(19)" )
			)
			( pin "J9U2.73"
				( objectStatus "@baseboard_fab2_lib.baseboard_fab2(sch_1):page82_i171:vdd(20)" )
			)
			( pin "J9U2.70"
				( objectStatus "@baseboard_fab2_lib.baseboard_fab2(sch_1):page82_i171:vdd(21)" )
			)
			( pin "J9U2.67"
				( objectStatus "@baseboard_fab2_lib.baseboard_fab2(sch_1):page82_i171:vdd(22)" )
			)
			( pin "J9U2.64"
				( objectStatus "@baseboard_fab2_lib.baseboard_fab2(sch_1):page82_i171:vdd(23)" )
			)
			( pin "J9U2.61"
				( objectStatus "@baseboard_fab2_lib.baseboard_fab2(sch_1):page82_i171:vdd(24)" )
			)
			( pin "J9U2.59"
				( objectStatus "@baseboard_fab2_lib.baseboard_fab2(sch_1):page82_i171:vdd(25)" )
			)
			( pin "J9U2.287"
				( objectStatus "@baseboard_fab2_lib.baseboard_fab2(sch_1):page82_i171:vpp(0)" )
			)
			( pin "J9U2.286"
				( objectStatus "@baseboard_fab2_lib.baseboard_fab2(sch_1):page82_i171:vpp(1)" )
			)
			( pin "J9U2.288"
				( objectStatus "@baseboard_fab2_lib.baseboard_fab2(sch_1):page82_i171:vpp(2)" )
			)
			( pin "J9U2.143"
				( objectStatus "@baseboard_fab2_lib.baseboard_fab2(sch_1):page82_i171:vpp(3)" )
			)
			( pin "J9U2.142"
				( objectStatus "@baseboard_fab2_lib.baseboard_fab2(sch_1):page82_i171:vpp(4)" )
			)
			( pin "J9U2.221"
				( objectStatus "@baseboard_fab2_lib.baseboard_fab2(sch_1):page82_i171:vtt(0)" )
			)
			( pin "J9U2.77"
				( objectStatus "@baseboard_fab2_lib.baseboard_fab2(sch_1):page82_i171:vtt(1)" )
			)
			( pin "C1G19.1"
				( objectStatus "@baseboard_fab2_lib.baseboard_fab2(sch_1):page82_i180:a" )
			)
			( pin "C1G19.2"
				( objectStatus "@baseboard_fab2_lib.baseboard_fab2(sch_1):page82_i180:b" )
			)
			( pin "J9U2.79"
				( objectStatus "@baseboard_fab2_lib.baseboard_fab2(sch_1):page82_i187:a0" )
			)
			( pin "J9U2.72"
				( objectStatus "@baseboard_fab2_lib.baseboard_fab2(sch_1):page82_i187:a1" )
			)
			( pin "J9U2.216"
				( objectStatus "@baseboard_fab2_lib.baseboard_fab2(sch_1):page82_i187:a2" )
			)
			( pin "J9U2.71"
				( objectStatus "@baseboard_fab2_lib.baseboard_fab2(sch_1):page82_i187:a3" )
			)
			( pin "J9U2.214"
				( objectStatus "@baseboard_fab2_lib.baseboard_fab2(sch_1):page82_i187:a4" )
			)
			( pin "J9U2.213"
				( objectStatus "@baseboard_fab2_lib.baseboard_fab2(sch_1):page82_i187:a5" )
			)
			( pin "J9U2.69"
				( objectStatus "@baseboard_fab2_lib.baseboard_fab2(sch_1):page82_i187:a6" )
			)
			( pin "J9U2.211"
				( objectStatus "@baseboard_fab2_lib.baseboard_fab2(sch_1):page82_i187:a7" )
			)
			( pin "J9U2.68"
				( objectStatus "@baseboard_fab2_lib.baseboard_fab2(sch_1):page82_i187:a8" )
			)
			( pin "J9U2.66"
				( objectStatus "@baseboard_fab2_lib.baseboard_fab2(sch_1):page82_i187:a9" )
			)
			( pin "J9U2.225"
				( objectStatus "@baseboard_fab2_lib.baseboard_fab2(sch_1):page82_i187:a10" )
			)
			( pin "J9U2.210"
				( objectStatus "@baseboard_fab2_lib.baseboard_fab2(sch_1):page82_i187:a11" )
			)
			( pin "J9U2.65"
				( objectStatus "@baseboard_fab2_lib.baseboard_fab2(sch_1):page82_i187:a12" )
			)
			( pin "J9U2.232"
				( objectStatus "@baseboard_fab2_lib.baseboard_fab2(sch_1):page82_i187:a13" )
			)
			( pin "J9U2.228"
				( objectStatus "@baseboard_fab2_lib.baseboard_fab2(sch_1):page82_i187:a14_we_n" )
			)
			( pin "J9U2.86"
				( objectStatus "@baseboard_fab2_lib.baseboard_fab2(sch_1):page82_i187:a15_cas_n" )
			)
			( pin "J9U2.82"
				( objectStatus "@baseboard_fab2_lib.baseboard_fab2(sch_1):page82_i187:a16_ras_n" )
			)
			( pin "J9U2.234"
				( objectStatus "@baseboard_fab2_lib.baseboard_fab2(sch_1):page82_i187:a17" )
			)
			( pin "J9U2.62"
				( objectStatus "@baseboard_fab2_lib.baseboard_fab2(sch_1):page82_i187:act_n" )
			)
			( pin "J9U2.208"
				( objectStatus "@baseboard_fab2_lib.baseboard_fab2(sch_1):page82_i187:alert_n" )
			)
			( pin "J9U2.81"
				( objectStatus "@baseboard_fab2_lib.baseboard_fab2(sch_1):page82_i187:ba(0)" )
			)
			( pin "J9U2.224"
				( objectStatus "@baseboard_fab2_lib.baseboard_fab2(sch_1):page82_i187:ba(1)" )
			)
			( pin "J9U2.63"
				( objectStatus "@baseboard_fab2_lib.baseboard_fab2(sch_1):page82_i187:bg(0)" )
			)
			( pin "J9U2.207"
				( objectStatus "@baseboard_fab2_lib.baseboard_fab2(sch_1):page82_i187:bg(1)" )
			)
			( pin "J9U2.235"
				( objectStatus "@baseboard_fab2_lib.baseboard_fab2(sch_1):page82_i187:c(2)" )
			)
			( pin "J9U2.49"
				( objectStatus "@baseboard_fab2_lib.baseboard_fab2(sch_1):page82_i187:cb(0)" )
			)
			( pin "J9U2.194"
				( objectStatus "@baseboard_fab2_lib.baseboard_fab2(sch_1):page82_i187:cb(1)" )
			)
			( pin "J9U2.56"
				( objectStatus "@baseboard_fab2_lib.baseboard_fab2(sch_1):page82_i187:cb(2)" )
			)
			( pin "J9U2.201"
				( objectStatus "@baseboard_fab2_lib.baseboard_fab2(sch_1):page82_i187:cb(3)" )
			)
			( pin "J9U2.47"
				( objectStatus "@baseboard_fab2_lib.baseboard_fab2(sch_1):page82_i187:cb(4)" )
			)
			( pin "J9U2.192"
				( objectStatus "@baseboard_fab2_lib.baseboard_fab2(sch_1):page82_i187:cb(5)" )
			)
			( pin "J9U2.54"
				( objectStatus "@baseboard_fab2_lib.baseboard_fab2(sch_1):page82_i187:cb(6)" )
			)
			( pin "J9U2.199"
				( objectStatus "@baseboard_fab2_lib.baseboard_fab2(sch_1):page82_i187:cb(7)" )
			)
			( pin "J9U2.75"
				( objectStatus "@baseboard_fab2_lib.baseboard_fab2(sch_1):page82_i187:ck0n" )
			)
			( pin "J9U2.74"
				( objectStatus "@baseboard_fab2_lib.baseboard_fab2(sch_1):page82_i187:ck0p" )
			)
			( pin "J9U2.219"
				( objectStatus "@baseboard_fab2_lib.baseboard_fab2(sch_1):page82_i187:ck1n" )
			)
			( pin "J9U2.218"
				( objectStatus "@baseboard_fab2_lib.baseboard_fab2(sch_1):page82_i187:ck1p" )
			)
			( pin "J9U2.60"
				( objectStatus "@baseboard_fab2_lib.baseboard_fab2(sch_1):page82_i187:cke(0)" )
			)
			( pin "J9U2.203"
				( objectStatus "@baseboard_fab2_lib.baseboard_fab2(sch_1):page82_i187:cke(1)" )
			)
			( pin "J9U2.5"
				( objectStatus "@baseboard_fab2_lib.baseboard_fab2(sch_1):page82_i187:dq(0)" )
			)
			( pin "J9U2.150"
				( objectStatus "@baseboard_fab2_lib.baseboard_fab2(sch_1):page82_i187:dq(1)" )
			)
			( pin "J9U2.12"
				( objectStatus "@baseboard_fab2_lib.baseboard_fab2(sch_1):page82_i187:dq(2)" )
			)
			( pin "J9U2.157"
				( objectStatus "@baseboard_fab2_lib.baseboard_fab2(sch_1):page82_i187:dq(3)" )
			)
			( pin "J9U2.3"
				( objectStatus "@baseboard_fab2_lib.baseboard_fab2(sch_1):page82_i187:dq(4)" )
			)
			( pin "J9U2.148"
				( objectStatus "@baseboard_fab2_lib.baseboard_fab2(sch_1):page82_i187:dq(5)" )
			)
			( pin "J9U2.10"
				( objectStatus "@baseboard_fab2_lib.baseboard_fab2(sch_1):page82_i187:dq(6)" )
			)
			( pin "J9U2.155"
				( objectStatus "@baseboard_fab2_lib.baseboard_fab2(sch_1):page82_i187:dq(7)" )
			)
			( pin "J9U2.16"
				( objectStatus "@baseboard_fab2_lib.baseboard_fab2(sch_1):page82_i187:dq(8)" )
			)
			( pin "J9U2.161"
				( objectStatus "@baseboard_fab2_lib.baseboard_fab2(sch_1):page82_i187:dq(9)" )
			)
			( pin "J9U2.23"
				( objectStatus "@baseboard_fab2_lib.baseboard_fab2(sch_1):page82_i187:dq(10)" )
			)
			( pin "J9U2.168"
				( objectStatus "@baseboard_fab2_lib.baseboard_fab2(sch_1):page82_i187:dq(11)" )
			)
			( pin "J9U2.14"
				( objectStatus "@baseboard_fab2_lib.baseboard_fab2(sch_1):page82_i187:dq(12)" )
			)
			( pin "J9U2.159"
				( objectStatus "@baseboard_fab2_lib.baseboard_fab2(sch_1):page82_i187:dq(13)" )
			)
			( pin "J9U2.21"
				( objectStatus "@baseboard_fab2_lib.baseboard_fab2(sch_1):page82_i187:dq(14)" )
			)
			( pin "J9U2.166"
				( objectStatus "@baseboard_fab2_lib.baseboard_fab2(sch_1):page82_i187:dq(15)" )
			)
			( pin "J9U2.27"
				( objectStatus "@baseboard_fab2_lib.baseboard_fab2(sch_1):page82_i187:dq(16)" )
			)
			( pin "J9U2.172"
				( objectStatus "@baseboard_fab2_lib.baseboard_fab2(sch_1):page82_i187:dq(17)" )
			)
			( pin "J9U2.34"
				( objectStatus "@baseboard_fab2_lib.baseboard_fab2(sch_1):page82_i187:dq(18)" )
			)
			( pin "J9U2.179"
				( objectStatus "@baseboard_fab2_lib.baseboard_fab2(sch_1):page82_i187:dq(19)" )
			)
			( pin "J9U2.25"
				( objectStatus "@baseboard_fab2_lib.baseboard_fab2(sch_1):page82_i187:dq(20)" )
			)
			( pin "J9U2.170"
				( objectStatus "@baseboard_fab2_lib.baseboard_fab2(sch_1):page82_i187:dq(21)" )
			)
			( pin "J9U2.32"
				( objectStatus "@baseboard_fab2_lib.baseboard_fab2(sch_1):page82_i187:dq(22)" )
			)
			( pin "J9U2.177"
				( objectStatus "@baseboard_fab2_lib.baseboard_fab2(sch_1):page82_i187:dq(23)" )
			)
			( pin "J9U2.38"
				( objectStatus "@baseboard_fab2_lib.baseboard_fab2(sch_1):page82_i187:dq(24)" )
			)
			( pin "J9U2.183"
				( objectStatus "@baseboard_fab2_lib.baseboard_fab2(sch_1):page82_i187:dq(25)" )
			)
			( pin "J9U2.45"
				( objectStatus "@baseboard_fab2_lib.baseboard_fab2(sch_1):page82_i187:dq(26)" )
			)
			( pin "J9U2.190"
				( objectStatus "@baseboard_fab2_lib.baseboard_fab2(sch_1):page82_i187:dq(27)" )
			)
			( pin "J9U2.36"
				( objectStatus "@baseboard_fab2_lib.baseboard_fab2(sch_1):page82_i187:dq(28)" )
			)
			( pin "J9U2.181"
				( objectStatus "@baseboard_fab2_lib.baseboard_fab2(sch_1):page82_i187:dq(29)" )
			)
			( pin "J9U2.43"
				( objectStatus "@baseboard_fab2_lib.baseboard_fab2(sch_1):page82_i187:dq(30)" )
			)
			( pin "J9U2.188"
				( objectStatus "@baseboard_fab2_lib.baseboard_fab2(sch_1):page82_i187:dq(31)" )
			)
			( pin "J9U2.97"
				( objectStatus "@baseboard_fab2_lib.baseboard_fab2(sch_1):page82_i187:dq(32)" )
			)
			( pin "J9U2.242"
				( objectStatus "@baseboard_fab2_lib.baseboard_fab2(sch_1):page82_i187:dq(33)" )
			)
			( pin "J9U2.104"
				( objectStatus "@baseboard_fab2_lib.baseboard_fab2(sch_1):page82_i187:dq(34)" )
			)
			( pin "J9U2.249"
				( objectStatus "@baseboard_fab2_lib.baseboard_fab2(sch_1):page82_i187:dq(35)" )
			)
			( pin "J9U2.95"
				( objectStatus "@baseboard_fab2_lib.baseboard_fab2(sch_1):page82_i187:dq(36)" )
			)
			( pin "J9U2.240"
				( objectStatus "@baseboard_fab2_lib.baseboard_fab2(sch_1):page82_i187:dq(37)" )
			)
			( pin "J9U2.102"
				( objectStatus "@baseboard_fab2_lib.baseboard_fab2(sch_1):page82_i187:dq(38)" )
			)
			( pin "J9U2.247"
				( objectStatus "@baseboard_fab2_lib.baseboard_fab2(sch_1):page82_i187:dq(39)" )
			)
			( pin "J9U2.108"
				( objectStatus "@baseboard_fab2_lib.baseboard_fab2(sch_1):page82_i187:dq(40)" )
			)
			( pin "J9U2.253"
				( objectStatus "@baseboard_fab2_lib.baseboard_fab2(sch_1):page82_i187:dq(41)" )
			)
			( pin "J9U2.115"
				( objectStatus "@baseboard_fab2_lib.baseboard_fab2(sch_1):page82_i187:dq(42)" )
			)
			( pin "J9U2.260"
				( objectStatus "@baseboard_fab2_lib.baseboard_fab2(sch_1):page82_i187:dq(43)" )
			)
			( pin "J9U2.106"
				( objectStatus "@baseboard_fab2_lib.baseboard_fab2(sch_1):page82_i187:dq(44)" )
			)
			( pin "J9U2.251"
				( objectStatus "@baseboard_fab2_lib.baseboard_fab2(sch_1):page82_i187:dq(45)" )
			)
			( pin "J9U2.113"
				( objectStatus "@baseboard_fab2_lib.baseboard_fab2(sch_1):page82_i187:dq(46)" )
			)
			( pin "J9U2.258"
				( objectStatus "@baseboard_fab2_lib.baseboard_fab2(sch_1):page82_i187:dq(47)" )
			)
			( pin "J9U2.119"
				( objectStatus "@baseboard_fab2_lib.baseboard_fab2(sch_1):page82_i187:dq(48)" )
			)
			( pin "J9U2.264"
				( objectStatus "@baseboard_fab2_lib.baseboard_fab2(sch_1):page82_i187:dq(49)" )
			)
			( pin "J9U2.126"
				( objectStatus "@baseboard_fab2_lib.baseboard_fab2(sch_1):page82_i187:dq(50)" )
			)
			( pin "J9U2.271"
				( objectStatus "@baseboard_fab2_lib.baseboard_fab2(sch_1):page82_i187:dq(51)" )
			)
			( pin "J9U2.117"
				( objectStatus "@baseboard_fab2_lib.baseboard_fab2(sch_1):page82_i187:dq(52)" )
			)
			( pin "J9U2.262"
				( objectStatus "@baseboard_fab2_lib.baseboard_fab2(sch_1):page82_i187:dq(53)" )
			)
			( pin "J9U2.124"
				( objectStatus "@baseboard_fab2_lib.baseboard_fab2(sch_1):page82_i187:dq(54)" )
			)
			( pin "J9U2.269"
				( objectStatus "@baseboard_fab2_lib.baseboard_fab2(sch_1):page82_i187:dq(55)" )
			)
			( pin "J9U2.130"
				( objectStatus "@baseboard_fab2_lib.baseboard_fab2(sch_1):page82_i187:dq(56)" )
			)
			( pin "J9U2.275"
				( objectStatus "@baseboard_fab2_lib.baseboard_fab2(sch_1):page82_i187:dq(57)" )
			)
			( pin "J9U2.137"
				( objectStatus "@baseboard_fab2_lib.baseboard_fab2(sch_1):page82_i187:dq(58)" )
			)
			( pin "J9U2.282"
				( objectStatus "@baseboard_fab2_lib.baseboard_fab2(sch_1):page82_i187:dq(59)" )
			)
			( pin "J9U2.128"
				( objectStatus "@baseboard_fab2_lib.baseboard_fab2(sch_1):page82_i187:dq(60)" )
			)
			( pin "J9U2.273"
				( objectStatus "@baseboard_fab2_lib.baseboard_fab2(sch_1):page82_i187:dq(61)" )
			)
			( pin "J9U2.135"
				( objectStatus "@baseboard_fab2_lib.baseboard_fab2(sch_1):page82_i187:dq(62)" )
			)
			( pin "J9U2.280"
				( objectStatus "@baseboard_fab2_lib.baseboard_fab2(sch_1):page82_i187:dq(63)" )
			)
			( pin "J9U2.78"
				( objectStatus "@baseboard_fab2_lib.baseboard_fab2(sch_1):page82_i187:event_n" )
			)
			( pin "J9U2.87"
				( objectStatus "@baseboard_fab2_lib.baseboard_fab2(sch_1):page82_i187:odt(0)" )
			)
			( pin "J9U2.91"
				( objectStatus "@baseboard_fab2_lib.baseboard_fab2(sch_1):page82_i187:odt(1)" )
			)
			( pin "J9U2.222"
				( objectStatus "@baseboard_fab2_lib.baseboard_fab2(sch_1):page82_i187:par" )
			)
			( pin "J9U2.58"
				( objectStatus "@baseboard_fab2_lib.baseboard_fab2(sch_1):page82_i187:reset_n" )
			)
			( pin "J9U2.205"
				( objectStatus "@baseboard_fab2_lib.baseboard_fab2(sch_1):page82_i187:rfu(0)" )
			)
			( pin "J9U2.227"
				( objectStatus "@baseboard_fab2_lib.baseboard_fab2(sch_1):page82_i187:rfu(1)" )
			)
			( pin "J9U2.144"
				( objectStatus "@baseboard_fab2_lib.baseboard_fab2(sch_1):page82_i187:rfu(2)" )
			)
			( pin "J9U2.84"
				( objectStatus "@baseboard_fab2_lib.baseboard_fab2(sch_1):page82_i187:s0_n" )
			)
			( pin "J9U2.89"
				( objectStatus "@baseboard_fab2_lib.baseboard_fab2(sch_1):page82_i187:s1_n" )
			)
			( pin "J9U2.93"
				( objectStatus "@baseboard_fab2_lib.baseboard_fab2(sch_1):page82_i187:s2_n_c(0)" )
			)
			( pin "J9U2.237"
				( objectStatus "@baseboard_fab2_lib.baseboard_fab2(sch_1):page82_i187:s3_n_c(1)" )
			)
			( pin "J9U2.139"
				( objectStatus "@baseboard_fab2_lib.baseboard_fab2(sch_1):page82_i187:sa(0)" )
			)
			( pin "J9U2.140"
				( objectStatus "@baseboard_fab2_lib.baseboard_fab2(sch_1):page82_i187:sa(1)" )
			)
			( pin "J9U2.238"
				( objectStatus "@baseboard_fab2_lib.baseboard_fab2(sch_1):page82_i187:sa(2)" )
			)
			( pin "J9U2.230"
				( objectStatus "@baseboard_fab2_lib.baseboard_fab2(sch_1):page82_i187:save_n_nc" )
			)
			( pin "J9U2.141"
				( objectStatus "@baseboard_fab2_lib.baseboard_fab2(sch_1):page82_i187:scl" )
			)
			( pin "J9U2.285"
				( objectStatus "@baseboard_fab2_lib.baseboard_fab2(sch_1):page82_i187:sda" )
			)
			( pin "J9U2.284"
				( objectStatus "@baseboard_fab2_lib.baseboard_fab2(sch_1):page82_i187:vddspd" )
			)
			( pin "J9U2.146"
				( objectStatus "@baseboard_fab2_lib.baseboard_fab2(sch_1):page82_i187:vrefca" )
			)
			( pin "J9U2.283"
				( objectStatus "@baseboard_fab2_lib.baseboard_fab2(sch_1):page82_i188:vss(0)" )
			)
			( pin "J9U2.281"
				( objectStatus "@baseboard_fab2_lib.baseboard_fab2(sch_1):page82_i188:vss(1)" )
			)
			( pin "J9U2.279"
				( objectStatus "@baseboard_fab2_lib.baseboard_fab2(sch_1):page82_i188:vss(2)" )
			)
			( pin "J9U2.276"
				( objectStatus "@baseboard_fab2_lib.baseboard_fab2(sch_1):page82_i188:vss(3)" )
			)
			( pin "J9U2.274"
				( objectStatus "@baseboard_fab2_lib.baseboard_fab2(sch_1):page82_i188:vss(4)" )
			)
			( pin "J9U2.272"
				( objectStatus "@baseboard_fab2_lib.baseboard_fab2(sch_1):page82_i188:vss(5)" )
			)
			( pin "J9U2.270"
				( objectStatus "@baseboard_fab2_lib.baseboard_fab2(sch_1):page82_i188:vss(6)" )
			)
			( pin "J9U2.268"
				( objectStatus "@baseboard_fab2_lib.baseboard_fab2(sch_1):page82_i188:vss(7)" )
			)
			( pin "J9U2.265"
				( objectStatus "@baseboard_fab2_lib.baseboard_fab2(sch_1):page82_i188:vss(8)" )
			)
			( pin "J9U2.263"
				( objectStatus "@baseboard_fab2_lib.baseboard_fab2(sch_1):page82_i188:vss(9)" )
			)
			( pin "J9U2.261"
				( objectStatus "@baseboard_fab2_lib.baseboard_fab2(sch_1):page82_i188:vss(10)" )
			)
			( pin "J9U2.259"
				( objectStatus "@baseboard_fab2_lib.baseboard_fab2(sch_1):page82_i188:vss(11)" )
			)
			( pin "J9U2.257"
				( objectStatus "@baseboard_fab2_lib.baseboard_fab2(sch_1):page82_i188:vss(12)" )
			)
			( pin "J9U2.254"
				( objectStatus "@baseboard_fab2_lib.baseboard_fab2(sch_1):page82_i188:vss(13)" )
			)
			( pin "J9U2.252"
				( objectStatus "@baseboard_fab2_lib.baseboard_fab2(sch_1):page82_i188:vss(14)" )
			)
			( pin "J9U2.250"
				( objectStatus "@baseboard_fab2_lib.baseboard_fab2(sch_1):page82_i188:vss(15)" )
			)
			( pin "J9U2.248"
				( objectStatus "@baseboard_fab2_lib.baseboard_fab2(sch_1):page82_i188:vss(16)" )
			)
			( pin "J9U2.246"
				( objectStatus "@baseboard_fab2_lib.baseboard_fab2(sch_1):page82_i188:vss(17)" )
			)
			( pin "J9U2.243"
				( objectStatus "@baseboard_fab2_lib.baseboard_fab2(sch_1):page82_i188:vss(18)" )
			)
			( pin "J9U2.241"
				( objectStatus "@baseboard_fab2_lib.baseboard_fab2(sch_1):page82_i188:vss(19)" )
			)
			( pin "J9U2.239"
				( objectStatus "@baseboard_fab2_lib.baseboard_fab2(sch_1):page82_i188:vss(20)" )
			)
			( pin "J9U2.202"
				( objectStatus "@baseboard_fab2_lib.baseboard_fab2(sch_1):page82_i188:vss(21)" )
			)
			( pin "J9U2.200"
				( objectStatus "@baseboard_fab2_lib.baseboard_fab2(sch_1):page82_i188:vss(22)" )
			)
			( pin "J9U2.198"
				( objectStatus "@baseboard_fab2_lib.baseboard_fab2(sch_1):page82_i188:vss(23)" )
			)
			( pin "J9U2.195"
				( objectStatus "@baseboard_fab2_lib.baseboard_fab2(sch_1):page82_i188:vss(24)" )
			)
			( pin "J9U2.193"
				( objectStatus "@baseboard_fab2_lib.baseboard_fab2(sch_1):page82_i188:vss(25)" )
			)
			( pin "J9U2.191"
				( objectStatus "@baseboard_fab2_lib.baseboard_fab2(sch_1):page82_i188:vss(26)" )
			)
			( pin "J9U2.189"
				( objectStatus "@baseboard_fab2_lib.baseboard_fab2(sch_1):page82_i188:vss(27)" )
			)
			( pin "J9U2.187"
				( objectStatus "@baseboard_fab2_lib.baseboard_fab2(sch_1):page82_i188:vss(28)" )
			)
			( pin "J9U2.184"
				( objectStatus "@baseboard_fab2_lib.baseboard_fab2(sch_1):page82_i188:vss(29)" )
			)
			( pin "J9U2.182"
				( objectStatus "@baseboard_fab2_lib.baseboard_fab2(sch_1):page82_i188:vss(30)" )
			)
			( pin "J9U2.180"
				( objectStatus "@baseboard_fab2_lib.baseboard_fab2(sch_1):page82_i188:vss(31)" )
			)
			( pin "J9U2.178"
				( objectStatus "@baseboard_fab2_lib.baseboard_fab2(sch_1):page82_i188:vss(32)" )
			)
			( pin "J9U2.176"
				( objectStatus "@baseboard_fab2_lib.baseboard_fab2(sch_1):page82_i188:vss(33)" )
			)
			( pin "J9U2.173"
				( objectStatus "@baseboard_fab2_lib.baseboard_fab2(sch_1):page82_i188:vss(34)" )
			)
			( pin "J9U2.171"
				( objectStatus "@baseboard_fab2_lib.baseboard_fab2(sch_1):page82_i188:vss(35)" )
			)
			( pin "J9U2.169"
				( objectStatus "@baseboard_fab2_lib.baseboard_fab2(sch_1):page82_i188:vss(36)" )
			)
			( pin "J9U2.167"
				( objectStatus "@baseboard_fab2_lib.baseboard_fab2(sch_1):page82_i188:vss(37)" )
			)
			( pin "J9U2.165"
				( objectStatus "@baseboard_fab2_lib.baseboard_fab2(sch_1):page82_i188:vss(38)" )
			)
			( pin "J9U2.162"
				( objectStatus "@baseboard_fab2_lib.baseboard_fab2(sch_1):page82_i188:vss(39)" )
			)
			( pin "J9U2.160"
				( objectStatus "@baseboard_fab2_lib.baseboard_fab2(sch_1):page82_i188:vss(40)" )
			)
			( pin "J9U2.158"
				( objectStatus "@baseboard_fab2_lib.baseboard_fab2(sch_1):page82_i188:vss(41)" )
			)
			( pin "J9U2.156"
				( objectStatus "@baseboard_fab2_lib.baseboard_fab2(sch_1):page82_i188:vss(42)" )
			)
			( pin "J9U2.154"
				( objectStatus "@baseboard_fab2_lib.baseboard_fab2(sch_1):page82_i188:vss(43)" )
			)
			( pin "J9U2.151"
				( objectStatus "@baseboard_fab2_lib.baseboard_fab2(sch_1):page82_i188:vss(44)" )
			)
			( pin "J9U2.149"
				( objectStatus "@baseboard_fab2_lib.baseboard_fab2(sch_1):page82_i188:vss(45)" )
			)
			( pin "J9U2.147"
				( objectStatus "@baseboard_fab2_lib.baseboard_fab2(sch_1):page82_i188:vss(46)" )
			)
			( pin "J9U2.138"
				( objectStatus "@baseboard_fab2_lib.baseboard_fab2(sch_1):page82_i188:vss(47)" )
			)
			( pin "J9U2.136"
				( objectStatus "@baseboard_fab2_lib.baseboard_fab2(sch_1):page82_i188:vss(48)" )
			)
			( pin "J9U2.134"
				( objectStatus "@baseboard_fab2_lib.baseboard_fab2(sch_1):page82_i188:vss(49)" )
			)
			( pin "J9U2.131"
				( objectStatus "@baseboard_fab2_lib.baseboard_fab2(sch_1):page82_i188:vss(50)" )
			)
			( pin "J9U2.129"
				( objectStatus "@baseboard_fab2_lib.baseboard_fab2(sch_1):page82_i188:vss(51)" )
			)
			( pin "J9U2.127"
				( objectStatus "@baseboard_fab2_lib.baseboard_fab2(sch_1):page82_i188:vss(52)" )
			)
			( pin "J9U2.125"
				( objectStatus "@baseboard_fab2_lib.baseboard_fab2(sch_1):page82_i188:vss(53)" )
			)
			( pin "J9U2.123"
				( objectStatus "@baseboard_fab2_lib.baseboard_fab2(sch_1):page82_i188:vss(54)" )
			)
			( pin "J9U2.120"
				( objectStatus "@baseboard_fab2_lib.baseboard_fab2(sch_1):page82_i188:vss(55)" )
			)
			( pin "J9U2.118"
				( objectStatus "@baseboard_fab2_lib.baseboard_fab2(sch_1):page82_i188:vss(56)" )
			)
			( pin "J9U2.116"
				( objectStatus "@baseboard_fab2_lib.baseboard_fab2(sch_1):page82_i188:vss(57)" )
			)
			( pin "J9U2.114"
				( objectStatus "@baseboard_fab2_lib.baseboard_fab2(sch_1):page82_i188:vss(58)" )
			)
			( pin "J9U2.112"
				( objectStatus "@baseboard_fab2_lib.baseboard_fab2(sch_1):page82_i188:vss(59)" )
			)
			( pin "J9U2.109"
				( objectStatus "@baseboard_fab2_lib.baseboard_fab2(sch_1):page82_i188:vss(60)" )
			)
			( pin "J9U2.107"
				( objectStatus "@baseboard_fab2_lib.baseboard_fab2(sch_1):page82_i188:vss(61)" )
			)
			( pin "J9U2.105"
				( objectStatus "@baseboard_fab2_lib.baseboard_fab2(sch_1):page82_i188:vss(62)" )
			)
			( pin "J9U2.103"
				( objectStatus "@baseboard_fab2_lib.baseboard_fab2(sch_1):page82_i188:vss(63)" )
			)
			( pin "J9U2.101"
				( objectStatus "@baseboard_fab2_lib.baseboard_fab2(sch_1):page82_i188:vss(64)" )
			)
			( pin "J9U2.98"
				( objectStatus "@baseboard_fab2_lib.baseboard_fab2(sch_1):page82_i188:vss(65)" )
			)
			( pin "J9U2.96"
				( objectStatus "@baseboard_fab2_lib.baseboard_fab2(sch_1):page82_i188:vss(66)" )
			)
			( pin "J9U2.94"
				( objectStatus "@baseboard_fab2_lib.baseboard_fab2(sch_1):page82_i188:vss(67)" )
			)
			( pin "J9U2.57"
				( objectStatus "@baseboard_fab2_lib.baseboard_fab2(sch_1):page82_i188:vss(68)" )
			)
			( pin "J9U2.55"
				( objectStatus "@baseboard_fab2_lib.baseboard_fab2(sch_1):page82_i188:vss(69)" )
			)
			( pin "J9U2.53"
				( objectStatus "@baseboard_fab2_lib.baseboard_fab2(sch_1):page82_i188:vss(70)" )
			)
			( pin "J9U2.50"
				( objectStatus "@baseboard_fab2_lib.baseboard_fab2(sch_1):page82_i188:vss(71)" )
			)
			( pin "J9U2.48"
				( objectStatus "@baseboard_fab2_lib.baseboard_fab2(sch_1):page82_i188:vss(72)" )
			)
			( pin "J9U2.46"
				( objectStatus "@baseboard_fab2_lib.baseboard_fab2(sch_1):page82_i188:vss(73)" )
			)
			( pin "J9U2.44"
				( objectStatus "@baseboard_fab2_lib.baseboard_fab2(sch_1):page82_i188:vss(74)" )
			)
			( pin "J9U2.42"
				( objectStatus "@baseboard_fab2_lib.baseboard_fab2(sch_1):page82_i188:vss(75)" )
			)
			( pin "J9U2.39"
				( objectStatus "@baseboard_fab2_lib.baseboard_fab2(sch_1):page82_i188:vss(76)" )
			)
			( pin "J9U2.37"
				( objectStatus "@baseboard_fab2_lib.baseboard_fab2(sch_1):page82_i188:vss(77)" )
			)
			( pin "J9U2.35"
				( objectStatus "@baseboard_fab2_lib.baseboard_fab2(sch_1):page82_i188:vss(78)" )
			)
			( pin "J9U2.33"
				( objectStatus "@baseboard_fab2_lib.baseboard_fab2(sch_1):page82_i188:vss(79)" )
			)
			( pin "J9U2.31"
				( objectStatus "@baseboard_fab2_lib.baseboard_fab2(sch_1):page82_i188:vss(80)" )
			)
			( pin "J9U2.28"
				( objectStatus "@baseboard_fab2_lib.baseboard_fab2(sch_1):page82_i188:vss(81)" )
			)
			( pin "J9U2.26"
				( objectStatus "@baseboard_fab2_lib.baseboard_fab2(sch_1):page82_i188:vss(82)" )
			)
			( pin "J9U2.24"
				( objectStatus "@baseboard_fab2_lib.baseboard_fab2(sch_1):page82_i188:vss(83)" )
			)
			( pin "J9U2.22"
				( objectStatus "@baseboard_fab2_lib.baseboard_fab2(sch_1):page82_i188:vss(84)" )
			)
			( pin "J9U2.20"
				( objectStatus "@baseboard_fab2_lib.baseboard_fab2(sch_1):page82_i188:vss(85)" )
			)
			( pin "J9U2.17"
				( objectStatus "@baseboard_fab2_lib.baseboard_fab2(sch_1):page82_i188:vss(86)" )
			)
			( pin "J9U2.15"
				( objectStatus "@baseboard_fab2_lib.baseboard_fab2(sch_1):page82_i188:vss(87)" )
			)
			( pin "J9U2.13"
				( objectStatus "@baseboard_fab2_lib.baseboard_fab2(sch_1):page82_i188:vss(88)" )
			)
			( pin "J9U2.11"
				( objectStatus "@baseboard_fab2_lib.baseboard_fab2(sch_1):page82_i188:vss(89)" )
			)
			( pin "J9U2.9"
				( objectStatus "@baseboard_fab2_lib.baseboard_fab2(sch_1):page82_i188:vss(90)" )
			)
			( pin "J9U2.6"
				( objectStatus "@baseboard_fab2_lib.baseboard_fab2(sch_1):page82_i188:vss(91)" )
			)
			( pin "J9U2.4"
				( objectStatus "@baseboard_fab2_lib.baseboard_fab2(sch_1):page82_i188:vss(92)" )
			)
			( pin "J9U2.2"
				( objectStatus "@baseboard_fab2_lib.baseboard_fab2(sch_1):page82_i188:vss(93)" )
			)
			( pin "J1B1.283"
				( objectStatus "@baseboard_fab2_lib.baseboard_fab2(sch_1):page83_i43:vss(0)" )
			)
			( pin "J1B1.281"
				( objectStatus "@baseboard_fab2_lib.baseboard_fab2(sch_1):page83_i43:vss(1)" )
			)
			( pin "J1B1.279"
				( objectStatus "@baseboard_fab2_lib.baseboard_fab2(sch_1):page83_i43:vss(2)" )
			)
			( pin "J1B1.276"
				( objectStatus "@baseboard_fab2_lib.baseboard_fab2(sch_1):page83_i43:vss(3)" )
			)
			( pin "J1B1.274"
				( objectStatus "@baseboard_fab2_lib.baseboard_fab2(sch_1):page83_i43:vss(4)" )
			)
			( pin "J1B1.272"
				( objectStatus "@baseboard_fab2_lib.baseboard_fab2(sch_1):page83_i43:vss(5)" )
			)
			( pin "J1B1.270"
				( objectStatus "@baseboard_fab2_lib.baseboard_fab2(sch_1):page83_i43:vss(6)" )
			)
			( pin "J1B1.268"
				( objectStatus "@baseboard_fab2_lib.baseboard_fab2(sch_1):page83_i43:vss(7)" )
			)
			( pin "J1B1.265"
				( objectStatus "@baseboard_fab2_lib.baseboard_fab2(sch_1):page83_i43:vss(8)" )
			)
			( pin "J1B1.263"
				( objectStatus "@baseboard_fab2_lib.baseboard_fab2(sch_1):page83_i43:vss(9)" )
			)
			( pin "J1B1.261"
				( objectStatus "@baseboard_fab2_lib.baseboard_fab2(sch_1):page83_i43:vss(10)" )
			)
			( pin "J1B1.259"
				( objectStatus "@baseboard_fab2_lib.baseboard_fab2(sch_1):page83_i43:vss(11)" )
			)
			( pin "J1B1.257"
				( objectStatus "@baseboard_fab2_lib.baseboard_fab2(sch_1):page83_i43:vss(12)" )
			)
			( pin "J1B1.254"
				( objectStatus "@baseboard_fab2_lib.baseboard_fab2(sch_1):page83_i43:vss(13)" )
			)
			( pin "J1B1.252"
				( objectStatus "@baseboard_fab2_lib.baseboard_fab2(sch_1):page83_i43:vss(14)" )
			)
			( pin "J1B1.250"
				( objectStatus "@baseboard_fab2_lib.baseboard_fab2(sch_1):page83_i43:vss(15)" )
			)
			( pin "J1B1.248"
				( objectStatus "@baseboard_fab2_lib.baseboard_fab2(sch_1):page83_i43:vss(16)" )
			)
			( pin "J1B1.246"
				( objectStatus "@baseboard_fab2_lib.baseboard_fab2(sch_1):page83_i43:vss(17)" )
			)
			( pin "J1B1.243"
				( objectStatus "@baseboard_fab2_lib.baseboard_fab2(sch_1):page83_i43:vss(18)" )
			)
			( pin "J1B1.241"
				( objectStatus "@baseboard_fab2_lib.baseboard_fab2(sch_1):page83_i43:vss(19)" )
			)
			( pin "J1B1.239"
				( objectStatus "@baseboard_fab2_lib.baseboard_fab2(sch_1):page83_i43:vss(20)" )
			)
			( pin "J1B1.202"
				( objectStatus "@baseboard_fab2_lib.baseboard_fab2(sch_1):page83_i43:vss(21)" )
			)
			( pin "J1B1.200"
				( objectStatus "@baseboard_fab2_lib.baseboard_fab2(sch_1):page83_i43:vss(22)" )
			)
			( pin "J1B1.198"
				( objectStatus "@baseboard_fab2_lib.baseboard_fab2(sch_1):page83_i43:vss(23)" )
			)
			( pin "J1B1.195"
				( objectStatus "@baseboard_fab2_lib.baseboard_fab2(sch_1):page83_i43:vss(24)" )
			)
			( pin "J1B1.193"
				( objectStatus "@baseboard_fab2_lib.baseboard_fab2(sch_1):page83_i43:vss(25)" )
			)
			( pin "J1B1.191"
				( objectStatus "@baseboard_fab2_lib.baseboard_fab2(sch_1):page83_i43:vss(26)" )
			)
			( pin "J1B1.189"
				( objectStatus "@baseboard_fab2_lib.baseboard_fab2(sch_1):page83_i43:vss(27)" )
			)
			( pin "J1B1.187"
				( objectStatus "@baseboard_fab2_lib.baseboard_fab2(sch_1):page83_i43:vss(28)" )
			)
			( pin "J1B1.184"
				( objectStatus "@baseboard_fab2_lib.baseboard_fab2(sch_1):page83_i43:vss(29)" )
			)
			( pin "J1B1.182"
				( objectStatus "@baseboard_fab2_lib.baseboard_fab2(sch_1):page83_i43:vss(30)" )
			)
			( pin "J1B1.180"
				( objectStatus "@baseboard_fab2_lib.baseboard_fab2(sch_1):page83_i43:vss(31)" )
			)
			( pin "J1B1.178"
				( objectStatus "@baseboard_fab2_lib.baseboard_fab2(sch_1):page83_i43:vss(32)" )
			)
			( pin "J1B1.176"
				( objectStatus "@baseboard_fab2_lib.baseboard_fab2(sch_1):page83_i43:vss(33)" )
			)
			( pin "J1B1.173"
				( objectStatus "@baseboard_fab2_lib.baseboard_fab2(sch_1):page83_i43:vss(34)" )
			)
			( pin "J1B1.171"
				( objectStatus "@baseboard_fab2_lib.baseboard_fab2(sch_1):page83_i43:vss(35)" )
			)
			( pin "J1B1.169"
				( objectStatus "@baseboard_fab2_lib.baseboard_fab2(sch_1):page83_i43:vss(36)" )
			)
			( pin "J1B1.167"
				( objectStatus "@baseboard_fab2_lib.baseboard_fab2(sch_1):page83_i43:vss(37)" )
			)
			( pin "J1B1.165"
				( objectStatus "@baseboard_fab2_lib.baseboard_fab2(sch_1):page83_i43:vss(38)" )
			)
			( pin "J1B1.162"
				( objectStatus "@baseboard_fab2_lib.baseboard_fab2(sch_1):page83_i43:vss(39)" )
			)
			( pin "J1B1.160"
				( objectStatus "@baseboard_fab2_lib.baseboard_fab2(sch_1):page83_i43:vss(40)" )
			)
			( pin "J1B1.158"
				( objectStatus "@baseboard_fab2_lib.baseboard_fab2(sch_1):page83_i43:vss(41)" )
			)
			( pin "J1B1.156"
				( objectStatus "@baseboard_fab2_lib.baseboard_fab2(sch_1):page83_i43:vss(42)" )
			)
			( pin "J1B1.154"
				( objectStatus "@baseboard_fab2_lib.baseboard_fab2(sch_1):page83_i43:vss(43)" )
			)
			( pin "J1B1.151"
				( objectStatus "@baseboard_fab2_lib.baseboard_fab2(sch_1):page83_i43:vss(44)" )
			)
			( pin "J1B1.149"
				( objectStatus "@baseboard_fab2_lib.baseboard_fab2(sch_1):page83_i43:vss(45)" )
			)
			( pin "J1B1.147"
				( objectStatus "@baseboard_fab2_lib.baseboard_fab2(sch_1):page83_i43:vss(46)" )
			)
			( pin "J1B1.138"
				( objectStatus "@baseboard_fab2_lib.baseboard_fab2(sch_1):page83_i43:vss(47)" )
			)
			( pin "J1B1.136"
				( objectStatus "@baseboard_fab2_lib.baseboard_fab2(sch_1):page83_i43:vss(48)" )
			)
			( pin "J1B1.134"
				( objectStatus "@baseboard_fab2_lib.baseboard_fab2(sch_1):page83_i43:vss(49)" )
			)
			( pin "J1B1.131"
				( objectStatus "@baseboard_fab2_lib.baseboard_fab2(sch_1):page83_i43:vss(50)" )
			)
			( pin "J1B1.129"
				( objectStatus "@baseboard_fab2_lib.baseboard_fab2(sch_1):page83_i43:vss(51)" )
			)
			( pin "J1B1.127"
				( objectStatus "@baseboard_fab2_lib.baseboard_fab2(sch_1):page83_i43:vss(52)" )
			)
			( pin "J1B1.125"
				( objectStatus "@baseboard_fab2_lib.baseboard_fab2(sch_1):page83_i43:vss(53)" )
			)
			( pin "J1B1.123"
				( objectStatus "@baseboard_fab2_lib.baseboard_fab2(sch_1):page83_i43:vss(54)" )
			)
			( pin "J1B1.120"
				( objectStatus "@baseboard_fab2_lib.baseboard_fab2(sch_1):page83_i43:vss(55)" )
			)
			( pin "J1B1.118"
				( objectStatus "@baseboard_fab2_lib.baseboard_fab2(sch_1):page83_i43:vss(56)" )
			)
			( pin "J1B1.116"
				( objectStatus "@baseboard_fab2_lib.baseboard_fab2(sch_1):page83_i43:vss(57)" )
			)
			( pin "J1B1.114"
				( objectStatus "@baseboard_fab2_lib.baseboard_fab2(sch_1):page83_i43:vss(58)" )
			)
			( pin "J1B1.112"
				( objectStatus "@baseboard_fab2_lib.baseboard_fab2(sch_1):page83_i43:vss(59)" )
			)
			( pin "J1B1.109"
				( objectStatus "@baseboard_fab2_lib.baseboard_fab2(sch_1):page83_i43:vss(60)" )
			)
			( pin "J1B1.107"
				( objectStatus "@baseboard_fab2_lib.baseboard_fab2(sch_1):page83_i43:vss(61)" )
			)
			( pin "J1B1.105"
				( objectStatus "@baseboard_fab2_lib.baseboard_fab2(sch_1):page83_i43:vss(62)" )
			)
			( pin "J1B1.103"
				( objectStatus "@baseboard_fab2_lib.baseboard_fab2(sch_1):page83_i43:vss(63)" )
			)
			( pin "J1B1.101"
				( objectStatus "@baseboard_fab2_lib.baseboard_fab2(sch_1):page83_i43:vss(64)" )
			)
			( pin "J1B1.98"
				( objectStatus "@baseboard_fab2_lib.baseboard_fab2(sch_1):page83_i43:vss(65)" )
			)
			( pin "J1B1.96"
				( objectStatus "@baseboard_fab2_lib.baseboard_fab2(sch_1):page83_i43:vss(66)" )
			)
			( pin "J1B1.94"
				( objectStatus "@baseboard_fab2_lib.baseboard_fab2(sch_1):page83_i43:vss(67)" )
			)
			( pin "J1B1.57"
				( objectStatus "@baseboard_fab2_lib.baseboard_fab2(sch_1):page83_i43:vss(68)" )
			)
			( pin "J1B1.55"
				( objectStatus "@baseboard_fab2_lib.baseboard_fab2(sch_1):page83_i43:vss(69)" )
			)
			( pin "J1B1.53"
				( objectStatus "@baseboard_fab2_lib.baseboard_fab2(sch_1):page83_i43:vss(70)" )
			)
			( pin "J1B1.50"
				( objectStatus "@baseboard_fab2_lib.baseboard_fab2(sch_1):page83_i43:vss(71)" )
			)
			( pin "J1B1.48"
				( objectStatus "@baseboard_fab2_lib.baseboard_fab2(sch_1):page83_i43:vss(72)" )
			)
			( pin "J1B1.46"
				( objectStatus "@baseboard_fab2_lib.baseboard_fab2(sch_1):page83_i43:vss(73)" )
			)
			( pin "J1B1.44"
				( objectStatus "@baseboard_fab2_lib.baseboard_fab2(sch_1):page83_i43:vss(74)" )
			)
			( pin "J1B1.42"
				( objectStatus "@baseboard_fab2_lib.baseboard_fab2(sch_1):page83_i43:vss(75)" )
			)
			( pin "J1B1.39"
				( objectStatus "@baseboard_fab2_lib.baseboard_fab2(sch_1):page83_i43:vss(76)" )
			)
			( pin "J1B1.37"
				( objectStatus "@baseboard_fab2_lib.baseboard_fab2(sch_1):page83_i43:vss(77)" )
			)
			( pin "J1B1.35"
				( objectStatus "@baseboard_fab2_lib.baseboard_fab2(sch_1):page83_i43:vss(78)" )
			)
			( pin "J1B1.33"
				( objectStatus "@baseboard_fab2_lib.baseboard_fab2(sch_1):page83_i43:vss(79)" )
			)
			( pin "J1B1.31"
				( objectStatus "@baseboard_fab2_lib.baseboard_fab2(sch_1):page83_i43:vss(80)" )
			)
			( pin "J1B1.28"
				( objectStatus "@baseboard_fab2_lib.baseboard_fab2(sch_1):page83_i43:vss(81)" )
			)
			( pin "J1B1.26"
				( objectStatus "@baseboard_fab2_lib.baseboard_fab2(sch_1):page83_i43:vss(82)" )
			)
			( pin "J1B1.24"
				( objectStatus "@baseboard_fab2_lib.baseboard_fab2(sch_1):page83_i43:vss(83)" )
			)
			( pin "J1B1.22"
				( objectStatus "@baseboard_fab2_lib.baseboard_fab2(sch_1):page83_i43:vss(84)" )
			)
			( pin "J1B1.20"
				( objectStatus "@baseboard_fab2_lib.baseboard_fab2(sch_1):page83_i43:vss(85)" )
			)
			( pin "J1B1.17"
				( objectStatus "@baseboard_fab2_lib.baseboard_fab2(sch_1):page83_i43:vss(86)" )
			)
			( pin "J1B1.15"
				( objectStatus "@baseboard_fab2_lib.baseboard_fab2(sch_1):page83_i43:vss(87)" )
			)
			( pin "J1B1.13"
				( objectStatus "@baseboard_fab2_lib.baseboard_fab2(sch_1):page83_i43:vss(88)" )
			)
			( pin "J1B1.11"
				( objectStatus "@baseboard_fab2_lib.baseboard_fab2(sch_1):page83_i43:vss(89)" )
			)
			( pin "J1B1.9"
				( objectStatus "@baseboard_fab2_lib.baseboard_fab2(sch_1):page83_i43:vss(90)" )
			)
			( pin "J1B1.6"
				( objectStatus "@baseboard_fab2_lib.baseboard_fab2(sch_1):page83_i43:vss(91)" )
			)
			( pin "J1B1.4"
				( objectStatus "@baseboard_fab2_lib.baseboard_fab2(sch_1):page83_i43:vss(92)" )
			)
			( pin "J1B1.2"
				( objectStatus "@baseboard_fab2_lib.baseboard_fab2(sch_1):page83_i43:vss(93)" )
			)
			( pin "J1B1.152"
				( objectStatus "@baseboard_fab2_lib.baseboard_fab2(sch_1):page83_i66:dqs0n" )
			)
			( pin "J1B1.153"
				( objectStatus "@baseboard_fab2_lib.baseboard_fab2(sch_1):page83_i66:dqs0p" )
			)
			( pin "J1B1.163"
				( objectStatus "@baseboard_fab2_lib.baseboard_fab2(sch_1):page83_i66:dqs1n" )
			)
			( pin "J1B1.164"
				( objectStatus "@baseboard_fab2_lib.baseboard_fab2(sch_1):page83_i66:dqs1p" )
			)
			( pin "J1B1.174"
				( objectStatus "@baseboard_fab2_lib.baseboard_fab2(sch_1):page83_i66:dqs2n" )
			)
			( pin "J1B1.175"
				( objectStatus "@baseboard_fab2_lib.baseboard_fab2(sch_1):page83_i66:dqs2p" )
			)
			( pin "J1B1.185"
				( objectStatus "@baseboard_fab2_lib.baseboard_fab2(sch_1):page83_i66:dqs3n" )
			)
			( pin "J1B1.186"
				( objectStatus "@baseboard_fab2_lib.baseboard_fab2(sch_1):page83_i66:dqs3p" )
			)
			( pin "J1B1.244"
				( objectStatus "@baseboard_fab2_lib.baseboard_fab2(sch_1):page83_i66:dqs4n" )
			)
			( pin "J1B1.245"
				( objectStatus "@baseboard_fab2_lib.baseboard_fab2(sch_1):page83_i66:dqs4p" )
			)
			( pin "J1B1.255"
				( objectStatus "@baseboard_fab2_lib.baseboard_fab2(sch_1):page83_i66:dqs5n" )
			)
			( pin "J1B1.256"
				( objectStatus "@baseboard_fab2_lib.baseboard_fab2(sch_1):page83_i66:dqs5p" )
			)
			( pin "J1B1.266"
				( objectStatus "@baseboard_fab2_lib.baseboard_fab2(sch_1):page83_i66:dqs6n" )
			)
			( pin "J1B1.267"
				( objectStatus "@baseboard_fab2_lib.baseboard_fab2(sch_1):page83_i66:dqs6p" )
			)
			( pin "J1B1.277"
				( objectStatus "@baseboard_fab2_lib.baseboard_fab2(sch_1):page83_i66:dqs7n" )
			)
			( pin "J1B1.278"
				( objectStatus "@baseboard_fab2_lib.baseboard_fab2(sch_1):page83_i66:dqs7p" )
			)
			( pin "J1B1.196"
				( objectStatus "@baseboard_fab2_lib.baseboard_fab2(sch_1):page83_i66:dqs8n" )
			)
			( pin "J1B1.197"
				( objectStatus "@baseboard_fab2_lib.baseboard_fab2(sch_1):page83_i66:dqs8p" )
			)
			( pin "J1B1.8"
				( objectStatus "@baseboard_fab2_lib.baseboard_fab2(sch_1):page83_i66:dqs9n" )
			)
			( pin "J1B1.7"
				( objectStatus "@baseboard_fab2_lib.baseboard_fab2(sch_1):page83_i66:dqs9p" )
			)
			( pin "J1B1.19"
				( objectStatus "@baseboard_fab2_lib.baseboard_fab2(sch_1):page83_i66:dqs10n" )
			)
			( pin "J1B1.18"
				( objectStatus "@baseboard_fab2_lib.baseboard_fab2(sch_1):page83_i66:dqs10p" )
			)
			( pin "J1B1.30"
				( objectStatus "@baseboard_fab2_lib.baseboard_fab2(sch_1):page83_i66:dqs11n" )
			)
			( pin "J1B1.29"
				( objectStatus "@baseboard_fab2_lib.baseboard_fab2(sch_1):page83_i66:dqs11p" )
			)
			( pin "J1B1.41"
				( objectStatus "@baseboard_fab2_lib.baseboard_fab2(sch_1):page83_i66:dqs12n" )
			)
			( pin "J1B1.40"
				( objectStatus "@baseboard_fab2_lib.baseboard_fab2(sch_1):page83_i66:dqs12p" )
			)
			( pin "J1B1.100"
				( objectStatus "@baseboard_fab2_lib.baseboard_fab2(sch_1):page83_i66:dqs13n" )
			)
			( pin "J1B1.99"
				( objectStatus "@baseboard_fab2_lib.baseboard_fab2(sch_1):page83_i66:dqs13p" )
			)
			( pin "J1B1.111"
				( objectStatus "@baseboard_fab2_lib.baseboard_fab2(sch_1):page83_i66:dqs14n" )
			)
			( pin "J1B1.110"
				( objectStatus "@baseboard_fab2_lib.baseboard_fab2(sch_1):page83_i66:dqs14p" )
			)
			( pin "J1B1.122"
				( objectStatus "@baseboard_fab2_lib.baseboard_fab2(sch_1):page83_i66:dqs15n" )
			)
			( pin "J1B1.121"
				( objectStatus "@baseboard_fab2_lib.baseboard_fab2(sch_1):page83_i66:dqs15p" )
			)
			( pin "J1B1.133"
				( objectStatus "@baseboard_fab2_lib.baseboard_fab2(sch_1):page83_i66:dqs16n" )
			)
			( pin "J1B1.132"
				( objectStatus "@baseboard_fab2_lib.baseboard_fab2(sch_1):page83_i66:dqs16p" )
			)
			( pin "J1B1.52"
				( objectStatus "@baseboard_fab2_lib.baseboard_fab2(sch_1):page83_i66:dqs17n" )
			)
			( pin "J1B1.51"
				( objectStatus "@baseboard_fab2_lib.baseboard_fab2(sch_1):page83_i66:dqs17p" )
			)
			( pin "J1B1.79"
				( objectStatus "@baseboard_fab2_lib.baseboard_fab2(sch_1):page83_i111:a0" )
			)
			( pin "J1B1.72"
				( objectStatus "@baseboard_fab2_lib.baseboard_fab2(sch_1):page83_i111:a1" )
			)
			( pin "J1B1.216"
				( objectStatus "@baseboard_fab2_lib.baseboard_fab2(sch_1):page83_i111:a2" )
			)
			( pin "J1B1.71"
				( objectStatus "@baseboard_fab2_lib.baseboard_fab2(sch_1):page83_i111:a3" )
			)
			( pin "J1B1.214"
				( objectStatus "@baseboard_fab2_lib.baseboard_fab2(sch_1):page83_i111:a4" )
			)
			( pin "J1B1.213"
				( objectStatus "@baseboard_fab2_lib.baseboard_fab2(sch_1):page83_i111:a5" )
			)
			( pin "J1B1.69"
				( objectStatus "@baseboard_fab2_lib.baseboard_fab2(sch_1):page83_i111:a6" )
			)
			( pin "J1B1.211"
				( objectStatus "@baseboard_fab2_lib.baseboard_fab2(sch_1):page83_i111:a7" )
			)
			( pin "J1B1.68"
				( objectStatus "@baseboard_fab2_lib.baseboard_fab2(sch_1):page83_i111:a8" )
			)
			( pin "J1B1.66"
				( objectStatus "@baseboard_fab2_lib.baseboard_fab2(sch_1):page83_i111:a9" )
			)
			( pin "J1B1.225"
				( objectStatus "@baseboard_fab2_lib.baseboard_fab2(sch_1):page83_i111:a10" )
			)
			( pin "J1B1.210"
				( objectStatus "@baseboard_fab2_lib.baseboard_fab2(sch_1):page83_i111:a11" )
			)
			( pin "J1B1.65"
				( objectStatus "@baseboard_fab2_lib.baseboard_fab2(sch_1):page83_i111:a12" )
			)
			( pin "J1B1.232"
				( objectStatus "@baseboard_fab2_lib.baseboard_fab2(sch_1):page83_i111:a13" )
			)
			( pin "J1B1.228"
				( objectStatus "@baseboard_fab2_lib.baseboard_fab2(sch_1):page83_i111:a14_we_n" )
			)
			( pin "J1B1.86"
				( objectStatus "@baseboard_fab2_lib.baseboard_fab2(sch_1):page83_i111:a15_cas_n" )
			)
			( pin "J1B1.82"
				( objectStatus "@baseboard_fab2_lib.baseboard_fab2(sch_1):page83_i111:a16_ras_n" )
			)
			( pin "J1B1.234"
				( objectStatus "@baseboard_fab2_lib.baseboard_fab2(sch_1):page83_i111:a17" )
			)
			( pin "J1B1.62"
				( objectStatus "@baseboard_fab2_lib.baseboard_fab2(sch_1):page83_i111:act_n" )
			)
			( pin "J1B1.208"
				( objectStatus "@baseboard_fab2_lib.baseboard_fab2(sch_1):page83_i111:alert_n" )
			)
			( pin "J1B1.81"
				( objectStatus "@baseboard_fab2_lib.baseboard_fab2(sch_1):page83_i111:ba(0)" )
			)
			( pin "J1B1.224"
				( objectStatus "@baseboard_fab2_lib.baseboard_fab2(sch_1):page83_i111:ba(1)" )
			)
			( pin "J1B1.63"
				( objectStatus "@baseboard_fab2_lib.baseboard_fab2(sch_1):page83_i111:bg(0)" )
			)
			( pin "J1B1.207"
				( objectStatus "@baseboard_fab2_lib.baseboard_fab2(sch_1):page83_i111:bg(1)" )
			)
			( pin "J1B1.235"
				( objectStatus "@baseboard_fab2_lib.baseboard_fab2(sch_1):page83_i111:c(2)" )
			)
			( pin "J1B1.49"
				( objectStatus "@baseboard_fab2_lib.baseboard_fab2(sch_1):page83_i111:cb(0)" )
			)
			( pin "J1B1.194"
				( objectStatus "@baseboard_fab2_lib.baseboard_fab2(sch_1):page83_i111:cb(1)" )
			)
			( pin "J1B1.56"
				( objectStatus "@baseboard_fab2_lib.baseboard_fab2(sch_1):page83_i111:cb(2)" )
			)
			( pin "J1B1.201"
				( objectStatus "@baseboard_fab2_lib.baseboard_fab2(sch_1):page83_i111:cb(3)" )
			)
			( pin "J1B1.47"
				( objectStatus "@baseboard_fab2_lib.baseboard_fab2(sch_1):page83_i111:cb(4)" )
			)
			( pin "J1B1.192"
				( objectStatus "@baseboard_fab2_lib.baseboard_fab2(sch_1):page83_i111:cb(5)" )
			)
			( pin "J1B1.54"
				( objectStatus "@baseboard_fab2_lib.baseboard_fab2(sch_1):page83_i111:cb(6)" )
			)
			( pin "J1B1.199"
				( objectStatus "@baseboard_fab2_lib.baseboard_fab2(sch_1):page83_i111:cb(7)" )
			)
			( pin "J1B1.75"
				( objectStatus "@baseboard_fab2_lib.baseboard_fab2(sch_1):page83_i111:ck0n" )
			)
			( pin "J1B1.74"
				( objectStatus "@baseboard_fab2_lib.baseboard_fab2(sch_1):page83_i111:ck0p" )
			)
			( pin "J1B1.219"
				( objectStatus "@baseboard_fab2_lib.baseboard_fab2(sch_1):page83_i111:ck1n" )
			)
			( pin "J1B1.218"
				( objectStatus "@baseboard_fab2_lib.baseboard_fab2(sch_1):page83_i111:ck1p" )
			)
			( pin "J1B1.60"
				( objectStatus "@baseboard_fab2_lib.baseboard_fab2(sch_1):page83_i111:cke(0)" )
			)
			( pin "J1B1.203"
				( objectStatus "@baseboard_fab2_lib.baseboard_fab2(sch_1):page83_i111:cke(1)" )
			)
			( pin "J1B1.5"
				( objectStatus "@baseboard_fab2_lib.baseboard_fab2(sch_1):page83_i111:dq(0)" )
			)
			( pin "J1B1.150"
				( objectStatus "@baseboard_fab2_lib.baseboard_fab2(sch_1):page83_i111:dq(1)" )
			)
			( pin "J1B1.12"
				( objectStatus "@baseboard_fab2_lib.baseboard_fab2(sch_1):page83_i111:dq(2)" )
			)
			( pin "J1B1.157"
				( objectStatus "@baseboard_fab2_lib.baseboard_fab2(sch_1):page83_i111:dq(3)" )
			)
			( pin "J1B1.3"
				( objectStatus "@baseboard_fab2_lib.baseboard_fab2(sch_1):page83_i111:dq(4)" )
			)
			( pin "J1B1.148"
				( objectStatus "@baseboard_fab2_lib.baseboard_fab2(sch_1):page83_i111:dq(5)" )
			)
			( pin "J1B1.10"
				( objectStatus "@baseboard_fab2_lib.baseboard_fab2(sch_1):page83_i111:dq(6)" )
			)
			( pin "J1B1.155"
				( objectStatus "@baseboard_fab2_lib.baseboard_fab2(sch_1):page83_i111:dq(7)" )
			)
			( pin "J1B1.16"
				( objectStatus "@baseboard_fab2_lib.baseboard_fab2(sch_1):page83_i111:dq(8)" )
			)
			( pin "J1B1.161"
				( objectStatus "@baseboard_fab2_lib.baseboard_fab2(sch_1):page83_i111:dq(9)" )
			)
			( pin "J1B1.23"
				( objectStatus "@baseboard_fab2_lib.baseboard_fab2(sch_1):page83_i111:dq(10)" )
			)
			( pin "J1B1.168"
				( objectStatus "@baseboard_fab2_lib.baseboard_fab2(sch_1):page83_i111:dq(11)" )
			)
			( pin "J1B1.14"
				( objectStatus "@baseboard_fab2_lib.baseboard_fab2(sch_1):page83_i111:dq(12)" )
			)
			( pin "J1B1.159"
				( objectStatus "@baseboard_fab2_lib.baseboard_fab2(sch_1):page83_i111:dq(13)" )
			)
			( pin "J1B1.21"
				( objectStatus "@baseboard_fab2_lib.baseboard_fab2(sch_1):page83_i111:dq(14)" )
			)
			( pin "J1B1.166"
				( objectStatus "@baseboard_fab2_lib.baseboard_fab2(sch_1):page83_i111:dq(15)" )
			)
			( pin "J1B1.27"
				( objectStatus "@baseboard_fab2_lib.baseboard_fab2(sch_1):page83_i111:dq(16)" )
			)
			( pin "J1B1.172"
				( objectStatus "@baseboard_fab2_lib.baseboard_fab2(sch_1):page83_i111:dq(17)" )
			)
			( pin "J1B1.34"
				( objectStatus "@baseboard_fab2_lib.baseboard_fab2(sch_1):page83_i111:dq(18)" )
			)
			( pin "J1B1.179"
				( objectStatus "@baseboard_fab2_lib.baseboard_fab2(sch_1):page83_i111:dq(19)" )
			)
			( pin "J1B1.25"
				( objectStatus "@baseboard_fab2_lib.baseboard_fab2(sch_1):page83_i111:dq(20)" )
			)
			( pin "J1B1.170"
				( objectStatus "@baseboard_fab2_lib.baseboard_fab2(sch_1):page83_i111:dq(21)" )
			)
			( pin "J1B1.32"
				( objectStatus "@baseboard_fab2_lib.baseboard_fab2(sch_1):page83_i111:dq(22)" )
			)
			( pin "J1B1.177"
				( objectStatus "@baseboard_fab2_lib.baseboard_fab2(sch_1):page83_i111:dq(23)" )
			)
			( pin "J1B1.38"
				( objectStatus "@baseboard_fab2_lib.baseboard_fab2(sch_1):page83_i111:dq(24)" )
			)
			( pin "J1B1.183"
				( objectStatus "@baseboard_fab2_lib.baseboard_fab2(sch_1):page83_i111:dq(25)" )
			)
			( pin "J1B1.45"
				( objectStatus "@baseboard_fab2_lib.baseboard_fab2(sch_1):page83_i111:dq(26)" )
			)
			( pin "J1B1.190"
				( objectStatus "@baseboard_fab2_lib.baseboard_fab2(sch_1):page83_i111:dq(27)" )
			)
			( pin "J1B1.36"
				( objectStatus "@baseboard_fab2_lib.baseboard_fab2(sch_1):page83_i111:dq(28)" )
			)
			( pin "J1B1.181"
				( objectStatus "@baseboard_fab2_lib.baseboard_fab2(sch_1):page83_i111:dq(29)" )
			)
			( pin "J1B1.43"
				( objectStatus "@baseboard_fab2_lib.baseboard_fab2(sch_1):page83_i111:dq(30)" )
			)
			( pin "J1B1.188"
				( objectStatus "@baseboard_fab2_lib.baseboard_fab2(sch_1):page83_i111:dq(31)" )
			)
			( pin "J1B1.97"
				( objectStatus "@baseboard_fab2_lib.baseboard_fab2(sch_1):page83_i111:dq(32)" )
			)
			( pin "J1B1.242"
				( objectStatus "@baseboard_fab2_lib.baseboard_fab2(sch_1):page83_i111:dq(33)" )
			)
			( pin "J1B1.104"
				( objectStatus "@baseboard_fab2_lib.baseboard_fab2(sch_1):page83_i111:dq(34)" )
			)
			( pin "J1B1.249"
				( objectStatus "@baseboard_fab2_lib.baseboard_fab2(sch_1):page83_i111:dq(35)" )
			)
			( pin "J1B1.95"
				( objectStatus "@baseboard_fab2_lib.baseboard_fab2(sch_1):page83_i111:dq(36)" )
			)
			( pin "J1B1.240"
				( objectStatus "@baseboard_fab2_lib.baseboard_fab2(sch_1):page83_i111:dq(37)" )
			)
			( pin "J1B1.102"
				( objectStatus "@baseboard_fab2_lib.baseboard_fab2(sch_1):page83_i111:dq(38)" )
			)
			( pin "J1B1.247"
				( objectStatus "@baseboard_fab2_lib.baseboard_fab2(sch_1):page83_i111:dq(39)" )
			)
			( pin "J1B1.108"
				( objectStatus "@baseboard_fab2_lib.baseboard_fab2(sch_1):page83_i111:dq(40)" )
			)
			( pin "J1B1.253"
				( objectStatus "@baseboard_fab2_lib.baseboard_fab2(sch_1):page83_i111:dq(41)" )
			)
			( pin "J1B1.115"
				( objectStatus "@baseboard_fab2_lib.baseboard_fab2(sch_1):page83_i111:dq(42)" )
			)
			( pin "J1B1.260"
				( objectStatus "@baseboard_fab2_lib.baseboard_fab2(sch_1):page83_i111:dq(43)" )
			)
			( pin "J1B1.106"
				( objectStatus "@baseboard_fab2_lib.baseboard_fab2(sch_1):page83_i111:dq(44)" )
			)
			( pin "J1B1.251"
				( objectStatus "@baseboard_fab2_lib.baseboard_fab2(sch_1):page83_i111:dq(45)" )
			)
			( pin "J1B1.113"
				( objectStatus "@baseboard_fab2_lib.baseboard_fab2(sch_1):page83_i111:dq(46)" )
			)
			( pin "J1B1.258"
				( objectStatus "@baseboard_fab2_lib.baseboard_fab2(sch_1):page83_i111:dq(47)" )
			)
			( pin "J1B1.119"
				( objectStatus "@baseboard_fab2_lib.baseboard_fab2(sch_1):page83_i111:dq(48)" )
			)
			( pin "J1B1.264"
				( objectStatus "@baseboard_fab2_lib.baseboard_fab2(sch_1):page83_i111:dq(49)" )
			)
			( pin "J1B1.126"
				( objectStatus "@baseboard_fab2_lib.baseboard_fab2(sch_1):page83_i111:dq(50)" )
			)
			( pin "J1B1.271"
				( objectStatus "@baseboard_fab2_lib.baseboard_fab2(sch_1):page83_i111:dq(51)" )
			)
			( pin "J1B1.117"
				( objectStatus "@baseboard_fab2_lib.baseboard_fab2(sch_1):page83_i111:dq(52)" )
			)
			( pin "J1B1.262"
				( objectStatus "@baseboard_fab2_lib.baseboard_fab2(sch_1):page83_i111:dq(53)" )
			)
			( pin "J1B1.124"
				( objectStatus "@baseboard_fab2_lib.baseboard_fab2(sch_1):page83_i111:dq(54)" )
			)
			( pin "J1B1.269"
				( objectStatus "@baseboard_fab2_lib.baseboard_fab2(sch_1):page83_i111:dq(55)" )
			)
			( pin "J1B1.130"
				( objectStatus "@baseboard_fab2_lib.baseboard_fab2(sch_1):page83_i111:dq(56)" )
			)
			( pin "J1B1.275"
				( objectStatus "@baseboard_fab2_lib.baseboard_fab2(sch_1):page83_i111:dq(57)" )
			)
			( pin "J1B1.137"
				( objectStatus "@baseboard_fab2_lib.baseboard_fab2(sch_1):page83_i111:dq(58)" )
			)
			( pin "J1B1.282"
				( objectStatus "@baseboard_fab2_lib.baseboard_fab2(sch_1):page83_i111:dq(59)" )
			)
			( pin "J1B1.128"
				( objectStatus "@baseboard_fab2_lib.baseboard_fab2(sch_1):page83_i111:dq(60)" )
			)
			( pin "J1B1.273"
				( objectStatus "@baseboard_fab2_lib.baseboard_fab2(sch_1):page83_i111:dq(61)" )
			)
			( pin "J1B1.135"
				( objectStatus "@baseboard_fab2_lib.baseboard_fab2(sch_1):page83_i111:dq(62)" )
			)
			( pin "J1B1.280"
				( objectStatus "@baseboard_fab2_lib.baseboard_fab2(sch_1):page83_i111:dq(63)" )
			)
			( pin "J1B1.78"
				( objectStatus "@baseboard_fab2_lib.baseboard_fab2(sch_1):page83_i111:event_n" )
			)
			( pin "J1B1.87"
				( objectStatus "@baseboard_fab2_lib.baseboard_fab2(sch_1):page83_i111:odt(0)" )
			)
			( pin "J1B1.91"
				( objectStatus "@baseboard_fab2_lib.baseboard_fab2(sch_1):page83_i111:odt(1)" )
			)
			( pin "J1B1.222"
				( objectStatus "@baseboard_fab2_lib.baseboard_fab2(sch_1):page83_i111:par" )
			)
			( pin "J1B1.58"
				( objectStatus "@baseboard_fab2_lib.baseboard_fab2(sch_1):page83_i111:reset_n" )
			)
			( pin "J1B1.205"
				( objectStatus "@baseboard_fab2_lib.baseboard_fab2(sch_1):page83_i111:rfu(0)" )
			)
			( pin "J1B1.227"
				( objectStatus "@baseboard_fab2_lib.baseboard_fab2(sch_1):page83_i111:rfu(1)" )
			)
			( pin "J1B1.144"
				( objectStatus "@baseboard_fab2_lib.baseboard_fab2(sch_1):page83_i111:rfu(2)" )
			)
			( pin "J1B1.84"
				( objectStatus "@baseboard_fab2_lib.baseboard_fab2(sch_1):page83_i111:s0_n" )
			)
			( pin "J1B1.89"
				( objectStatus "@baseboard_fab2_lib.baseboard_fab2(sch_1):page83_i111:s1_n" )
			)
			( pin "J1B1.93"
				( objectStatus "@baseboard_fab2_lib.baseboard_fab2(sch_1):page83_i111:s2_n_c(0)" )
			)
			( pin "J1B1.237"
				( objectStatus "@baseboard_fab2_lib.baseboard_fab2(sch_1):page83_i111:s3_n_c(1)" )
			)
			( pin "J1B1.139"
				( objectStatus "@baseboard_fab2_lib.baseboard_fab2(sch_1):page83_i111:sa(0)" )
			)
			( pin "J1B1.140"
				( objectStatus "@baseboard_fab2_lib.baseboard_fab2(sch_1):page83_i111:sa(1)" )
			)
			( pin "J1B1.238"
				( objectStatus "@baseboard_fab2_lib.baseboard_fab2(sch_1):page83_i111:sa(2)" )
			)
			( pin "J1B1.230"
				( objectStatus "@baseboard_fab2_lib.baseboard_fab2(sch_1):page83_i111:save_n_nc" )
			)
			( pin "J1B1.141"
				( objectStatus "@baseboard_fab2_lib.baseboard_fab2(sch_1):page83_i111:scl" )
			)
			( pin "J1B1.285"
				( objectStatus "@baseboard_fab2_lib.baseboard_fab2(sch_1):page83_i111:sda" )
			)
			( pin "J1B1.284"
				( objectStatus "@baseboard_fab2_lib.baseboard_fab2(sch_1):page83_i111:vddspd" )
			)
			( pin "J1B1.146"
				( objectStatus "@baseboard_fab2_lib.baseboard_fab2(sch_1):page83_i111:vrefca" )
			)
			( pin "J1B1.145"
				( objectStatus "@baseboard_fab2_lib.baseboard_fab2(sch_1):page83_i167:\12v\(0)" )
			)
			( pin "J1B1.1"
				( objectStatus "@baseboard_fab2_lib.baseboard_fab2(sch_1):page83_i167:\12v\(1)" )
			)
			( pin "J1B1.236"
				( objectStatus "@baseboard_fab2_lib.baseboard_fab2(sch_1):page83_i167:vdd(0)" )
			)
			( pin "J1B1.233"
				( objectStatus "@baseboard_fab2_lib.baseboard_fab2(sch_1):page83_i167:vdd(1)" )
			)
			( pin "J1B1.231"
				( objectStatus "@baseboard_fab2_lib.baseboard_fab2(sch_1):page83_i167:vdd(2)" )
			)
			( pin "J1B1.229"
				( objectStatus "@baseboard_fab2_lib.baseboard_fab2(sch_1):page83_i167:vdd(3)" )
			)
			( pin "J1B1.226"
				( objectStatus "@baseboard_fab2_lib.baseboard_fab2(sch_1):page83_i167:vdd(4)" )
			)
			( pin "J1B1.223"
				( objectStatus "@baseboard_fab2_lib.baseboard_fab2(sch_1):page83_i167:vdd(5)" )
			)
			( pin "J1B1.220"
				( objectStatus "@baseboard_fab2_lib.baseboard_fab2(sch_1):page83_i167:vdd(6)" )
			)
			( pin "J1B1.217"
				( objectStatus "@baseboard_fab2_lib.baseboard_fab2(sch_1):page83_i167:vdd(7)" )
			)
			( pin "J1B1.215"
				( objectStatus "@baseboard_fab2_lib.baseboard_fab2(sch_1):page83_i167:vdd(8)" )
			)
			( pin "J1B1.212"
				( objectStatus "@baseboard_fab2_lib.baseboard_fab2(sch_1):page83_i167:vdd(9)" )
			)
			( pin "J1B1.209"
				( objectStatus "@baseboard_fab2_lib.baseboard_fab2(sch_1):page83_i167:vdd(10)" )
			)
			( pin "J1B1.206"
				( objectStatus "@baseboard_fab2_lib.baseboard_fab2(sch_1):page83_i167:vdd(11)" )
			)
			( pin "J1B1.204"
				( objectStatus "@baseboard_fab2_lib.baseboard_fab2(sch_1):page83_i167:vdd(12)" )
			)
			( pin "J1B1.92"
				( objectStatus "@baseboard_fab2_lib.baseboard_fab2(sch_1):page83_i167:vdd(13)" )
			)
			( pin "J1B1.90"
				( objectStatus "@baseboard_fab2_lib.baseboard_fab2(sch_1):page83_i167:vdd(14)" )
			)
			( pin "J1B1.88"
				( objectStatus "@baseboard_fab2_lib.baseboard_fab2(sch_1):page83_i167:vdd(15)" )
			)
			( pin "J1B1.85"
				( objectStatus "@baseboard_fab2_lib.baseboard_fab2(sch_1):page83_i167:vdd(16)" )
			)
			( pin "J1B1.83"
				( objectStatus "@baseboard_fab2_lib.baseboard_fab2(sch_1):page83_i167:vdd(17)" )
			)
			( pin "J1B1.80"
				( objectStatus "@baseboard_fab2_lib.baseboard_fab2(sch_1):page83_i167:vdd(18)" )
			)
			( pin "J1B1.76"
				( objectStatus "@baseboard_fab2_lib.baseboard_fab2(sch_1):page83_i167:vdd(19)" )
			)
			( pin "J1B1.73"
				( objectStatus "@baseboard_fab2_lib.baseboard_fab2(sch_1):page83_i167:vdd(20)" )
			)
			( pin "J1B1.70"
				( objectStatus "@baseboard_fab2_lib.baseboard_fab2(sch_1):page83_i167:vdd(21)" )
			)
			( pin "J1B1.67"
				( objectStatus "@baseboard_fab2_lib.baseboard_fab2(sch_1):page83_i167:vdd(22)" )
			)
			( pin "J1B1.64"
				( objectStatus "@baseboard_fab2_lib.baseboard_fab2(sch_1):page83_i167:vdd(23)" )
			)
			( pin "J1B1.61"
				( objectStatus "@baseboard_fab2_lib.baseboard_fab2(sch_1):page83_i167:vdd(24)" )
			)
			( pin "J1B1.59"
				( objectStatus "@baseboard_fab2_lib.baseboard_fab2(sch_1):page83_i167:vdd(25)" )
			)
			( pin "J1B1.287"
				( objectStatus "@baseboard_fab2_lib.baseboard_fab2(sch_1):page83_i167:vpp(0)" )
			)
			( pin "J1B1.286"
				( objectStatus "@baseboard_fab2_lib.baseboard_fab2(sch_1):page83_i167:vpp(1)" )
			)
			( pin "J1B1.288"
				( objectStatus "@baseboard_fab2_lib.baseboard_fab2(sch_1):page83_i167:vpp(2)" )
			)
			( pin "J1B1.143"
				( objectStatus "@baseboard_fab2_lib.baseboard_fab2(sch_1):page83_i167:vpp(3)" )
			)
			( pin "J1B1.142"
				( objectStatus "@baseboard_fab2_lib.baseboard_fab2(sch_1):page83_i167:vpp(4)" )
			)
			( pin "J1B1.221"
				( objectStatus "@baseboard_fab2_lib.baseboard_fab2(sch_1):page83_i167:vtt(0)" )
			)
			( pin "J1B1.77"
				( objectStatus "@baseboard_fab2_lib.baseboard_fab2(sch_1):page83_i167:vtt(1)" )
			)
			( pin "C1B9.1"
				( objectStatus "@baseboard_fab2_lib.baseboard_fab2(sch_1):page83_i176:a" )
			)
			( pin "C1B9.2"
				( objectStatus "@baseboard_fab2_lib.baseboard_fab2(sch_1):page83_i176:b" )
			)
			( pin "C9M1.1"
				( objectStatus "@baseboard_fab2_lib.baseboard_fab2(sch_1):page84_i4:a" )
			)
			( pin "C9M1.2"
				( objectStatus "@baseboard_fab2_lib.baseboard_fab2(sch_1):page84_i4:b" )
			)
			( pin "J9M1.79"
				( objectStatus "@baseboard_fab2_lib.baseboard_fab2(sch_1):page84_i14:a0" )
			)
			( pin "J9M1.72"
				( objectStatus "@baseboard_fab2_lib.baseboard_fab2(sch_1):page84_i14:a1" )
			)
			( pin "J9M1.216"
				( objectStatus "@baseboard_fab2_lib.baseboard_fab2(sch_1):page84_i14:a2" )
			)
			( pin "J9M1.71"
				( objectStatus "@baseboard_fab2_lib.baseboard_fab2(sch_1):page84_i14:a3" )
			)
			( pin "J9M1.214"
				( objectStatus "@baseboard_fab2_lib.baseboard_fab2(sch_1):page84_i14:a4" )
			)
			( pin "J9M1.213"
				( objectStatus "@baseboard_fab2_lib.baseboard_fab2(sch_1):page84_i14:a5" )
			)
			( pin "J9M1.69"
				( objectStatus "@baseboard_fab2_lib.baseboard_fab2(sch_1):page84_i14:a6" )
			)
			( pin "J9M1.211"
				( objectStatus "@baseboard_fab2_lib.baseboard_fab2(sch_1):page84_i14:a7" )
			)
			( pin "J9M1.68"
				( objectStatus "@baseboard_fab2_lib.baseboard_fab2(sch_1):page84_i14:a8" )
			)
			( pin "J9M1.66"
				( objectStatus "@baseboard_fab2_lib.baseboard_fab2(sch_1):page84_i14:a9" )
			)
			( pin "J9M1.225"
				( objectStatus "@baseboard_fab2_lib.baseboard_fab2(sch_1):page84_i14:a10" )
			)
			( pin "J9M1.210"
				( objectStatus "@baseboard_fab2_lib.baseboard_fab2(sch_1):page84_i14:a11" )
			)
			( pin "J9M1.65"
				( objectStatus "@baseboard_fab2_lib.baseboard_fab2(sch_1):page84_i14:a12" )
			)
			( pin "J9M1.232"
				( objectStatus "@baseboard_fab2_lib.baseboard_fab2(sch_1):page84_i14:a13" )
			)
			( pin "J9M1.228"
				( objectStatus "@baseboard_fab2_lib.baseboard_fab2(sch_1):page84_i14:a14_we_n" )
			)
			( pin "J9M1.86"
				( objectStatus "@baseboard_fab2_lib.baseboard_fab2(sch_1):page84_i14:a15_cas_n" )
			)
			( pin "J9M1.82"
				( objectStatus "@baseboard_fab2_lib.baseboard_fab2(sch_1):page84_i14:a16_ras_n" )
			)
			( pin "J9M1.234"
				( objectStatus "@baseboard_fab2_lib.baseboard_fab2(sch_1):page84_i14:a17" )
			)
			( pin "J9M1.62"
				( objectStatus "@baseboard_fab2_lib.baseboard_fab2(sch_1):page84_i14:act_n" )
			)
			( pin "J9M1.208"
				( objectStatus "@baseboard_fab2_lib.baseboard_fab2(sch_1):page84_i14:alert_n" )
			)
			( pin "J9M1.81"
				( objectStatus "@baseboard_fab2_lib.baseboard_fab2(sch_1):page84_i14:ba(0)" )
			)
			( pin "J9M1.224"
				( objectStatus "@baseboard_fab2_lib.baseboard_fab2(sch_1):page84_i14:ba(1)" )
			)
			( pin "J9M1.63"
				( objectStatus "@baseboard_fab2_lib.baseboard_fab2(sch_1):page84_i14:bg(0)" )
			)
			( pin "J9M1.207"
				( objectStatus "@baseboard_fab2_lib.baseboard_fab2(sch_1):page84_i14:bg(1)" )
			)
			( pin "J9M1.235"
				( objectStatus "@baseboard_fab2_lib.baseboard_fab2(sch_1):page84_i14:c(2)" )
			)
			( pin "J9M1.49"
				( objectStatus "@baseboard_fab2_lib.baseboard_fab2(sch_1):page84_i14:cb(0)" )
			)
			( pin "J9M1.194"
				( objectStatus "@baseboard_fab2_lib.baseboard_fab2(sch_1):page84_i14:cb(1)" )
			)
			( pin "J9M1.56"
				( objectStatus "@baseboard_fab2_lib.baseboard_fab2(sch_1):page84_i14:cb(2)" )
			)
			( pin "J9M1.201"
				( objectStatus "@baseboard_fab2_lib.baseboard_fab2(sch_1):page84_i14:cb(3)" )
			)
			( pin "J9M1.47"
				( objectStatus "@baseboard_fab2_lib.baseboard_fab2(sch_1):page84_i14:cb(4)" )
			)
			( pin "J9M1.192"
				( objectStatus "@baseboard_fab2_lib.baseboard_fab2(sch_1):page84_i14:cb(5)" )
			)
			( pin "J9M1.54"
				( objectStatus "@baseboard_fab2_lib.baseboard_fab2(sch_1):page84_i14:cb(6)" )
			)
			( pin "J9M1.199"
				( objectStatus "@baseboard_fab2_lib.baseboard_fab2(sch_1):page84_i14:cb(7)" )
			)
			( pin "J9M1.75"
				( objectStatus "@baseboard_fab2_lib.baseboard_fab2(sch_1):page84_i14:ck0n" )
			)
			( pin "J9M1.74"
				( objectStatus "@baseboard_fab2_lib.baseboard_fab2(sch_1):page84_i14:ck0p" )
			)
			( pin "J9M1.219"
				( objectStatus "@baseboard_fab2_lib.baseboard_fab2(sch_1):page84_i14:ck1n" )
			)
			( pin "J9M1.218"
				( objectStatus "@baseboard_fab2_lib.baseboard_fab2(sch_1):page84_i14:ck1p" )
			)
			( pin "J9M1.60"
				( objectStatus "@baseboard_fab2_lib.baseboard_fab2(sch_1):page84_i14:cke(0)" )
			)
			( pin "J9M1.203"
				( objectStatus "@baseboard_fab2_lib.baseboard_fab2(sch_1):page84_i14:cke(1)" )
			)
			( pin "J9M1.5"
				( objectStatus "@baseboard_fab2_lib.baseboard_fab2(sch_1):page84_i14:dq(0)" )
			)
			( pin "J9M1.150"
				( objectStatus "@baseboard_fab2_lib.baseboard_fab2(sch_1):page84_i14:dq(1)" )
			)
			( pin "J9M1.12"
				( objectStatus "@baseboard_fab2_lib.baseboard_fab2(sch_1):page84_i14:dq(2)" )
			)
			( pin "J9M1.157"
				( objectStatus "@baseboard_fab2_lib.baseboard_fab2(sch_1):page84_i14:dq(3)" )
			)
			( pin "J9M1.3"
				( objectStatus "@baseboard_fab2_lib.baseboard_fab2(sch_1):page84_i14:dq(4)" )
			)
			( pin "J9M1.148"
				( objectStatus "@baseboard_fab2_lib.baseboard_fab2(sch_1):page84_i14:dq(5)" )
			)
			( pin "J9M1.10"
				( objectStatus "@baseboard_fab2_lib.baseboard_fab2(sch_1):page84_i14:dq(6)" )
			)
			( pin "J9M1.155"
				( objectStatus "@baseboard_fab2_lib.baseboard_fab2(sch_1):page84_i14:dq(7)" )
			)
			( pin "J9M1.16"
				( objectStatus "@baseboard_fab2_lib.baseboard_fab2(sch_1):page84_i14:dq(8)" )
			)
			( pin "J9M1.161"
				( objectStatus "@baseboard_fab2_lib.baseboard_fab2(sch_1):page84_i14:dq(9)" )
			)
			( pin "J9M1.23"
				( objectStatus "@baseboard_fab2_lib.baseboard_fab2(sch_1):page84_i14:dq(10)" )
			)
			( pin "J9M1.168"
				( objectStatus "@baseboard_fab2_lib.baseboard_fab2(sch_1):page84_i14:dq(11)" )
			)
			( pin "J9M1.14"
				( objectStatus "@baseboard_fab2_lib.baseboard_fab2(sch_1):page84_i14:dq(12)" )
			)
			( pin "J9M1.159"
				( objectStatus "@baseboard_fab2_lib.baseboard_fab2(sch_1):page84_i14:dq(13)" )
			)
			( pin "J9M1.21"
				( objectStatus "@baseboard_fab2_lib.baseboard_fab2(sch_1):page84_i14:dq(14)" )
			)
			( pin "J9M1.166"
				( objectStatus "@baseboard_fab2_lib.baseboard_fab2(sch_1):page84_i14:dq(15)" )
			)
			( pin "J9M1.27"
				( objectStatus "@baseboard_fab2_lib.baseboard_fab2(sch_1):page84_i14:dq(16)" )
			)
			( pin "J9M1.172"
				( objectStatus "@baseboard_fab2_lib.baseboard_fab2(sch_1):page84_i14:dq(17)" )
			)
			( pin "J9M1.34"
				( objectStatus "@baseboard_fab2_lib.baseboard_fab2(sch_1):page84_i14:dq(18)" )
			)
			( pin "J9M1.179"
				( objectStatus "@baseboard_fab2_lib.baseboard_fab2(sch_1):page84_i14:dq(19)" )
			)
			( pin "J9M1.25"
				( objectStatus "@baseboard_fab2_lib.baseboard_fab2(sch_1):page84_i14:dq(20)" )
			)
			( pin "J9M1.170"
				( objectStatus "@baseboard_fab2_lib.baseboard_fab2(sch_1):page84_i14:dq(21)" )
			)
			( pin "J9M1.32"
				( objectStatus "@baseboard_fab2_lib.baseboard_fab2(sch_1):page84_i14:dq(22)" )
			)
			( pin "J9M1.177"
				( objectStatus "@baseboard_fab2_lib.baseboard_fab2(sch_1):page84_i14:dq(23)" )
			)
			( pin "J9M1.38"
				( objectStatus "@baseboard_fab2_lib.baseboard_fab2(sch_1):page84_i14:dq(24)" )
			)
			( pin "J9M1.183"
				( objectStatus "@baseboard_fab2_lib.baseboard_fab2(sch_1):page84_i14:dq(25)" )
			)
			( pin "J9M1.45"
				( objectStatus "@baseboard_fab2_lib.baseboard_fab2(sch_1):page84_i14:dq(26)" )
			)
			( pin "J9M1.190"
				( objectStatus "@baseboard_fab2_lib.baseboard_fab2(sch_1):page84_i14:dq(27)" )
			)
			( pin "J9M1.36"
				( objectStatus "@baseboard_fab2_lib.baseboard_fab2(sch_1):page84_i14:dq(28)" )
			)
			( pin "J9M1.181"
				( objectStatus "@baseboard_fab2_lib.baseboard_fab2(sch_1):page84_i14:dq(29)" )
			)
			( pin "J9M1.43"
				( objectStatus "@baseboard_fab2_lib.baseboard_fab2(sch_1):page84_i14:dq(30)" )
			)
			( pin "J9M1.188"
				( objectStatus "@baseboard_fab2_lib.baseboard_fab2(sch_1):page84_i14:dq(31)" )
			)
			( pin "J9M1.97"
				( objectStatus "@baseboard_fab2_lib.baseboard_fab2(sch_1):page84_i14:dq(32)" )
			)
			( pin "J9M1.242"
				( objectStatus "@baseboard_fab2_lib.baseboard_fab2(sch_1):page84_i14:dq(33)" )
			)
			( pin "J9M1.104"
				( objectStatus "@baseboard_fab2_lib.baseboard_fab2(sch_1):page84_i14:dq(34)" )
			)
			( pin "J9M1.249"
				( objectStatus "@baseboard_fab2_lib.baseboard_fab2(sch_1):page84_i14:dq(35)" )
			)
			( pin "J9M1.95"
				( objectStatus "@baseboard_fab2_lib.baseboard_fab2(sch_1):page84_i14:dq(36)" )
			)
			( pin "J9M1.240"
				( objectStatus "@baseboard_fab2_lib.baseboard_fab2(sch_1):page84_i14:dq(37)" )
			)
			( pin "J9M1.102"
				( objectStatus "@baseboard_fab2_lib.baseboard_fab2(sch_1):page84_i14:dq(38)" )
			)
			( pin "J9M1.247"
				( objectStatus "@baseboard_fab2_lib.baseboard_fab2(sch_1):page84_i14:dq(39)" )
			)
			( pin "J9M1.108"
				( objectStatus "@baseboard_fab2_lib.baseboard_fab2(sch_1):page84_i14:dq(40)" )
			)
			( pin "J9M1.253"
				( objectStatus "@baseboard_fab2_lib.baseboard_fab2(sch_1):page84_i14:dq(41)" )
			)
			( pin "J9M1.115"
				( objectStatus "@baseboard_fab2_lib.baseboard_fab2(sch_1):page84_i14:dq(42)" )
			)
			( pin "J9M1.260"
				( objectStatus "@baseboard_fab2_lib.baseboard_fab2(sch_1):page84_i14:dq(43)" )
			)
			( pin "J9M1.106"
				( objectStatus "@baseboard_fab2_lib.baseboard_fab2(sch_1):page84_i14:dq(44)" )
			)
			( pin "J9M1.251"
				( objectStatus "@baseboard_fab2_lib.baseboard_fab2(sch_1):page84_i14:dq(45)" )
			)
			( pin "J9M1.113"
				( objectStatus "@baseboard_fab2_lib.baseboard_fab2(sch_1):page84_i14:dq(46)" )
			)
			( pin "J9M1.258"
				( objectStatus "@baseboard_fab2_lib.baseboard_fab2(sch_1):page84_i14:dq(47)" )
			)
			( pin "J9M1.119"
				( objectStatus "@baseboard_fab2_lib.baseboard_fab2(sch_1):page84_i14:dq(48)" )
			)
			( pin "J9M1.264"
				( objectStatus "@baseboard_fab2_lib.baseboard_fab2(sch_1):page84_i14:dq(49)" )
			)
			( pin "J9M1.126"
				( objectStatus "@baseboard_fab2_lib.baseboard_fab2(sch_1):page84_i14:dq(50)" )
			)
			( pin "J9M1.271"
				( objectStatus "@baseboard_fab2_lib.baseboard_fab2(sch_1):page84_i14:dq(51)" )
			)
			( pin "J9M1.117"
				( objectStatus "@baseboard_fab2_lib.baseboard_fab2(sch_1):page84_i14:dq(52)" )
			)
			( pin "J9M1.262"
				( objectStatus "@baseboard_fab2_lib.baseboard_fab2(sch_1):page84_i14:dq(53)" )
			)
			( pin "J9M1.124"
				( objectStatus "@baseboard_fab2_lib.baseboard_fab2(sch_1):page84_i14:dq(54)" )
			)
			( pin "J9M1.269"
				( objectStatus "@baseboard_fab2_lib.baseboard_fab2(sch_1):page84_i14:dq(55)" )
			)
			( pin "J9M1.130"
				( objectStatus "@baseboard_fab2_lib.baseboard_fab2(sch_1):page84_i14:dq(56)" )
			)
			( pin "J9M1.275"
				( objectStatus "@baseboard_fab2_lib.baseboard_fab2(sch_1):page84_i14:dq(57)" )
			)
			( pin "J9M1.137"
				( objectStatus "@baseboard_fab2_lib.baseboard_fab2(sch_1):page84_i14:dq(58)" )
			)
			( pin "J9M1.282"
				( objectStatus "@baseboard_fab2_lib.baseboard_fab2(sch_1):page84_i14:dq(59)" )
			)
			( pin "J9M1.128"
				( objectStatus "@baseboard_fab2_lib.baseboard_fab2(sch_1):page84_i14:dq(60)" )
			)
			( pin "J9M1.273"
				( objectStatus "@baseboard_fab2_lib.baseboard_fab2(sch_1):page84_i14:dq(61)" )
			)
			( pin "J9M1.135"
				( objectStatus "@baseboard_fab2_lib.baseboard_fab2(sch_1):page84_i14:dq(62)" )
			)
			( pin "J9M1.280"
				( objectStatus "@baseboard_fab2_lib.baseboard_fab2(sch_1):page84_i14:dq(63)" )
			)
			( pin "J9M1.78"
				( objectStatus "@baseboard_fab2_lib.baseboard_fab2(sch_1):page84_i14:event_n" )
			)
			( pin "J9M1.87"
				( objectStatus "@baseboard_fab2_lib.baseboard_fab2(sch_1):page84_i14:odt(0)" )
			)
			( pin "J9M1.91"
				( objectStatus "@baseboard_fab2_lib.baseboard_fab2(sch_1):page84_i14:odt(1)" )
			)
			( pin "J9M1.222"
				( objectStatus "@baseboard_fab2_lib.baseboard_fab2(sch_1):page84_i14:par" )
			)
			( pin "J9M1.58"
				( objectStatus "@baseboard_fab2_lib.baseboard_fab2(sch_1):page84_i14:reset_n" )
			)
			( pin "J9M1.205"
				( objectStatus "@baseboard_fab2_lib.baseboard_fab2(sch_1):page84_i14:rfu(0)" )
			)
			( pin "J9M1.227"
				( objectStatus "@baseboard_fab2_lib.baseboard_fab2(sch_1):page84_i14:rfu(1)" )
			)
			( pin "J9M1.144"
				( objectStatus "@baseboard_fab2_lib.baseboard_fab2(sch_1):page84_i14:rfu(2)" )
			)
			( pin "J9M1.84"
				( objectStatus "@baseboard_fab2_lib.baseboard_fab2(sch_1):page84_i14:s0_n" )
			)
			( pin "J9M1.89"
				( objectStatus "@baseboard_fab2_lib.baseboard_fab2(sch_1):page84_i14:s1_n" )
			)
			( pin "J9M1.93"
				( objectStatus "@baseboard_fab2_lib.baseboard_fab2(sch_1):page84_i14:s2_n_c(0)" )
			)
			( pin "J9M1.237"
				( objectStatus "@baseboard_fab2_lib.baseboard_fab2(sch_1):page84_i14:s3_n_c(1)" )
			)
			( pin "J9M1.139"
				( objectStatus "@baseboard_fab2_lib.baseboard_fab2(sch_1):page84_i14:sa(0)" )
			)
			( pin "J9M1.140"
				( objectStatus "@baseboard_fab2_lib.baseboard_fab2(sch_1):page84_i14:sa(1)" )
			)
			( pin "J9M1.238"
				( objectStatus "@baseboard_fab2_lib.baseboard_fab2(sch_1):page84_i14:sa(2)" )
			)
			( pin "J9M1.230"
				( objectStatus "@baseboard_fab2_lib.baseboard_fab2(sch_1):page84_i14:save_n_nc" )
			)
			( pin "J9M1.141"
				( objectStatus "@baseboard_fab2_lib.baseboard_fab2(sch_1):page84_i14:scl" )
			)
			( pin "J9M1.285"
				( objectStatus "@baseboard_fab2_lib.baseboard_fab2(sch_1):page84_i14:sda" )
			)
			( pin "J9M1.284"
				( objectStatus "@baseboard_fab2_lib.baseboard_fab2(sch_1):page84_i14:vddspd" )
			)
			( pin "J9M1.146"
				( objectStatus "@baseboard_fab2_lib.baseboard_fab2(sch_1):page84_i14:vrefca" )
			)
			( pin "J9M1.145"
				( objectStatus "@baseboard_fab2_lib.baseboard_fab2(sch_1):page84_i57:\12v\(0)" )
			)
			( pin "J9M1.1"
				( objectStatus "@baseboard_fab2_lib.baseboard_fab2(sch_1):page84_i57:\12v\(1)" )
			)
			( pin "J9M1.236"
				( objectStatus "@baseboard_fab2_lib.baseboard_fab2(sch_1):page84_i57:vdd(0)" )
			)
			( pin "J9M1.233"
				( objectStatus "@baseboard_fab2_lib.baseboard_fab2(sch_1):page84_i57:vdd(1)" )
			)
			( pin "J9M1.231"
				( objectStatus "@baseboard_fab2_lib.baseboard_fab2(sch_1):page84_i57:vdd(2)" )
			)
			( pin "J9M1.229"
				( objectStatus "@baseboard_fab2_lib.baseboard_fab2(sch_1):page84_i57:vdd(3)" )
			)
			( pin "J9M1.226"
				( objectStatus "@baseboard_fab2_lib.baseboard_fab2(sch_1):page84_i57:vdd(4)" )
			)
			( pin "J9M1.223"
				( objectStatus "@baseboard_fab2_lib.baseboard_fab2(sch_1):page84_i57:vdd(5)" )
			)
			( pin "J9M1.220"
				( objectStatus "@baseboard_fab2_lib.baseboard_fab2(sch_1):page84_i57:vdd(6)" )
			)
			( pin "J9M1.217"
				( objectStatus "@baseboard_fab2_lib.baseboard_fab2(sch_1):page84_i57:vdd(7)" )
			)
			( pin "J9M1.215"
				( objectStatus "@baseboard_fab2_lib.baseboard_fab2(sch_1):page84_i57:vdd(8)" )
			)
			( pin "J9M1.212"
				( objectStatus "@baseboard_fab2_lib.baseboard_fab2(sch_1):page84_i57:vdd(9)" )
			)
			( pin "J9M1.209"
				( objectStatus "@baseboard_fab2_lib.baseboard_fab2(sch_1):page84_i57:vdd(10)" )
			)
			( pin "J9M1.206"
				( objectStatus "@baseboard_fab2_lib.baseboard_fab2(sch_1):page84_i57:vdd(11)" )
			)
			( pin "J9M1.204"
				( objectStatus "@baseboard_fab2_lib.baseboard_fab2(sch_1):page84_i57:vdd(12)" )
			)
			( pin "J9M1.92"
				( objectStatus "@baseboard_fab2_lib.baseboard_fab2(sch_1):page84_i57:vdd(13)" )
			)
			( pin "J9M1.90"
				( objectStatus "@baseboard_fab2_lib.baseboard_fab2(sch_1):page84_i57:vdd(14)" )
			)
			( pin "J9M1.88"
				( objectStatus "@baseboard_fab2_lib.baseboard_fab2(sch_1):page84_i57:vdd(15)" )
			)
			( pin "J9M1.85"
				( objectStatus "@baseboard_fab2_lib.baseboard_fab2(sch_1):page84_i57:vdd(16)" )
			)
			( pin "J9M1.83"
				( objectStatus "@baseboard_fab2_lib.baseboard_fab2(sch_1):page84_i57:vdd(17)" )
			)
			( pin "J9M1.80"
				( objectStatus "@baseboard_fab2_lib.baseboard_fab2(sch_1):page84_i57:vdd(18)" )
			)
			( pin "J9M1.76"
				( objectStatus "@baseboard_fab2_lib.baseboard_fab2(sch_1):page84_i57:vdd(19)" )
			)
			( pin "J9M1.73"
				( objectStatus "@baseboard_fab2_lib.baseboard_fab2(sch_1):page84_i57:vdd(20)" )
			)
			( pin "J9M1.70"
				( objectStatus "@baseboard_fab2_lib.baseboard_fab2(sch_1):page84_i57:vdd(21)" )
			)
			( pin "J9M1.67"
				( objectStatus "@baseboard_fab2_lib.baseboard_fab2(sch_1):page84_i57:vdd(22)" )
			)
			( pin "J9M1.64"
				( objectStatus "@baseboard_fab2_lib.baseboard_fab2(sch_1):page84_i57:vdd(23)" )
			)
			( pin "J9M1.61"
				( objectStatus "@baseboard_fab2_lib.baseboard_fab2(sch_1):page84_i57:vdd(24)" )
			)
			( pin "J9M1.59"
				( objectStatus "@baseboard_fab2_lib.baseboard_fab2(sch_1):page84_i57:vdd(25)" )
			)
			( pin "J9M1.287"
				( objectStatus "@baseboard_fab2_lib.baseboard_fab2(sch_1):page84_i57:vpp(0)" )
			)
			( pin "J9M1.286"
				( objectStatus "@baseboard_fab2_lib.baseboard_fab2(sch_1):page84_i57:vpp(1)" )
			)
			( pin "J9M1.288"
				( objectStatus "@baseboard_fab2_lib.baseboard_fab2(sch_1):page84_i57:vpp(2)" )
			)
			( pin "J9M1.143"
				( objectStatus "@baseboard_fab2_lib.baseboard_fab2(sch_1):page84_i57:vpp(3)" )
			)
			( pin "J9M1.142"
				( objectStatus "@baseboard_fab2_lib.baseboard_fab2(sch_1):page84_i57:vpp(4)" )
			)
			( pin "J9M1.221"
				( objectStatus "@baseboard_fab2_lib.baseboard_fab2(sch_1):page84_i57:vtt(0)" )
			)
			( pin "J9M1.77"
				( objectStatus "@baseboard_fab2_lib.baseboard_fab2(sch_1):page84_i57:vtt(1)" )
			)
			( pin "J9M1.152"
				( objectStatus "@baseboard_fab2_lib.baseboard_fab2(sch_1):page84_i102:dqs0n" )
			)
			( pin "J9M1.153"
				( objectStatus "@baseboard_fab2_lib.baseboard_fab2(sch_1):page84_i102:dqs0p" )
			)
			( pin "J9M1.163"
				( objectStatus "@baseboard_fab2_lib.baseboard_fab2(sch_1):page84_i102:dqs1n" )
			)
			( pin "J9M1.164"
				( objectStatus "@baseboard_fab2_lib.baseboard_fab2(sch_1):page84_i102:dqs1p" )
			)
			( pin "J9M1.174"
				( objectStatus "@baseboard_fab2_lib.baseboard_fab2(sch_1):page84_i102:dqs2n" )
			)
			( pin "J9M1.175"
				( objectStatus "@baseboard_fab2_lib.baseboard_fab2(sch_1):page84_i102:dqs2p" )
			)
			( pin "J9M1.185"
				( objectStatus "@baseboard_fab2_lib.baseboard_fab2(sch_1):page84_i102:dqs3n" )
			)
			( pin "J9M1.186"
				( objectStatus "@baseboard_fab2_lib.baseboard_fab2(sch_1):page84_i102:dqs3p" )
			)
			( pin "J9M1.244"
				( objectStatus "@baseboard_fab2_lib.baseboard_fab2(sch_1):page84_i102:dqs4n" )
			)
			( pin "J9M1.245"
				( objectStatus "@baseboard_fab2_lib.baseboard_fab2(sch_1):page84_i102:dqs4p" )
			)
			( pin "J9M1.255"
				( objectStatus "@baseboard_fab2_lib.baseboard_fab2(sch_1):page84_i102:dqs5n" )
			)
			( pin "J9M1.256"
				( objectStatus "@baseboard_fab2_lib.baseboard_fab2(sch_1):page84_i102:dqs5p" )
			)
			( pin "J9M1.266"
				( objectStatus "@baseboard_fab2_lib.baseboard_fab2(sch_1):page84_i102:dqs6n" )
			)
			( pin "J9M1.267"
				( objectStatus "@baseboard_fab2_lib.baseboard_fab2(sch_1):page84_i102:dqs6p" )
			)
			( pin "J9M1.277"
				( objectStatus "@baseboard_fab2_lib.baseboard_fab2(sch_1):page84_i102:dqs7n" )
			)
			( pin "J9M1.278"
				( objectStatus "@baseboard_fab2_lib.baseboard_fab2(sch_1):page84_i102:dqs7p" )
			)
			( pin "J9M1.196"
				( objectStatus "@baseboard_fab2_lib.baseboard_fab2(sch_1):page84_i102:dqs8n" )
			)
			( pin "J9M1.197"
				( objectStatus "@baseboard_fab2_lib.baseboard_fab2(sch_1):page84_i102:dqs8p" )
			)
			( pin "J9M1.8"
				( objectStatus "@baseboard_fab2_lib.baseboard_fab2(sch_1):page84_i102:dqs9n" )
			)
			( pin "J9M1.7"
				( objectStatus "@baseboard_fab2_lib.baseboard_fab2(sch_1):page84_i102:dqs9p" )
			)
			( pin "J9M1.19"
				( objectStatus "@baseboard_fab2_lib.baseboard_fab2(sch_1):page84_i102:dqs10n" )
			)
			( pin "J9M1.18"
				( objectStatus "@baseboard_fab2_lib.baseboard_fab2(sch_1):page84_i102:dqs10p" )
			)
			( pin "J9M1.30"
				( objectStatus "@baseboard_fab2_lib.baseboard_fab2(sch_1):page84_i102:dqs11n" )
			)
			( pin "J9M1.29"
				( objectStatus "@baseboard_fab2_lib.baseboard_fab2(sch_1):page84_i102:dqs11p" )
			)
			( pin "J9M1.41"
				( objectStatus "@baseboard_fab2_lib.baseboard_fab2(sch_1):page84_i102:dqs12n" )
			)
			( pin "J9M1.40"
				( objectStatus "@baseboard_fab2_lib.baseboard_fab2(sch_1):page84_i102:dqs12p" )
			)
			( pin "J9M1.100"
				( objectStatus "@baseboard_fab2_lib.baseboard_fab2(sch_1):page84_i102:dqs13n" )
			)
			( pin "J9M1.99"
				( objectStatus "@baseboard_fab2_lib.baseboard_fab2(sch_1):page84_i102:dqs13p" )
			)
			( pin "J9M1.111"
				( objectStatus "@baseboard_fab2_lib.baseboard_fab2(sch_1):page84_i102:dqs14n" )
			)
			( pin "J9M1.110"
				( objectStatus "@baseboard_fab2_lib.baseboard_fab2(sch_1):page84_i102:dqs14p" )
			)
			( pin "J9M1.122"
				( objectStatus "@baseboard_fab2_lib.baseboard_fab2(sch_1):page84_i102:dqs15n" )
			)
			( pin "J9M1.121"
				( objectStatus "@baseboard_fab2_lib.baseboard_fab2(sch_1):page84_i102:dqs15p" )
			)
			( pin "J9M1.133"
				( objectStatus "@baseboard_fab2_lib.baseboard_fab2(sch_1):page84_i102:dqs16n" )
			)
			( pin "J9M1.132"
				( objectStatus "@baseboard_fab2_lib.baseboard_fab2(sch_1):page84_i102:dqs16p" )
			)
			( pin "J9M1.52"
				( objectStatus "@baseboard_fab2_lib.baseboard_fab2(sch_1):page84_i102:dqs17n" )
			)
			( pin "J9M1.51"
				( objectStatus "@baseboard_fab2_lib.baseboard_fab2(sch_1):page84_i102:dqs17p" )
			)
			( pin "J9M1.283"
				( objectStatus "@baseboard_fab2_lib.baseboard_fab2(sch_1):page84_i138:vss(0)" )
			)
			( pin "J9M1.281"
				( objectStatus "@baseboard_fab2_lib.baseboard_fab2(sch_1):page84_i138:vss(1)" )
			)
			( pin "J9M1.279"
				( objectStatus "@baseboard_fab2_lib.baseboard_fab2(sch_1):page84_i138:vss(2)" )
			)
			( pin "J9M1.276"
				( objectStatus "@baseboard_fab2_lib.baseboard_fab2(sch_1):page84_i138:vss(3)" )
			)
			( pin "J9M1.274"
				( objectStatus "@baseboard_fab2_lib.baseboard_fab2(sch_1):page84_i138:vss(4)" )
			)
			( pin "J9M1.272"
				( objectStatus "@baseboard_fab2_lib.baseboard_fab2(sch_1):page84_i138:vss(5)" )
			)
			( pin "J9M1.270"
				( objectStatus "@baseboard_fab2_lib.baseboard_fab2(sch_1):page84_i138:vss(6)" )
			)
			( pin "J9M1.268"
				( objectStatus "@baseboard_fab2_lib.baseboard_fab2(sch_1):page84_i138:vss(7)" )
			)
			( pin "J9M1.265"
				( objectStatus "@baseboard_fab2_lib.baseboard_fab2(sch_1):page84_i138:vss(8)" )
			)
			( pin "J9M1.263"
				( objectStatus "@baseboard_fab2_lib.baseboard_fab2(sch_1):page84_i138:vss(9)" )
			)
			( pin "J9M1.261"
				( objectStatus "@baseboard_fab2_lib.baseboard_fab2(sch_1):page84_i138:vss(10)" )
			)
			( pin "J9M1.259"
				( objectStatus "@baseboard_fab2_lib.baseboard_fab2(sch_1):page84_i138:vss(11)" )
			)
			( pin "J9M1.257"
				( objectStatus "@baseboard_fab2_lib.baseboard_fab2(sch_1):page84_i138:vss(12)" )
			)
			( pin "J9M1.254"
				( objectStatus "@baseboard_fab2_lib.baseboard_fab2(sch_1):page84_i138:vss(13)" )
			)
			( pin "J9M1.252"
				( objectStatus "@baseboard_fab2_lib.baseboard_fab2(sch_1):page84_i138:vss(14)" )
			)
			( pin "J9M1.250"
				( objectStatus "@baseboard_fab2_lib.baseboard_fab2(sch_1):page84_i138:vss(15)" )
			)
			( pin "J9M1.248"
				( objectStatus "@baseboard_fab2_lib.baseboard_fab2(sch_1):page84_i138:vss(16)" )
			)
			( pin "J9M1.246"
				( objectStatus "@baseboard_fab2_lib.baseboard_fab2(sch_1):page84_i138:vss(17)" )
			)
			( pin "J9M1.243"
				( objectStatus "@baseboard_fab2_lib.baseboard_fab2(sch_1):page84_i138:vss(18)" )
			)
			( pin "J9M1.241"
				( objectStatus "@baseboard_fab2_lib.baseboard_fab2(sch_1):page84_i138:vss(19)" )
			)
			( pin "J9M1.239"
				( objectStatus "@baseboard_fab2_lib.baseboard_fab2(sch_1):page84_i138:vss(20)" )
			)
			( pin "J9M1.202"
				( objectStatus "@baseboard_fab2_lib.baseboard_fab2(sch_1):page84_i138:vss(21)" )
			)
			( pin "J9M1.200"
				( objectStatus "@baseboard_fab2_lib.baseboard_fab2(sch_1):page84_i138:vss(22)" )
			)
			( pin "J9M1.198"
				( objectStatus "@baseboard_fab2_lib.baseboard_fab2(sch_1):page84_i138:vss(23)" )
			)
			( pin "J9M1.195"
				( objectStatus "@baseboard_fab2_lib.baseboard_fab2(sch_1):page84_i138:vss(24)" )
			)
			( pin "J9M1.193"
				( objectStatus "@baseboard_fab2_lib.baseboard_fab2(sch_1):page84_i138:vss(25)" )
			)
			( pin "J9M1.191"
				( objectStatus "@baseboard_fab2_lib.baseboard_fab2(sch_1):page84_i138:vss(26)" )
			)
			( pin "J9M1.189"
				( objectStatus "@baseboard_fab2_lib.baseboard_fab2(sch_1):page84_i138:vss(27)" )
			)
			( pin "J9M1.187"
				( objectStatus "@baseboard_fab2_lib.baseboard_fab2(sch_1):page84_i138:vss(28)" )
			)
			( pin "J9M1.184"
				( objectStatus "@baseboard_fab2_lib.baseboard_fab2(sch_1):page84_i138:vss(29)" )
			)
			( pin "J9M1.182"
				( objectStatus "@baseboard_fab2_lib.baseboard_fab2(sch_1):page84_i138:vss(30)" )
			)
			( pin "J9M1.180"
				( objectStatus "@baseboard_fab2_lib.baseboard_fab2(sch_1):page84_i138:vss(31)" )
			)
			( pin "J9M1.178"
				( objectStatus "@baseboard_fab2_lib.baseboard_fab2(sch_1):page84_i138:vss(32)" )
			)
			( pin "J9M1.176"
				( objectStatus "@baseboard_fab2_lib.baseboard_fab2(sch_1):page84_i138:vss(33)" )
			)
			( pin "J9M1.173"
				( objectStatus "@baseboard_fab2_lib.baseboard_fab2(sch_1):page84_i138:vss(34)" )
			)
			( pin "J9M1.171"
				( objectStatus "@baseboard_fab2_lib.baseboard_fab2(sch_1):page84_i138:vss(35)" )
			)
			( pin "J9M1.169"
				( objectStatus "@baseboard_fab2_lib.baseboard_fab2(sch_1):page84_i138:vss(36)" )
			)
			( pin "J9M1.167"
				( objectStatus "@baseboard_fab2_lib.baseboard_fab2(sch_1):page84_i138:vss(37)" )
			)
			( pin "J9M1.165"
				( objectStatus "@baseboard_fab2_lib.baseboard_fab2(sch_1):page84_i138:vss(38)" )
			)
			( pin "J9M1.162"
				( objectStatus "@baseboard_fab2_lib.baseboard_fab2(sch_1):page84_i138:vss(39)" )
			)
			( pin "J9M1.160"
				( objectStatus "@baseboard_fab2_lib.baseboard_fab2(sch_1):page84_i138:vss(40)" )
			)
			( pin "J9M1.158"
				( objectStatus "@baseboard_fab2_lib.baseboard_fab2(sch_1):page84_i138:vss(41)" )
			)
			( pin "J9M1.156"
				( objectStatus "@baseboard_fab2_lib.baseboard_fab2(sch_1):page84_i138:vss(42)" )
			)
			( pin "J9M1.154"
				( objectStatus "@baseboard_fab2_lib.baseboard_fab2(sch_1):page84_i138:vss(43)" )
			)
			( pin "J9M1.151"
				( objectStatus "@baseboard_fab2_lib.baseboard_fab2(sch_1):page84_i138:vss(44)" )
			)
			( pin "J9M1.149"
				( objectStatus "@baseboard_fab2_lib.baseboard_fab2(sch_1):page84_i138:vss(45)" )
			)
			( pin "J9M1.147"
				( objectStatus "@baseboard_fab2_lib.baseboard_fab2(sch_1):page84_i138:vss(46)" )
			)
			( pin "J9M1.138"
				( objectStatus "@baseboard_fab2_lib.baseboard_fab2(sch_1):page84_i138:vss(47)" )
			)
			( pin "J9M1.136"
				( objectStatus "@baseboard_fab2_lib.baseboard_fab2(sch_1):page84_i138:vss(48)" )
			)
			( pin "J9M1.134"
				( objectStatus "@baseboard_fab2_lib.baseboard_fab2(sch_1):page84_i138:vss(49)" )
			)
			( pin "J9M1.131"
				( objectStatus "@baseboard_fab2_lib.baseboard_fab2(sch_1):page84_i138:vss(50)" )
			)
			( pin "J9M1.129"
				( objectStatus "@baseboard_fab2_lib.baseboard_fab2(sch_1):page84_i138:vss(51)" )
			)
			( pin "J9M1.127"
				( objectStatus "@baseboard_fab2_lib.baseboard_fab2(sch_1):page84_i138:vss(52)" )
			)
			( pin "J9M1.125"
				( objectStatus "@baseboard_fab2_lib.baseboard_fab2(sch_1):page84_i138:vss(53)" )
			)
			( pin "J9M1.123"
				( objectStatus "@baseboard_fab2_lib.baseboard_fab2(sch_1):page84_i138:vss(54)" )
			)
			( pin "J9M1.120"
				( objectStatus "@baseboard_fab2_lib.baseboard_fab2(sch_1):page84_i138:vss(55)" )
			)
			( pin "J9M1.118"
				( objectStatus "@baseboard_fab2_lib.baseboard_fab2(sch_1):page84_i138:vss(56)" )
			)
			( pin "J9M1.116"
				( objectStatus "@baseboard_fab2_lib.baseboard_fab2(sch_1):page84_i138:vss(57)" )
			)
			( pin "J9M1.114"
				( objectStatus "@baseboard_fab2_lib.baseboard_fab2(sch_1):page84_i138:vss(58)" )
			)
			( pin "J9M1.112"
				( objectStatus "@baseboard_fab2_lib.baseboard_fab2(sch_1):page84_i138:vss(59)" )
			)
			( pin "J9M1.109"
				( objectStatus "@baseboard_fab2_lib.baseboard_fab2(sch_1):page84_i138:vss(60)" )
			)
			( pin "J9M1.107"
				( objectStatus "@baseboard_fab2_lib.baseboard_fab2(sch_1):page84_i138:vss(61)" )
			)
			( pin "J9M1.105"
				( objectStatus "@baseboard_fab2_lib.baseboard_fab2(sch_1):page84_i138:vss(62)" )
			)
			( pin "J9M1.103"
				( objectStatus "@baseboard_fab2_lib.baseboard_fab2(sch_1):page84_i138:vss(63)" )
			)
			( pin "J9M1.101"
				( objectStatus "@baseboard_fab2_lib.baseboard_fab2(sch_1):page84_i138:vss(64)" )
			)
			( pin "J9M1.98"
				( objectStatus "@baseboard_fab2_lib.baseboard_fab2(sch_1):page84_i138:vss(65)" )
			)
			( pin "J9M1.96"
				( objectStatus "@baseboard_fab2_lib.baseboard_fab2(sch_1):page84_i138:vss(66)" )
			)
			( pin "J9M1.94"
				( objectStatus "@baseboard_fab2_lib.baseboard_fab2(sch_1):page84_i138:vss(67)" )
			)
			( pin "J9M1.57"
				( objectStatus "@baseboard_fab2_lib.baseboard_fab2(sch_1):page84_i138:vss(68)" )
			)
			( pin "J9M1.55"
				( objectStatus "@baseboard_fab2_lib.baseboard_fab2(sch_1):page84_i138:vss(69)" )
			)
			( pin "J9M1.53"
				( objectStatus "@baseboard_fab2_lib.baseboard_fab2(sch_1):page84_i138:vss(70)" )
			)
			( pin "J9M1.50"
				( objectStatus "@baseboard_fab2_lib.baseboard_fab2(sch_1):page84_i138:vss(71)" )
			)
			( pin "J9M1.48"
				( objectStatus "@baseboard_fab2_lib.baseboard_fab2(sch_1):page84_i138:vss(72)" )
			)
			( pin "J9M1.46"
				( objectStatus "@baseboard_fab2_lib.baseboard_fab2(sch_1):page84_i138:vss(73)" )
			)
			( pin "J9M1.44"
				( objectStatus "@baseboard_fab2_lib.baseboard_fab2(sch_1):page84_i138:vss(74)" )
			)
			( pin "J9M1.42"
				( objectStatus "@baseboard_fab2_lib.baseboard_fab2(sch_1):page84_i138:vss(75)" )
			)
			( pin "J9M1.39"
				( objectStatus "@baseboard_fab2_lib.baseboard_fab2(sch_1):page84_i138:vss(76)" )
			)
			( pin "J9M1.37"
				( objectStatus "@baseboard_fab2_lib.baseboard_fab2(sch_1):page84_i138:vss(77)" )
			)
			( pin "J9M1.35"
				( objectStatus "@baseboard_fab2_lib.baseboard_fab2(sch_1):page84_i138:vss(78)" )
			)
			( pin "J9M1.33"
				( objectStatus "@baseboard_fab2_lib.baseboard_fab2(sch_1):page84_i138:vss(79)" )
			)
			( pin "J9M1.31"
				( objectStatus "@baseboard_fab2_lib.baseboard_fab2(sch_1):page84_i138:vss(80)" )
			)
			( pin "J9M1.28"
				( objectStatus "@baseboard_fab2_lib.baseboard_fab2(sch_1):page84_i138:vss(81)" )
			)
			( pin "J9M1.26"
				( objectStatus "@baseboard_fab2_lib.baseboard_fab2(sch_1):page84_i138:vss(82)" )
			)
			( pin "J9M1.24"
				( objectStatus "@baseboard_fab2_lib.baseboard_fab2(sch_1):page84_i138:vss(83)" )
			)
			( pin "J9M1.22"
				( objectStatus "@baseboard_fab2_lib.baseboard_fab2(sch_1):page84_i138:vss(84)" )
			)
			( pin "J9M1.20"
				( objectStatus "@baseboard_fab2_lib.baseboard_fab2(sch_1):page84_i138:vss(85)" )
			)
			( pin "J9M1.17"
				( objectStatus "@baseboard_fab2_lib.baseboard_fab2(sch_1):page84_i138:vss(86)" )
			)
			( pin "J9M1.15"
				( objectStatus "@baseboard_fab2_lib.baseboard_fab2(sch_1):page84_i138:vss(87)" )
			)
			( pin "J9M1.13"
				( objectStatus "@baseboard_fab2_lib.baseboard_fab2(sch_1):page84_i138:vss(88)" )
			)
			( pin "J9M1.11"
				( objectStatus "@baseboard_fab2_lib.baseboard_fab2(sch_1):page84_i138:vss(89)" )
			)
			( pin "J9M1.9"
				( objectStatus "@baseboard_fab2_lib.baseboard_fab2(sch_1):page84_i138:vss(90)" )
			)
			( pin "J9M1.6"
				( objectStatus "@baseboard_fab2_lib.baseboard_fab2(sch_1):page84_i138:vss(91)" )
			)
			( pin "J9M1.4"
				( objectStatus "@baseboard_fab2_lib.baseboard_fab2(sch_1):page84_i138:vss(92)" )
			)
			( pin "J9M1.2"
				( objectStatus "@baseboard_fab2_lib.baseboard_fab2(sch_1):page84_i138:vss(93)" )
			)
			( pin "J1A2.283"
				( objectStatus "@baseboard_fab2_lib.baseboard_fab2(sch_1):page85_i43:vss(0)" )
			)
			( pin "J1A2.281"
				( objectStatus "@baseboard_fab2_lib.baseboard_fab2(sch_1):page85_i43:vss(1)" )
			)
			( pin "J1A2.279"
				( objectStatus "@baseboard_fab2_lib.baseboard_fab2(sch_1):page85_i43:vss(2)" )
			)
			( pin "J1A2.276"
				( objectStatus "@baseboard_fab2_lib.baseboard_fab2(sch_1):page85_i43:vss(3)" )
			)
			( pin "J1A2.274"
				( objectStatus "@baseboard_fab2_lib.baseboard_fab2(sch_1):page85_i43:vss(4)" )
			)
			( pin "J1A2.272"
				( objectStatus "@baseboard_fab2_lib.baseboard_fab2(sch_1):page85_i43:vss(5)" )
			)
			( pin "J1A2.270"
				( objectStatus "@baseboard_fab2_lib.baseboard_fab2(sch_1):page85_i43:vss(6)" )
			)
			( pin "J1A2.268"
				( objectStatus "@baseboard_fab2_lib.baseboard_fab2(sch_1):page85_i43:vss(7)" )
			)
			( pin "J1A2.265"
				( objectStatus "@baseboard_fab2_lib.baseboard_fab2(sch_1):page85_i43:vss(8)" )
			)
			( pin "J1A2.263"
				( objectStatus "@baseboard_fab2_lib.baseboard_fab2(sch_1):page85_i43:vss(9)" )
			)
			( pin "J1A2.261"
				( objectStatus "@baseboard_fab2_lib.baseboard_fab2(sch_1):page85_i43:vss(10)" )
			)
			( pin "J1A2.259"
				( objectStatus "@baseboard_fab2_lib.baseboard_fab2(sch_1):page85_i43:vss(11)" )
			)
			( pin "J1A2.257"
				( objectStatus "@baseboard_fab2_lib.baseboard_fab2(sch_1):page85_i43:vss(12)" )
			)
			( pin "J1A2.254"
				( objectStatus "@baseboard_fab2_lib.baseboard_fab2(sch_1):page85_i43:vss(13)" )
			)
			( pin "J1A2.252"
				( objectStatus "@baseboard_fab2_lib.baseboard_fab2(sch_1):page85_i43:vss(14)" )
			)
			( pin "J1A2.250"
				( objectStatus "@baseboard_fab2_lib.baseboard_fab2(sch_1):page85_i43:vss(15)" )
			)
			( pin "J1A2.248"
				( objectStatus "@baseboard_fab2_lib.baseboard_fab2(sch_1):page85_i43:vss(16)" )
			)
			( pin "J1A2.246"
				( objectStatus "@baseboard_fab2_lib.baseboard_fab2(sch_1):page85_i43:vss(17)" )
			)
			( pin "J1A2.243"
				( objectStatus "@baseboard_fab2_lib.baseboard_fab2(sch_1):page85_i43:vss(18)" )
			)
			( pin "J1A2.241"
				( objectStatus "@baseboard_fab2_lib.baseboard_fab2(sch_1):page85_i43:vss(19)" )
			)
			( pin "J1A2.239"
				( objectStatus "@baseboard_fab2_lib.baseboard_fab2(sch_1):page85_i43:vss(20)" )
			)
			( pin "J1A2.202"
				( objectStatus "@baseboard_fab2_lib.baseboard_fab2(sch_1):page85_i43:vss(21)" )
			)
			( pin "J1A2.200"
				( objectStatus "@baseboard_fab2_lib.baseboard_fab2(sch_1):page85_i43:vss(22)" )
			)
			( pin "J1A2.198"
				( objectStatus "@baseboard_fab2_lib.baseboard_fab2(sch_1):page85_i43:vss(23)" )
			)
			( pin "J1A2.195"
				( objectStatus "@baseboard_fab2_lib.baseboard_fab2(sch_1):page85_i43:vss(24)" )
			)
			( pin "J1A2.193"
				( objectStatus "@baseboard_fab2_lib.baseboard_fab2(sch_1):page85_i43:vss(25)" )
			)
			( pin "J1A2.191"
				( objectStatus "@baseboard_fab2_lib.baseboard_fab2(sch_1):page85_i43:vss(26)" )
			)
			( pin "J1A2.189"
				( objectStatus "@baseboard_fab2_lib.baseboard_fab2(sch_1):page85_i43:vss(27)" )
			)
			( pin "J1A2.187"
				( objectStatus "@baseboard_fab2_lib.baseboard_fab2(sch_1):page85_i43:vss(28)" )
			)
			( pin "J1A2.184"
				( objectStatus "@baseboard_fab2_lib.baseboard_fab2(sch_1):page85_i43:vss(29)" )
			)
			( pin "J1A2.182"
				( objectStatus "@baseboard_fab2_lib.baseboard_fab2(sch_1):page85_i43:vss(30)" )
			)
			( pin "J1A2.180"
				( objectStatus "@baseboard_fab2_lib.baseboard_fab2(sch_1):page85_i43:vss(31)" )
			)
			( pin "J1A2.178"
				( objectStatus "@baseboard_fab2_lib.baseboard_fab2(sch_1):page85_i43:vss(32)" )
			)
			( pin "J1A2.176"
				( objectStatus "@baseboard_fab2_lib.baseboard_fab2(sch_1):page85_i43:vss(33)" )
			)
			( pin "J1A2.173"
				( objectStatus "@baseboard_fab2_lib.baseboard_fab2(sch_1):page85_i43:vss(34)" )
			)
			( pin "J1A2.171"
				( objectStatus "@baseboard_fab2_lib.baseboard_fab2(sch_1):page85_i43:vss(35)" )
			)
			( pin "J1A2.169"
				( objectStatus "@baseboard_fab2_lib.baseboard_fab2(sch_1):page85_i43:vss(36)" )
			)
			( pin "J1A2.167"
				( objectStatus "@baseboard_fab2_lib.baseboard_fab2(sch_1):page85_i43:vss(37)" )
			)
			( pin "J1A2.165"
				( objectStatus "@baseboard_fab2_lib.baseboard_fab2(sch_1):page85_i43:vss(38)" )
			)
			( pin "J1A2.162"
				( objectStatus "@baseboard_fab2_lib.baseboard_fab2(sch_1):page85_i43:vss(39)" )
			)
			( pin "J1A2.160"
				( objectStatus "@baseboard_fab2_lib.baseboard_fab2(sch_1):page85_i43:vss(40)" )
			)
			( pin "J1A2.158"
				( objectStatus "@baseboard_fab2_lib.baseboard_fab2(sch_1):page85_i43:vss(41)" )
			)
			( pin "J1A2.156"
				( objectStatus "@baseboard_fab2_lib.baseboard_fab2(sch_1):page85_i43:vss(42)" )
			)
			( pin "J1A2.154"
				( objectStatus "@baseboard_fab2_lib.baseboard_fab2(sch_1):page85_i43:vss(43)" )
			)
			( pin "J1A2.151"
				( objectStatus "@baseboard_fab2_lib.baseboard_fab2(sch_1):page85_i43:vss(44)" )
			)
			( pin "J1A2.149"
				( objectStatus "@baseboard_fab2_lib.baseboard_fab2(sch_1):page85_i43:vss(45)" )
			)
			( pin "J1A2.147"
				( objectStatus "@baseboard_fab2_lib.baseboard_fab2(sch_1):page85_i43:vss(46)" )
			)
			( pin "J1A2.138"
				( objectStatus "@baseboard_fab2_lib.baseboard_fab2(sch_1):page85_i43:vss(47)" )
			)
			( pin "J1A2.136"
				( objectStatus "@baseboard_fab2_lib.baseboard_fab2(sch_1):page85_i43:vss(48)" )
			)
			( pin "J1A2.134"
				( objectStatus "@baseboard_fab2_lib.baseboard_fab2(sch_1):page85_i43:vss(49)" )
			)
			( pin "J1A2.131"
				( objectStatus "@baseboard_fab2_lib.baseboard_fab2(sch_1):page85_i43:vss(50)" )
			)
			( pin "J1A2.129"
				( objectStatus "@baseboard_fab2_lib.baseboard_fab2(sch_1):page85_i43:vss(51)" )
			)
			( pin "J1A2.127"
				( objectStatus "@baseboard_fab2_lib.baseboard_fab2(sch_1):page85_i43:vss(52)" )
			)
			( pin "J1A2.125"
				( objectStatus "@baseboard_fab2_lib.baseboard_fab2(sch_1):page85_i43:vss(53)" )
			)
			( pin "J1A2.123"
				( objectStatus "@baseboard_fab2_lib.baseboard_fab2(sch_1):page85_i43:vss(54)" )
			)
			( pin "J1A2.120"
				( objectStatus "@baseboard_fab2_lib.baseboard_fab2(sch_1):page85_i43:vss(55)" )
			)
			( pin "J1A2.118"
				( objectStatus "@baseboard_fab2_lib.baseboard_fab2(sch_1):page85_i43:vss(56)" )
			)
			( pin "J1A2.116"
				( objectStatus "@baseboard_fab2_lib.baseboard_fab2(sch_1):page85_i43:vss(57)" )
			)
			( pin "J1A2.114"
				( objectStatus "@baseboard_fab2_lib.baseboard_fab2(sch_1):page85_i43:vss(58)" )
			)
			( pin "J1A2.112"
				( objectStatus "@baseboard_fab2_lib.baseboard_fab2(sch_1):page85_i43:vss(59)" )
			)
			( pin "J1A2.109"
				( objectStatus "@baseboard_fab2_lib.baseboard_fab2(sch_1):page85_i43:vss(60)" )
			)
			( pin "J1A2.107"
				( objectStatus "@baseboard_fab2_lib.baseboard_fab2(sch_1):page85_i43:vss(61)" )
			)
			( pin "J1A2.105"
				( objectStatus "@baseboard_fab2_lib.baseboard_fab2(sch_1):page85_i43:vss(62)" )
			)
			( pin "J1A2.103"
				( objectStatus "@baseboard_fab2_lib.baseboard_fab2(sch_1):page85_i43:vss(63)" )
			)
			( pin "J1A2.101"
				( objectStatus "@baseboard_fab2_lib.baseboard_fab2(sch_1):page85_i43:vss(64)" )
			)
			( pin "J1A2.98"
				( objectStatus "@baseboard_fab2_lib.baseboard_fab2(sch_1):page85_i43:vss(65)" )
			)
			( pin "J1A2.96"
				( objectStatus "@baseboard_fab2_lib.baseboard_fab2(sch_1):page85_i43:vss(66)" )
			)
			( pin "J1A2.94"
				( objectStatus "@baseboard_fab2_lib.baseboard_fab2(sch_1):page85_i43:vss(67)" )
			)
			( pin "J1A2.57"
				( objectStatus "@baseboard_fab2_lib.baseboard_fab2(sch_1):page85_i43:vss(68)" )
			)
			( pin "J1A2.55"
				( objectStatus "@baseboard_fab2_lib.baseboard_fab2(sch_1):page85_i43:vss(69)" )
			)
			( pin "J1A2.53"
				( objectStatus "@baseboard_fab2_lib.baseboard_fab2(sch_1):page85_i43:vss(70)" )
			)
			( pin "J1A2.50"
				( objectStatus "@baseboard_fab2_lib.baseboard_fab2(sch_1):page85_i43:vss(71)" )
			)
			( pin "J1A2.48"
				( objectStatus "@baseboard_fab2_lib.baseboard_fab2(sch_1):page85_i43:vss(72)" )
			)
			( pin "J1A2.46"
				( objectStatus "@baseboard_fab2_lib.baseboard_fab2(sch_1):page85_i43:vss(73)" )
			)
			( pin "J1A2.44"
				( objectStatus "@baseboard_fab2_lib.baseboard_fab2(sch_1):page85_i43:vss(74)" )
			)
			( pin "J1A2.42"
				( objectStatus "@baseboard_fab2_lib.baseboard_fab2(sch_1):page85_i43:vss(75)" )
			)
			( pin "J1A2.39"
				( objectStatus "@baseboard_fab2_lib.baseboard_fab2(sch_1):page85_i43:vss(76)" )
			)
			( pin "J1A2.37"
				( objectStatus "@baseboard_fab2_lib.baseboard_fab2(sch_1):page85_i43:vss(77)" )
			)
			( pin "J1A2.35"
				( objectStatus "@baseboard_fab2_lib.baseboard_fab2(sch_1):page85_i43:vss(78)" )
			)
			( pin "J1A2.33"
				( objectStatus "@baseboard_fab2_lib.baseboard_fab2(sch_1):page85_i43:vss(79)" )
			)
			( pin "J1A2.31"
				( objectStatus "@baseboard_fab2_lib.baseboard_fab2(sch_1):page85_i43:vss(80)" )
			)
			( pin "J1A2.28"
				( objectStatus "@baseboard_fab2_lib.baseboard_fab2(sch_1):page85_i43:vss(81)" )
			)
			( pin "J1A2.26"
				( objectStatus "@baseboard_fab2_lib.baseboard_fab2(sch_1):page85_i43:vss(82)" )
			)
			( pin "J1A2.24"
				( objectStatus "@baseboard_fab2_lib.baseboard_fab2(sch_1):page85_i43:vss(83)" )
			)
			( pin "J1A2.22"
				( objectStatus "@baseboard_fab2_lib.baseboard_fab2(sch_1):page85_i43:vss(84)" )
			)
			( pin "J1A2.20"
				( objectStatus "@baseboard_fab2_lib.baseboard_fab2(sch_1):page85_i43:vss(85)" )
			)
			( pin "J1A2.17"
				( objectStatus "@baseboard_fab2_lib.baseboard_fab2(sch_1):page85_i43:vss(86)" )
			)
			( pin "J1A2.15"
				( objectStatus "@baseboard_fab2_lib.baseboard_fab2(sch_1):page85_i43:vss(87)" )
			)
			( pin "J1A2.13"
				( objectStatus "@baseboard_fab2_lib.baseboard_fab2(sch_1):page85_i43:vss(88)" )
			)
			( pin "J1A2.11"
				( objectStatus "@baseboard_fab2_lib.baseboard_fab2(sch_1):page85_i43:vss(89)" )
			)
			( pin "J1A2.9"
				( objectStatus "@baseboard_fab2_lib.baseboard_fab2(sch_1):page85_i43:vss(90)" )
			)
			( pin "J1A2.6"
				( objectStatus "@baseboard_fab2_lib.baseboard_fab2(sch_1):page85_i43:vss(91)" )
			)
			( pin "J1A2.4"
				( objectStatus "@baseboard_fab2_lib.baseboard_fab2(sch_1):page85_i43:vss(92)" )
			)
			( pin "J1A2.2"
				( objectStatus "@baseboard_fab2_lib.baseboard_fab2(sch_1):page85_i43:vss(93)" )
			)
			( pin "J1A2.152"
				( objectStatus "@baseboard_fab2_lib.baseboard_fab2(sch_1):page85_i66:dqs0n" )
			)
			( pin "J1A2.153"
				( objectStatus "@baseboard_fab2_lib.baseboard_fab2(sch_1):page85_i66:dqs0p" )
			)
			( pin "J1A2.163"
				( objectStatus "@baseboard_fab2_lib.baseboard_fab2(sch_1):page85_i66:dqs1n" )
			)
			( pin "J1A2.164"
				( objectStatus "@baseboard_fab2_lib.baseboard_fab2(sch_1):page85_i66:dqs1p" )
			)
			( pin "J1A2.174"
				( objectStatus "@baseboard_fab2_lib.baseboard_fab2(sch_1):page85_i66:dqs2n" )
			)
			( pin "J1A2.175"
				( objectStatus "@baseboard_fab2_lib.baseboard_fab2(sch_1):page85_i66:dqs2p" )
			)
			( pin "J1A2.185"
				( objectStatus "@baseboard_fab2_lib.baseboard_fab2(sch_1):page85_i66:dqs3n" )
			)
			( pin "J1A2.186"
				( objectStatus "@baseboard_fab2_lib.baseboard_fab2(sch_1):page85_i66:dqs3p" )
			)
			( pin "J1A2.244"
				( objectStatus "@baseboard_fab2_lib.baseboard_fab2(sch_1):page85_i66:dqs4n" )
			)
			( pin "J1A2.245"
				( objectStatus "@baseboard_fab2_lib.baseboard_fab2(sch_1):page85_i66:dqs4p" )
			)
			( pin "J1A2.255"
				( objectStatus "@baseboard_fab2_lib.baseboard_fab2(sch_1):page85_i66:dqs5n" )
			)
			( pin "J1A2.256"
				( objectStatus "@baseboard_fab2_lib.baseboard_fab2(sch_1):page85_i66:dqs5p" )
			)
			( pin "J1A2.266"
				( objectStatus "@baseboard_fab2_lib.baseboard_fab2(sch_1):page85_i66:dqs6n" )
			)
			( pin "J1A2.267"
				( objectStatus "@baseboard_fab2_lib.baseboard_fab2(sch_1):page85_i66:dqs6p" )
			)
			( pin "J1A2.277"
				( objectStatus "@baseboard_fab2_lib.baseboard_fab2(sch_1):page85_i66:dqs7n" )
			)
			( pin "J1A2.278"
				( objectStatus "@baseboard_fab2_lib.baseboard_fab2(sch_1):page85_i66:dqs7p" )
			)
			( pin "J1A2.196"
				( objectStatus "@baseboard_fab2_lib.baseboard_fab2(sch_1):page85_i66:dqs8n" )
			)
			( pin "J1A2.197"
				( objectStatus "@baseboard_fab2_lib.baseboard_fab2(sch_1):page85_i66:dqs8p" )
			)
			( pin "J1A2.8"
				( objectStatus "@baseboard_fab2_lib.baseboard_fab2(sch_1):page85_i66:dqs9n" )
			)
			( pin "J1A2.7"
				( objectStatus "@baseboard_fab2_lib.baseboard_fab2(sch_1):page85_i66:dqs9p" )
			)
			( pin "J1A2.19"
				( objectStatus "@baseboard_fab2_lib.baseboard_fab2(sch_1):page85_i66:dqs10n" )
			)
			( pin "J1A2.18"
				( objectStatus "@baseboard_fab2_lib.baseboard_fab2(sch_1):page85_i66:dqs10p" )
			)
			( pin "J1A2.30"
				( objectStatus "@baseboard_fab2_lib.baseboard_fab2(sch_1):page85_i66:dqs11n" )
			)
			( pin "J1A2.29"
				( objectStatus "@baseboard_fab2_lib.baseboard_fab2(sch_1):page85_i66:dqs11p" )
			)
			( pin "J1A2.41"
				( objectStatus "@baseboard_fab2_lib.baseboard_fab2(sch_1):page85_i66:dqs12n" )
			)
			( pin "J1A2.40"
				( objectStatus "@baseboard_fab2_lib.baseboard_fab2(sch_1):page85_i66:dqs12p" )
			)
			( pin "J1A2.100"
				( objectStatus "@baseboard_fab2_lib.baseboard_fab2(sch_1):page85_i66:dqs13n" )
			)
			( pin "J1A2.99"
				( objectStatus "@baseboard_fab2_lib.baseboard_fab2(sch_1):page85_i66:dqs13p" )
			)
			( pin "J1A2.111"
				( objectStatus "@baseboard_fab2_lib.baseboard_fab2(sch_1):page85_i66:dqs14n" )
			)
			( pin "J1A2.110"
				( objectStatus "@baseboard_fab2_lib.baseboard_fab2(sch_1):page85_i66:dqs14p" )
			)
			( pin "J1A2.122"
				( objectStatus "@baseboard_fab2_lib.baseboard_fab2(sch_1):page85_i66:dqs15n" )
			)
			( pin "J1A2.121"
				( objectStatus "@baseboard_fab2_lib.baseboard_fab2(sch_1):page85_i66:dqs15p" )
			)
			( pin "J1A2.133"
				( objectStatus "@baseboard_fab2_lib.baseboard_fab2(sch_1):page85_i66:dqs16n" )
			)
			( pin "J1A2.132"
				( objectStatus "@baseboard_fab2_lib.baseboard_fab2(sch_1):page85_i66:dqs16p" )
			)
			( pin "J1A2.52"
				( objectStatus "@baseboard_fab2_lib.baseboard_fab2(sch_1):page85_i66:dqs17n" )
			)
			( pin "J1A2.51"
				( objectStatus "@baseboard_fab2_lib.baseboard_fab2(sch_1):page85_i66:dqs17p" )
			)
			( pin "J1A2.79"
				( objectStatus "@baseboard_fab2_lib.baseboard_fab2(sch_1):page85_i111:a0" )
			)
			( pin "J1A2.72"
				( objectStatus "@baseboard_fab2_lib.baseboard_fab2(sch_1):page85_i111:a1" )
			)
			( pin "J1A2.216"
				( objectStatus "@baseboard_fab2_lib.baseboard_fab2(sch_1):page85_i111:a2" )
			)
			( pin "J1A2.71"
				( objectStatus "@baseboard_fab2_lib.baseboard_fab2(sch_1):page85_i111:a3" )
			)
			( pin "J1A2.214"
				( objectStatus "@baseboard_fab2_lib.baseboard_fab2(sch_1):page85_i111:a4" )
			)
			( pin "J1A2.213"
				( objectStatus "@baseboard_fab2_lib.baseboard_fab2(sch_1):page85_i111:a5" )
			)
			( pin "J1A2.69"
				( objectStatus "@baseboard_fab2_lib.baseboard_fab2(sch_1):page85_i111:a6" )
			)
			( pin "J1A2.211"
				( objectStatus "@baseboard_fab2_lib.baseboard_fab2(sch_1):page85_i111:a7" )
			)
			( pin "J1A2.68"
				( objectStatus "@baseboard_fab2_lib.baseboard_fab2(sch_1):page85_i111:a8" )
			)
			( pin "J1A2.66"
				( objectStatus "@baseboard_fab2_lib.baseboard_fab2(sch_1):page85_i111:a9" )
			)
			( pin "J1A2.225"
				( objectStatus "@baseboard_fab2_lib.baseboard_fab2(sch_1):page85_i111:a10" )
			)
			( pin "J1A2.210"
				( objectStatus "@baseboard_fab2_lib.baseboard_fab2(sch_1):page85_i111:a11" )
			)
			( pin "J1A2.65"
				( objectStatus "@baseboard_fab2_lib.baseboard_fab2(sch_1):page85_i111:a12" )
			)
			( pin "J1A2.232"
				( objectStatus "@baseboard_fab2_lib.baseboard_fab2(sch_1):page85_i111:a13" )
			)
			( pin "J1A2.228"
				( objectStatus "@baseboard_fab2_lib.baseboard_fab2(sch_1):page85_i111:a14_we_n" )
			)
			( pin "J1A2.86"
				( objectStatus "@baseboard_fab2_lib.baseboard_fab2(sch_1):page85_i111:a15_cas_n" )
			)
			( pin "J1A2.82"
				( objectStatus "@baseboard_fab2_lib.baseboard_fab2(sch_1):page85_i111:a16_ras_n" )
			)
			( pin "J1A2.234"
				( objectStatus "@baseboard_fab2_lib.baseboard_fab2(sch_1):page85_i111:a17" )
			)
			( pin "J1A2.62"
				( objectStatus "@baseboard_fab2_lib.baseboard_fab2(sch_1):page85_i111:act_n" )
			)
			( pin "J1A2.208"
				( objectStatus "@baseboard_fab2_lib.baseboard_fab2(sch_1):page85_i111:alert_n" )
			)
			( pin "J1A2.81"
				( objectStatus "@baseboard_fab2_lib.baseboard_fab2(sch_1):page85_i111:ba(0)" )
			)
			( pin "J1A2.224"
				( objectStatus "@baseboard_fab2_lib.baseboard_fab2(sch_1):page85_i111:ba(1)" )
			)
			( pin "J1A2.63"
				( objectStatus "@baseboard_fab2_lib.baseboard_fab2(sch_1):page85_i111:bg(0)" )
			)
			( pin "J1A2.207"
				( objectStatus "@baseboard_fab2_lib.baseboard_fab2(sch_1):page85_i111:bg(1)" )
			)
			( pin "J1A2.235"
				( objectStatus "@baseboard_fab2_lib.baseboard_fab2(sch_1):page85_i111:c(2)" )
			)
			( pin "J1A2.49"
				( objectStatus "@baseboard_fab2_lib.baseboard_fab2(sch_1):page85_i111:cb(0)" )
			)
			( pin "J1A2.194"
				( objectStatus "@baseboard_fab2_lib.baseboard_fab2(sch_1):page85_i111:cb(1)" )
			)
			( pin "J1A2.56"
				( objectStatus "@baseboard_fab2_lib.baseboard_fab2(sch_1):page85_i111:cb(2)" )
			)
			( pin "J1A2.201"
				( objectStatus "@baseboard_fab2_lib.baseboard_fab2(sch_1):page85_i111:cb(3)" )
			)
			( pin "J1A2.47"
				( objectStatus "@baseboard_fab2_lib.baseboard_fab2(sch_1):page85_i111:cb(4)" )
			)
			( pin "J1A2.192"
				( objectStatus "@baseboard_fab2_lib.baseboard_fab2(sch_1):page85_i111:cb(5)" )
			)
			( pin "J1A2.54"
				( objectStatus "@baseboard_fab2_lib.baseboard_fab2(sch_1):page85_i111:cb(6)" )
			)
			( pin "J1A2.199"
				( objectStatus "@baseboard_fab2_lib.baseboard_fab2(sch_1):page85_i111:cb(7)" )
			)
			( pin "J1A2.75"
				( objectStatus "@baseboard_fab2_lib.baseboard_fab2(sch_1):page85_i111:ck0n" )
			)
			( pin "J1A2.74"
				( objectStatus "@baseboard_fab2_lib.baseboard_fab2(sch_1):page85_i111:ck0p" )
			)
			( pin "J1A2.219"
				( objectStatus "@baseboard_fab2_lib.baseboard_fab2(sch_1):page85_i111:ck1n" )
			)
			( pin "J1A2.218"
				( objectStatus "@baseboard_fab2_lib.baseboard_fab2(sch_1):page85_i111:ck1p" )
			)
			( pin "J1A2.60"
				( objectStatus "@baseboard_fab2_lib.baseboard_fab2(sch_1):page85_i111:cke(0)" )
			)
			( pin "J1A2.203"
				( objectStatus "@baseboard_fab2_lib.baseboard_fab2(sch_1):page85_i111:cke(1)" )
			)
			( pin "J1A2.5"
				( objectStatus "@baseboard_fab2_lib.baseboard_fab2(sch_1):page85_i111:dq(0)" )
			)
			( pin "J1A2.150"
				( objectStatus "@baseboard_fab2_lib.baseboard_fab2(sch_1):page85_i111:dq(1)" )
			)
			( pin "J1A2.12"
				( objectStatus "@baseboard_fab2_lib.baseboard_fab2(sch_1):page85_i111:dq(2)" )
			)
			( pin "J1A2.157"
				( objectStatus "@baseboard_fab2_lib.baseboard_fab2(sch_1):page85_i111:dq(3)" )
			)
			( pin "J1A2.3"
				( objectStatus "@baseboard_fab2_lib.baseboard_fab2(sch_1):page85_i111:dq(4)" )
			)
			( pin "J1A2.148"
				( objectStatus "@baseboard_fab2_lib.baseboard_fab2(sch_1):page85_i111:dq(5)" )
			)
			( pin "J1A2.10"
				( objectStatus "@baseboard_fab2_lib.baseboard_fab2(sch_1):page85_i111:dq(6)" )
			)
			( pin "J1A2.155"
				( objectStatus "@baseboard_fab2_lib.baseboard_fab2(sch_1):page85_i111:dq(7)" )
			)
			( pin "J1A2.16"
				( objectStatus "@baseboard_fab2_lib.baseboard_fab2(sch_1):page85_i111:dq(8)" )
			)
			( pin "J1A2.161"
				( objectStatus "@baseboard_fab2_lib.baseboard_fab2(sch_1):page85_i111:dq(9)" )
			)
			( pin "J1A2.23"
				( objectStatus "@baseboard_fab2_lib.baseboard_fab2(sch_1):page85_i111:dq(10)" )
			)
			( pin "J1A2.168"
				( objectStatus "@baseboard_fab2_lib.baseboard_fab2(sch_1):page85_i111:dq(11)" )
			)
			( pin "J1A2.14"
				( objectStatus "@baseboard_fab2_lib.baseboard_fab2(sch_1):page85_i111:dq(12)" )
			)
			( pin "J1A2.159"
				( objectStatus "@baseboard_fab2_lib.baseboard_fab2(sch_1):page85_i111:dq(13)" )
			)
			( pin "J1A2.21"
				( objectStatus "@baseboard_fab2_lib.baseboard_fab2(sch_1):page85_i111:dq(14)" )
			)
			( pin "J1A2.166"
				( objectStatus "@baseboard_fab2_lib.baseboard_fab2(sch_1):page85_i111:dq(15)" )
			)
			( pin "J1A2.27"
				( objectStatus "@baseboard_fab2_lib.baseboard_fab2(sch_1):page85_i111:dq(16)" )
			)
			( pin "J1A2.172"
				( objectStatus "@baseboard_fab2_lib.baseboard_fab2(sch_1):page85_i111:dq(17)" )
			)
			( pin "J1A2.34"
				( objectStatus "@baseboard_fab2_lib.baseboard_fab2(sch_1):page85_i111:dq(18)" )
			)
			( pin "J1A2.179"
				( objectStatus "@baseboard_fab2_lib.baseboard_fab2(sch_1):page85_i111:dq(19)" )
			)
			( pin "J1A2.25"
				( objectStatus "@baseboard_fab2_lib.baseboard_fab2(sch_1):page85_i111:dq(20)" )
			)
			( pin "J1A2.170"
				( objectStatus "@baseboard_fab2_lib.baseboard_fab2(sch_1):page85_i111:dq(21)" )
			)
			( pin "J1A2.32"
				( objectStatus "@baseboard_fab2_lib.baseboard_fab2(sch_1):page85_i111:dq(22)" )
			)
			( pin "J1A2.177"
				( objectStatus "@baseboard_fab2_lib.baseboard_fab2(sch_1):page85_i111:dq(23)" )
			)
			( pin "J1A2.38"
				( objectStatus "@baseboard_fab2_lib.baseboard_fab2(sch_1):page85_i111:dq(24)" )
			)
			( pin "J1A2.183"
				( objectStatus "@baseboard_fab2_lib.baseboard_fab2(sch_1):page85_i111:dq(25)" )
			)
			( pin "J1A2.45"
				( objectStatus "@baseboard_fab2_lib.baseboard_fab2(sch_1):page85_i111:dq(26)" )
			)
			( pin "J1A2.190"
				( objectStatus "@baseboard_fab2_lib.baseboard_fab2(sch_1):page85_i111:dq(27)" )
			)
			( pin "J1A2.36"
				( objectStatus "@baseboard_fab2_lib.baseboard_fab2(sch_1):page85_i111:dq(28)" )
			)
			( pin "J1A2.181"
				( objectStatus "@baseboard_fab2_lib.baseboard_fab2(sch_1):page85_i111:dq(29)" )
			)
			( pin "J1A2.43"
				( objectStatus "@baseboard_fab2_lib.baseboard_fab2(sch_1):page85_i111:dq(30)" )
			)
			( pin "J1A2.188"
				( objectStatus "@baseboard_fab2_lib.baseboard_fab2(sch_1):page85_i111:dq(31)" )
			)
			( pin "J1A2.97"
				( objectStatus "@baseboard_fab2_lib.baseboard_fab2(sch_1):page85_i111:dq(32)" )
			)
			( pin "J1A2.242"
				( objectStatus "@baseboard_fab2_lib.baseboard_fab2(sch_1):page85_i111:dq(33)" )
			)
			( pin "J1A2.104"
				( objectStatus "@baseboard_fab2_lib.baseboard_fab2(sch_1):page85_i111:dq(34)" )
			)
			( pin "J1A2.249"
				( objectStatus "@baseboard_fab2_lib.baseboard_fab2(sch_1):page85_i111:dq(35)" )
			)
			( pin "J1A2.95"
				( objectStatus "@baseboard_fab2_lib.baseboard_fab2(sch_1):page85_i111:dq(36)" )
			)
			( pin "J1A2.240"
				( objectStatus "@baseboard_fab2_lib.baseboard_fab2(sch_1):page85_i111:dq(37)" )
			)
			( pin "J1A2.102"
				( objectStatus "@baseboard_fab2_lib.baseboard_fab2(sch_1):page85_i111:dq(38)" )
			)
			( pin "J1A2.247"
				( objectStatus "@baseboard_fab2_lib.baseboard_fab2(sch_1):page85_i111:dq(39)" )
			)
			( pin "J1A2.108"
				( objectStatus "@baseboard_fab2_lib.baseboard_fab2(sch_1):page85_i111:dq(40)" )
			)
			( pin "J1A2.253"
				( objectStatus "@baseboard_fab2_lib.baseboard_fab2(sch_1):page85_i111:dq(41)" )
			)
			( pin "J1A2.115"
				( objectStatus "@baseboard_fab2_lib.baseboard_fab2(sch_1):page85_i111:dq(42)" )
			)
			( pin "J1A2.260"
				( objectStatus "@baseboard_fab2_lib.baseboard_fab2(sch_1):page85_i111:dq(43)" )
			)
			( pin "J1A2.106"
				( objectStatus "@baseboard_fab2_lib.baseboard_fab2(sch_1):page85_i111:dq(44)" )
			)
			( pin "J1A2.251"
				( objectStatus "@baseboard_fab2_lib.baseboard_fab2(sch_1):page85_i111:dq(45)" )
			)
			( pin "J1A2.113"
				( objectStatus "@baseboard_fab2_lib.baseboard_fab2(sch_1):page85_i111:dq(46)" )
			)
			( pin "J1A2.258"
				( objectStatus "@baseboard_fab2_lib.baseboard_fab2(sch_1):page85_i111:dq(47)" )
			)
			( pin "J1A2.119"
				( objectStatus "@baseboard_fab2_lib.baseboard_fab2(sch_1):page85_i111:dq(48)" )
			)
			( pin "J1A2.264"
				( objectStatus "@baseboard_fab2_lib.baseboard_fab2(sch_1):page85_i111:dq(49)" )
			)
			( pin "J1A2.126"
				( objectStatus "@baseboard_fab2_lib.baseboard_fab2(sch_1):page85_i111:dq(50)" )
			)
			( pin "J1A2.271"
				( objectStatus "@baseboard_fab2_lib.baseboard_fab2(sch_1):page85_i111:dq(51)" )
			)
			( pin "J1A2.117"
				( objectStatus "@baseboard_fab2_lib.baseboard_fab2(sch_1):page85_i111:dq(52)" )
			)
			( pin "J1A2.262"
				( objectStatus "@baseboard_fab2_lib.baseboard_fab2(sch_1):page85_i111:dq(53)" )
			)
			( pin "J1A2.124"
				( objectStatus "@baseboard_fab2_lib.baseboard_fab2(sch_1):page85_i111:dq(54)" )
			)
			( pin "J1A2.269"
				( objectStatus "@baseboard_fab2_lib.baseboard_fab2(sch_1):page85_i111:dq(55)" )
			)
			( pin "J1A2.130"
				( objectStatus "@baseboard_fab2_lib.baseboard_fab2(sch_1):page85_i111:dq(56)" )
			)
			( pin "J1A2.275"
				( objectStatus "@baseboard_fab2_lib.baseboard_fab2(sch_1):page85_i111:dq(57)" )
			)
			( pin "J1A2.137"
				( objectStatus "@baseboard_fab2_lib.baseboard_fab2(sch_1):page85_i111:dq(58)" )
			)
			( pin "J1A2.282"
				( objectStatus "@baseboard_fab2_lib.baseboard_fab2(sch_1):page85_i111:dq(59)" )
			)
			( pin "J1A2.128"
				( objectStatus "@baseboard_fab2_lib.baseboard_fab2(sch_1):page85_i111:dq(60)" )
			)
			( pin "J1A2.273"
				( objectStatus "@baseboard_fab2_lib.baseboard_fab2(sch_1):page85_i111:dq(61)" )
			)
			( pin "J1A2.135"
				( objectStatus "@baseboard_fab2_lib.baseboard_fab2(sch_1):page85_i111:dq(62)" )
			)
			( pin "J1A2.280"
				( objectStatus "@baseboard_fab2_lib.baseboard_fab2(sch_1):page85_i111:dq(63)" )
			)
			( pin "J1A2.78"
				( objectStatus "@baseboard_fab2_lib.baseboard_fab2(sch_1):page85_i111:event_n" )
			)
			( pin "J1A2.87"
				( objectStatus "@baseboard_fab2_lib.baseboard_fab2(sch_1):page85_i111:odt(0)" )
			)
			( pin "J1A2.91"
				( objectStatus "@baseboard_fab2_lib.baseboard_fab2(sch_1):page85_i111:odt(1)" )
			)
			( pin "J1A2.222"
				( objectStatus "@baseboard_fab2_lib.baseboard_fab2(sch_1):page85_i111:par" )
			)
			( pin "J1A2.58"
				( objectStatus "@baseboard_fab2_lib.baseboard_fab2(sch_1):page85_i111:reset_n" )
			)
			( pin "J1A2.205"
				( objectStatus "@baseboard_fab2_lib.baseboard_fab2(sch_1):page85_i111:rfu(0)" )
			)
			( pin "J1A2.227"
				( objectStatus "@baseboard_fab2_lib.baseboard_fab2(sch_1):page85_i111:rfu(1)" )
			)
			( pin "J1A2.144"
				( objectStatus "@baseboard_fab2_lib.baseboard_fab2(sch_1):page85_i111:rfu(2)" )
			)
			( pin "J1A2.84"
				( objectStatus "@baseboard_fab2_lib.baseboard_fab2(sch_1):page85_i111:s0_n" )
			)
			( pin "J1A2.89"
				( objectStatus "@baseboard_fab2_lib.baseboard_fab2(sch_1):page85_i111:s1_n" )
			)
			( pin "J1A2.93"
				( objectStatus "@baseboard_fab2_lib.baseboard_fab2(sch_1):page85_i111:s2_n_c(0)" )
			)
			( pin "J1A2.237"
				( objectStatus "@baseboard_fab2_lib.baseboard_fab2(sch_1):page85_i111:s3_n_c(1)" )
			)
			( pin "J1A2.139"
				( objectStatus "@baseboard_fab2_lib.baseboard_fab2(sch_1):page85_i111:sa(0)" )
			)
			( pin "J1A2.140"
				( objectStatus "@baseboard_fab2_lib.baseboard_fab2(sch_1):page85_i111:sa(1)" )
			)
			( pin "J1A2.238"
				( objectStatus "@baseboard_fab2_lib.baseboard_fab2(sch_1):page85_i111:sa(2)" )
			)
			( pin "J1A2.230"
				( objectStatus "@baseboard_fab2_lib.baseboard_fab2(sch_1):page85_i111:save_n_nc" )
			)
			( pin "J1A2.141"
				( objectStatus "@baseboard_fab2_lib.baseboard_fab2(sch_1):page85_i111:scl" )
			)
			( pin "J1A2.285"
				( objectStatus "@baseboard_fab2_lib.baseboard_fab2(sch_1):page85_i111:sda" )
			)
			( pin "J1A2.284"
				( objectStatus "@baseboard_fab2_lib.baseboard_fab2(sch_1):page85_i111:vddspd" )
			)
			( pin "J1A2.146"
				( objectStatus "@baseboard_fab2_lib.baseboard_fab2(sch_1):page85_i111:vrefca" )
			)
			( pin "J1A2.145"
				( objectStatus "@baseboard_fab2_lib.baseboard_fab2(sch_1):page85_i172:\12v\(0)" )
			)
			( pin "J1A2.1"
				( objectStatus "@baseboard_fab2_lib.baseboard_fab2(sch_1):page85_i172:\12v\(1)" )
			)
			( pin "J1A2.236"
				( objectStatus "@baseboard_fab2_lib.baseboard_fab2(sch_1):page85_i172:vdd(0)" )
			)
			( pin "J1A2.233"
				( objectStatus "@baseboard_fab2_lib.baseboard_fab2(sch_1):page85_i172:vdd(1)" )
			)
			( pin "J1A2.231"
				( objectStatus "@baseboard_fab2_lib.baseboard_fab2(sch_1):page85_i172:vdd(2)" )
			)
			( pin "J1A2.229"
				( objectStatus "@baseboard_fab2_lib.baseboard_fab2(sch_1):page85_i172:vdd(3)" )
			)
			( pin "J1A2.226"
				( objectStatus "@baseboard_fab2_lib.baseboard_fab2(sch_1):page85_i172:vdd(4)" )
			)
			( pin "J1A2.223"
				( objectStatus "@baseboard_fab2_lib.baseboard_fab2(sch_1):page85_i172:vdd(5)" )
			)
			( pin "J1A2.220"
				( objectStatus "@baseboard_fab2_lib.baseboard_fab2(sch_1):page85_i172:vdd(6)" )
			)
			( pin "J1A2.217"
				( objectStatus "@baseboard_fab2_lib.baseboard_fab2(sch_1):page85_i172:vdd(7)" )
			)
			( pin "J1A2.215"
				( objectStatus "@baseboard_fab2_lib.baseboard_fab2(sch_1):page85_i172:vdd(8)" )
			)
			( pin "J1A2.212"
				( objectStatus "@baseboard_fab2_lib.baseboard_fab2(sch_1):page85_i172:vdd(9)" )
			)
			( pin "J1A2.209"
				( objectStatus "@baseboard_fab2_lib.baseboard_fab2(sch_1):page85_i172:vdd(10)" )
			)
			( pin "J1A2.206"
				( objectStatus "@baseboard_fab2_lib.baseboard_fab2(sch_1):page85_i172:vdd(11)" )
			)
			( pin "J1A2.204"
				( objectStatus "@baseboard_fab2_lib.baseboard_fab2(sch_1):page85_i172:vdd(12)" )
			)
			( pin "J1A2.92"
				( objectStatus "@baseboard_fab2_lib.baseboard_fab2(sch_1):page85_i172:vdd(13)" )
			)
			( pin "J1A2.90"
				( objectStatus "@baseboard_fab2_lib.baseboard_fab2(sch_1):page85_i172:vdd(14)" )
			)
			( pin "J1A2.88"
				( objectStatus "@baseboard_fab2_lib.baseboard_fab2(sch_1):page85_i172:vdd(15)" )
			)
			( pin "J1A2.85"
				( objectStatus "@baseboard_fab2_lib.baseboard_fab2(sch_1):page85_i172:vdd(16)" )
			)
			( pin "J1A2.83"
				( objectStatus "@baseboard_fab2_lib.baseboard_fab2(sch_1):page85_i172:vdd(17)" )
			)
			( pin "J1A2.80"
				( objectStatus "@baseboard_fab2_lib.baseboard_fab2(sch_1):page85_i172:vdd(18)" )
			)
			( pin "J1A2.76"
				( objectStatus "@baseboard_fab2_lib.baseboard_fab2(sch_1):page85_i172:vdd(19)" )
			)
			( pin "J1A2.73"
				( objectStatus "@baseboard_fab2_lib.baseboard_fab2(sch_1):page85_i172:vdd(20)" )
			)
			( pin "J1A2.70"
				( objectStatus "@baseboard_fab2_lib.baseboard_fab2(sch_1):page85_i172:vdd(21)" )
			)
			( pin "J1A2.67"
				( objectStatus "@baseboard_fab2_lib.baseboard_fab2(sch_1):page85_i172:vdd(22)" )
			)
			( pin "J1A2.64"
				( objectStatus "@baseboard_fab2_lib.baseboard_fab2(sch_1):page85_i172:vdd(23)" )
			)
			( pin "J1A2.61"
				( objectStatus "@baseboard_fab2_lib.baseboard_fab2(sch_1):page85_i172:vdd(24)" )
			)
			( pin "J1A2.59"
				( objectStatus "@baseboard_fab2_lib.baseboard_fab2(sch_1):page85_i172:vdd(25)" )
			)
			( pin "J1A2.287"
				( objectStatus "@baseboard_fab2_lib.baseboard_fab2(sch_1):page85_i172:vpp(0)" )
			)
			( pin "J1A2.286"
				( objectStatus "@baseboard_fab2_lib.baseboard_fab2(sch_1):page85_i172:vpp(1)" )
			)
			( pin "J1A2.288"
				( objectStatus "@baseboard_fab2_lib.baseboard_fab2(sch_1):page85_i172:vpp(2)" )
			)
			( pin "J1A2.143"
				( objectStatus "@baseboard_fab2_lib.baseboard_fab2(sch_1):page85_i172:vpp(3)" )
			)
			( pin "J1A2.142"
				( objectStatus "@baseboard_fab2_lib.baseboard_fab2(sch_1):page85_i172:vpp(4)" )
			)
			( pin "J1A2.221"
				( objectStatus "@baseboard_fab2_lib.baseboard_fab2(sch_1):page85_i172:vtt(0)" )
			)
			( pin "J1A2.77"
				( objectStatus "@baseboard_fab2_lib.baseboard_fab2(sch_1):page85_i172:vtt(1)" )
			)
			( pin "C9L7.1"
				( objectStatus "@baseboard_fab2_lib.baseboard_fab2(sch_1):page85_i181:a" )
			)
			( pin "C9L7.2"
				( objectStatus "@baseboard_fab2_lib.baseboard_fab2(sch_1):page85_i181:b" )
			)
			( pin "J9L2.79"
				( objectStatus "@baseboard_fab2_lib.baseboard_fab2(sch_1):page86_i12:a0" )
			)
			( pin "J9L2.72"
				( objectStatus "@baseboard_fab2_lib.baseboard_fab2(sch_1):page86_i12:a1" )
			)
			( pin "J9L2.216"
				( objectStatus "@baseboard_fab2_lib.baseboard_fab2(sch_1):page86_i12:a2" )
			)
			( pin "J9L2.71"
				( objectStatus "@baseboard_fab2_lib.baseboard_fab2(sch_1):page86_i12:a3" )
			)
			( pin "J9L2.214"
				( objectStatus "@baseboard_fab2_lib.baseboard_fab2(sch_1):page86_i12:a4" )
			)
			( pin "J9L2.213"
				( objectStatus "@baseboard_fab2_lib.baseboard_fab2(sch_1):page86_i12:a5" )
			)
			( pin "J9L2.69"
				( objectStatus "@baseboard_fab2_lib.baseboard_fab2(sch_1):page86_i12:a6" )
			)
			( pin "J9L2.211"
				( objectStatus "@baseboard_fab2_lib.baseboard_fab2(sch_1):page86_i12:a7" )
			)
			( pin "J9L2.68"
				( objectStatus "@baseboard_fab2_lib.baseboard_fab2(sch_1):page86_i12:a8" )
			)
			( pin "J9L2.66"
				( objectStatus "@baseboard_fab2_lib.baseboard_fab2(sch_1):page86_i12:a9" )
			)
			( pin "J9L2.225"
				( objectStatus "@baseboard_fab2_lib.baseboard_fab2(sch_1):page86_i12:a10" )
			)
			( pin "J9L2.210"
				( objectStatus "@baseboard_fab2_lib.baseboard_fab2(sch_1):page86_i12:a11" )
			)
			( pin "J9L2.65"
				( objectStatus "@baseboard_fab2_lib.baseboard_fab2(sch_1):page86_i12:a12" )
			)
			( pin "J9L2.232"
				( objectStatus "@baseboard_fab2_lib.baseboard_fab2(sch_1):page86_i12:a13" )
			)
			( pin "J9L2.228"
				( objectStatus "@baseboard_fab2_lib.baseboard_fab2(sch_1):page86_i12:a14_we_n" )
			)
			( pin "J9L2.86"
				( objectStatus "@baseboard_fab2_lib.baseboard_fab2(sch_1):page86_i12:a15_cas_n" )
			)
			( pin "J9L2.82"
				( objectStatus "@baseboard_fab2_lib.baseboard_fab2(sch_1):page86_i12:a16_ras_n" )
			)
			( pin "J9L2.234"
				( objectStatus "@baseboard_fab2_lib.baseboard_fab2(sch_1):page86_i12:a17" )
			)
			( pin "J9L2.62"
				( objectStatus "@baseboard_fab2_lib.baseboard_fab2(sch_1):page86_i12:act_n" )
			)
			( pin "J9L2.208"
				( objectStatus "@baseboard_fab2_lib.baseboard_fab2(sch_1):page86_i12:alert_n" )
			)
			( pin "J9L2.81"
				( objectStatus "@baseboard_fab2_lib.baseboard_fab2(sch_1):page86_i12:ba(0)" )
			)
			( pin "J9L2.224"
				( objectStatus "@baseboard_fab2_lib.baseboard_fab2(sch_1):page86_i12:ba(1)" )
			)
			( pin "J9L2.63"
				( objectStatus "@baseboard_fab2_lib.baseboard_fab2(sch_1):page86_i12:bg(0)" )
			)
			( pin "J9L2.207"
				( objectStatus "@baseboard_fab2_lib.baseboard_fab2(sch_1):page86_i12:bg(1)" )
			)
			( pin "J9L2.235"
				( objectStatus "@baseboard_fab2_lib.baseboard_fab2(sch_1):page86_i12:c(2)" )
			)
			( pin "J9L2.49"
				( objectStatus "@baseboard_fab2_lib.baseboard_fab2(sch_1):page86_i12:cb(0)" )
			)
			( pin "J9L2.194"
				( objectStatus "@baseboard_fab2_lib.baseboard_fab2(sch_1):page86_i12:cb(1)" )
			)
			( pin "J9L2.56"
				( objectStatus "@baseboard_fab2_lib.baseboard_fab2(sch_1):page86_i12:cb(2)" )
			)
			( pin "J9L2.201"
				( objectStatus "@baseboard_fab2_lib.baseboard_fab2(sch_1):page86_i12:cb(3)" )
			)
			( pin "J9L2.47"
				( objectStatus "@baseboard_fab2_lib.baseboard_fab2(sch_1):page86_i12:cb(4)" )
			)
			( pin "J9L2.192"
				( objectStatus "@baseboard_fab2_lib.baseboard_fab2(sch_1):page86_i12:cb(5)" )
			)
			( pin "J9L2.54"
				( objectStatus "@baseboard_fab2_lib.baseboard_fab2(sch_1):page86_i12:cb(6)" )
			)
			( pin "J9L2.199"
				( objectStatus "@baseboard_fab2_lib.baseboard_fab2(sch_1):page86_i12:cb(7)" )
			)
			( pin "J9L2.75"
				( objectStatus "@baseboard_fab2_lib.baseboard_fab2(sch_1):page86_i12:ck0n" )
			)
			( pin "J9L2.74"
				( objectStatus "@baseboard_fab2_lib.baseboard_fab2(sch_1):page86_i12:ck0p" )
			)
			( pin "J9L2.219"
				( objectStatus "@baseboard_fab2_lib.baseboard_fab2(sch_1):page86_i12:ck1n" )
			)
			( pin "J9L2.218"
				( objectStatus "@baseboard_fab2_lib.baseboard_fab2(sch_1):page86_i12:ck1p" )
			)
			( pin "J9L2.60"
				( objectStatus "@baseboard_fab2_lib.baseboard_fab2(sch_1):page86_i12:cke(0)" )
			)
			( pin "J9L2.203"
				( objectStatus "@baseboard_fab2_lib.baseboard_fab2(sch_1):page86_i12:cke(1)" )
			)
			( pin "J9L2.5"
				( objectStatus "@baseboard_fab2_lib.baseboard_fab2(sch_1):page86_i12:dq(0)" )
			)
			( pin "J9L2.150"
				( objectStatus "@baseboard_fab2_lib.baseboard_fab2(sch_1):page86_i12:dq(1)" )
			)
			( pin "J9L2.12"
				( objectStatus "@baseboard_fab2_lib.baseboard_fab2(sch_1):page86_i12:dq(2)" )
			)
			( pin "J9L2.157"
				( objectStatus "@baseboard_fab2_lib.baseboard_fab2(sch_1):page86_i12:dq(3)" )
			)
			( pin "J9L2.3"
				( objectStatus "@baseboard_fab2_lib.baseboard_fab2(sch_1):page86_i12:dq(4)" )
			)
			( pin "J9L2.148"
				( objectStatus "@baseboard_fab2_lib.baseboard_fab2(sch_1):page86_i12:dq(5)" )
			)
			( pin "J9L2.10"
				( objectStatus "@baseboard_fab2_lib.baseboard_fab2(sch_1):page86_i12:dq(6)" )
			)
			( pin "J9L2.155"
				( objectStatus "@baseboard_fab2_lib.baseboard_fab2(sch_1):page86_i12:dq(7)" )
			)
			( pin "J9L2.16"
				( objectStatus "@baseboard_fab2_lib.baseboard_fab2(sch_1):page86_i12:dq(8)" )
			)
			( pin "J9L2.161"
				( objectStatus "@baseboard_fab2_lib.baseboard_fab2(sch_1):page86_i12:dq(9)" )
			)
			( pin "J9L2.23"
				( objectStatus "@baseboard_fab2_lib.baseboard_fab2(sch_1):page86_i12:dq(10)" )
			)
			( pin "J9L2.168"
				( objectStatus "@baseboard_fab2_lib.baseboard_fab2(sch_1):page86_i12:dq(11)" )
			)
			( pin "J9L2.14"
				( objectStatus "@baseboard_fab2_lib.baseboard_fab2(sch_1):page86_i12:dq(12)" )
			)
			( pin "J9L2.159"
				( objectStatus "@baseboard_fab2_lib.baseboard_fab2(sch_1):page86_i12:dq(13)" )
			)
			( pin "J9L2.21"
				( objectStatus "@baseboard_fab2_lib.baseboard_fab2(sch_1):page86_i12:dq(14)" )
			)
			( pin "J9L2.166"
				( objectStatus "@baseboard_fab2_lib.baseboard_fab2(sch_1):page86_i12:dq(15)" )
			)
			( pin "J9L2.27"
				( objectStatus "@baseboard_fab2_lib.baseboard_fab2(sch_1):page86_i12:dq(16)" )
			)
			( pin "J9L2.172"
				( objectStatus "@baseboard_fab2_lib.baseboard_fab2(sch_1):page86_i12:dq(17)" )
			)
			( pin "J9L2.34"
				( objectStatus "@baseboard_fab2_lib.baseboard_fab2(sch_1):page86_i12:dq(18)" )
			)
			( pin "J9L2.179"
				( objectStatus "@baseboard_fab2_lib.baseboard_fab2(sch_1):page86_i12:dq(19)" )
			)
			( pin "J9L2.25"
				( objectStatus "@baseboard_fab2_lib.baseboard_fab2(sch_1):page86_i12:dq(20)" )
			)
			( pin "J9L2.170"
				( objectStatus "@baseboard_fab2_lib.baseboard_fab2(sch_1):page86_i12:dq(21)" )
			)
			( pin "J9L2.32"
				( objectStatus "@baseboard_fab2_lib.baseboard_fab2(sch_1):page86_i12:dq(22)" )
			)
			( pin "J9L2.177"
				( objectStatus "@baseboard_fab2_lib.baseboard_fab2(sch_1):page86_i12:dq(23)" )
			)
			( pin "J9L2.38"
				( objectStatus "@baseboard_fab2_lib.baseboard_fab2(sch_1):page86_i12:dq(24)" )
			)
			( pin "J9L2.183"
				( objectStatus "@baseboard_fab2_lib.baseboard_fab2(sch_1):page86_i12:dq(25)" )
			)
			( pin "J9L2.45"
				( objectStatus "@baseboard_fab2_lib.baseboard_fab2(sch_1):page86_i12:dq(26)" )
			)
			( pin "J9L2.190"
				( objectStatus "@baseboard_fab2_lib.baseboard_fab2(sch_1):page86_i12:dq(27)" )
			)
			( pin "J9L2.36"
				( objectStatus "@baseboard_fab2_lib.baseboard_fab2(sch_1):page86_i12:dq(28)" )
			)
			( pin "J9L2.181"
				( objectStatus "@baseboard_fab2_lib.baseboard_fab2(sch_1):page86_i12:dq(29)" )
			)
			( pin "J9L2.43"
				( objectStatus "@baseboard_fab2_lib.baseboard_fab2(sch_1):page86_i12:dq(30)" )
			)
			( pin "J9L2.188"
				( objectStatus "@baseboard_fab2_lib.baseboard_fab2(sch_1):page86_i12:dq(31)" )
			)
			( pin "J9L2.97"
				( objectStatus "@baseboard_fab2_lib.baseboard_fab2(sch_1):page86_i12:dq(32)" )
			)
			( pin "J9L2.242"
				( objectStatus "@baseboard_fab2_lib.baseboard_fab2(sch_1):page86_i12:dq(33)" )
			)
			( pin "J9L2.104"
				( objectStatus "@baseboard_fab2_lib.baseboard_fab2(sch_1):page86_i12:dq(34)" )
			)
			( pin "J9L2.249"
				( objectStatus "@baseboard_fab2_lib.baseboard_fab2(sch_1):page86_i12:dq(35)" )
			)
			( pin "J9L2.95"
				( objectStatus "@baseboard_fab2_lib.baseboard_fab2(sch_1):page86_i12:dq(36)" )
			)
			( pin "J9L2.240"
				( objectStatus "@baseboard_fab2_lib.baseboard_fab2(sch_1):page86_i12:dq(37)" )
			)
			( pin "J9L2.102"
				( objectStatus "@baseboard_fab2_lib.baseboard_fab2(sch_1):page86_i12:dq(38)" )
			)
			( pin "J9L2.247"
				( objectStatus "@baseboard_fab2_lib.baseboard_fab2(sch_1):page86_i12:dq(39)" )
			)
			( pin "J9L2.108"
				( objectStatus "@baseboard_fab2_lib.baseboard_fab2(sch_1):page86_i12:dq(40)" )
			)
			( pin "J9L2.253"
				( objectStatus "@baseboard_fab2_lib.baseboard_fab2(sch_1):page86_i12:dq(41)" )
			)
			( pin "J9L2.115"
				( objectStatus "@baseboard_fab2_lib.baseboard_fab2(sch_1):page86_i12:dq(42)" )
			)
			( pin "J9L2.260"
				( objectStatus "@baseboard_fab2_lib.baseboard_fab2(sch_1):page86_i12:dq(43)" )
			)
			( pin "J9L2.106"
				( objectStatus "@baseboard_fab2_lib.baseboard_fab2(sch_1):page86_i12:dq(44)" )
			)
			( pin "J9L2.251"
				( objectStatus "@baseboard_fab2_lib.baseboard_fab2(sch_1):page86_i12:dq(45)" )
			)
			( pin "J9L2.113"
				( objectStatus "@baseboard_fab2_lib.baseboard_fab2(sch_1):page86_i12:dq(46)" )
			)
			( pin "J9L2.258"
				( objectStatus "@baseboard_fab2_lib.baseboard_fab2(sch_1):page86_i12:dq(47)" )
			)
			( pin "J9L2.119"
				( objectStatus "@baseboard_fab2_lib.baseboard_fab2(sch_1):page86_i12:dq(48)" )
			)
			( pin "J9L2.264"
				( objectStatus "@baseboard_fab2_lib.baseboard_fab2(sch_1):page86_i12:dq(49)" )
			)
			( pin "J9L2.126"
				( objectStatus "@baseboard_fab2_lib.baseboard_fab2(sch_1):page86_i12:dq(50)" )
			)
			( pin "J9L2.271"
				( objectStatus "@baseboard_fab2_lib.baseboard_fab2(sch_1):page86_i12:dq(51)" )
			)
			( pin "J9L2.117"
				( objectStatus "@baseboard_fab2_lib.baseboard_fab2(sch_1):page86_i12:dq(52)" )
			)
			( pin "J9L2.262"
				( objectStatus "@baseboard_fab2_lib.baseboard_fab2(sch_1):page86_i12:dq(53)" )
			)
			( pin "J9L2.124"
				( objectStatus "@baseboard_fab2_lib.baseboard_fab2(sch_1):page86_i12:dq(54)" )
			)
			( pin "J9L2.269"
				( objectStatus "@baseboard_fab2_lib.baseboard_fab2(sch_1):page86_i12:dq(55)" )
			)
			( pin "J9L2.130"
				( objectStatus "@baseboard_fab2_lib.baseboard_fab2(sch_1):page86_i12:dq(56)" )
			)
			( pin "J9L2.275"
				( objectStatus "@baseboard_fab2_lib.baseboard_fab2(sch_1):page86_i12:dq(57)" )
			)
			( pin "J9L2.137"
				( objectStatus "@baseboard_fab2_lib.baseboard_fab2(sch_1):page86_i12:dq(58)" )
			)
			( pin "J9L2.282"
				( objectStatus "@baseboard_fab2_lib.baseboard_fab2(sch_1):page86_i12:dq(59)" )
			)
			( pin "J9L2.128"
				( objectStatus "@baseboard_fab2_lib.baseboard_fab2(sch_1):page86_i12:dq(60)" )
			)
			( pin "J9L2.273"
				( objectStatus "@baseboard_fab2_lib.baseboard_fab2(sch_1):page86_i12:dq(61)" )
			)
			( pin "J9L2.135"
				( objectStatus "@baseboard_fab2_lib.baseboard_fab2(sch_1):page86_i12:dq(62)" )
			)
			( pin "J9L2.280"
				( objectStatus "@baseboard_fab2_lib.baseboard_fab2(sch_1):page86_i12:dq(63)" )
			)
			( pin "J9L2.78"
				( objectStatus "@baseboard_fab2_lib.baseboard_fab2(sch_1):page86_i12:event_n" )
			)
			( pin "J9L2.87"
				( objectStatus "@baseboard_fab2_lib.baseboard_fab2(sch_1):page86_i12:odt(0)" )
			)
			( pin "J9L2.91"
				( objectStatus "@baseboard_fab2_lib.baseboard_fab2(sch_1):page86_i12:odt(1)" )
			)
			( pin "J9L2.222"
				( objectStatus "@baseboard_fab2_lib.baseboard_fab2(sch_1):page86_i12:par" )
			)
			( pin "J9L2.58"
				( objectStatus "@baseboard_fab2_lib.baseboard_fab2(sch_1):page86_i12:reset_n" )
			)
			( pin "J9L2.205"
				( objectStatus "@baseboard_fab2_lib.baseboard_fab2(sch_1):page86_i12:rfu(0)" )
			)
			( pin "J9L2.227"
				( objectStatus "@baseboard_fab2_lib.baseboard_fab2(sch_1):page86_i12:rfu(1)" )
			)
			( pin "J9L2.144"
				( objectStatus "@baseboard_fab2_lib.baseboard_fab2(sch_1):page86_i12:rfu(2)" )
			)
			( pin "J9L2.84"
				( objectStatus "@baseboard_fab2_lib.baseboard_fab2(sch_1):page86_i12:s0_n" )
			)
			( pin "J9L2.89"
				( objectStatus "@baseboard_fab2_lib.baseboard_fab2(sch_1):page86_i12:s1_n" )
			)
			( pin "J9L2.93"
				( objectStatus "@baseboard_fab2_lib.baseboard_fab2(sch_1):page86_i12:s2_n_c(0)" )
			)
			( pin "J9L2.237"
				( objectStatus "@baseboard_fab2_lib.baseboard_fab2(sch_1):page86_i12:s3_n_c(1)" )
			)
			( pin "J9L2.139"
				( objectStatus "@baseboard_fab2_lib.baseboard_fab2(sch_1):page86_i12:sa(0)" )
			)
			( pin "J9L2.140"
				( objectStatus "@baseboard_fab2_lib.baseboard_fab2(sch_1):page86_i12:sa(1)" )
			)
			( pin "J9L2.238"
				( objectStatus "@baseboard_fab2_lib.baseboard_fab2(sch_1):page86_i12:sa(2)" )
			)
			( pin "J9L2.230"
				( objectStatus "@baseboard_fab2_lib.baseboard_fab2(sch_1):page86_i12:save_n_nc" )
			)
			( pin "J9L2.141"
				( objectStatus "@baseboard_fab2_lib.baseboard_fab2(sch_1):page86_i12:scl" )
			)
			( pin "J9L2.285"
				( objectStatus "@baseboard_fab2_lib.baseboard_fab2(sch_1):page86_i12:sda" )
			)
			( pin "J9L2.284"
				( objectStatus "@baseboard_fab2_lib.baseboard_fab2(sch_1):page86_i12:vddspd" )
			)
			( pin "J9L2.146"
				( objectStatus "@baseboard_fab2_lib.baseboard_fab2(sch_1):page86_i12:vrefca" )
			)
			( pin "J9L2.145"
				( objectStatus "@baseboard_fab2_lib.baseboard_fab2(sch_1):page86_i55:\12v\(0)" )
			)
			( pin "J9L2.1"
				( objectStatus "@baseboard_fab2_lib.baseboard_fab2(sch_1):page86_i55:\12v\(1)" )
			)
			( pin "J9L2.236"
				( objectStatus "@baseboard_fab2_lib.baseboard_fab2(sch_1):page86_i55:vdd(0)" )
			)
			( pin "J9L2.233"
				( objectStatus "@baseboard_fab2_lib.baseboard_fab2(sch_1):page86_i55:vdd(1)" )
			)
			( pin "J9L2.231"
				( objectStatus "@baseboard_fab2_lib.baseboard_fab2(sch_1):page86_i55:vdd(2)" )
			)
			( pin "J9L2.229"
				( objectStatus "@baseboard_fab2_lib.baseboard_fab2(sch_1):page86_i55:vdd(3)" )
			)
			( pin "J9L2.226"
				( objectStatus "@baseboard_fab2_lib.baseboard_fab2(sch_1):page86_i55:vdd(4)" )
			)
			( pin "J9L2.223"
				( objectStatus "@baseboard_fab2_lib.baseboard_fab2(sch_1):page86_i55:vdd(5)" )
			)
			( pin "J9L2.220"
				( objectStatus "@baseboard_fab2_lib.baseboard_fab2(sch_1):page86_i55:vdd(6)" )
			)
			( pin "J9L2.217"
				( objectStatus "@baseboard_fab2_lib.baseboard_fab2(sch_1):page86_i55:vdd(7)" )
			)
			( pin "J9L2.215"
				( objectStatus "@baseboard_fab2_lib.baseboard_fab2(sch_1):page86_i55:vdd(8)" )
			)
			( pin "J9L2.212"
				( objectStatus "@baseboard_fab2_lib.baseboard_fab2(sch_1):page86_i55:vdd(9)" )
			)
			( pin "J9L2.209"
				( objectStatus "@baseboard_fab2_lib.baseboard_fab2(sch_1):page86_i55:vdd(10)" )
			)
			( pin "J9L2.206"
				( objectStatus "@baseboard_fab2_lib.baseboard_fab2(sch_1):page86_i55:vdd(11)" )
			)
			( pin "J9L2.204"
				( objectStatus "@baseboard_fab2_lib.baseboard_fab2(sch_1):page86_i55:vdd(12)" )
			)
			( pin "J9L2.92"
				( objectStatus "@baseboard_fab2_lib.baseboard_fab2(sch_1):page86_i55:vdd(13)" )
			)
			( pin "J9L2.90"
				( objectStatus "@baseboard_fab2_lib.baseboard_fab2(sch_1):page86_i55:vdd(14)" )
			)
			( pin "J9L2.88"
				( objectStatus "@baseboard_fab2_lib.baseboard_fab2(sch_1):page86_i55:vdd(15)" )
			)
			( pin "J9L2.85"
				( objectStatus "@baseboard_fab2_lib.baseboard_fab2(sch_1):page86_i55:vdd(16)" )
			)
			( pin "J9L2.83"
				( objectStatus "@baseboard_fab2_lib.baseboard_fab2(sch_1):page86_i55:vdd(17)" )
			)
			( pin "J9L2.80"
				( objectStatus "@baseboard_fab2_lib.baseboard_fab2(sch_1):page86_i55:vdd(18)" )
			)
			( pin "J9L2.76"
				( objectStatus "@baseboard_fab2_lib.baseboard_fab2(sch_1):page86_i55:vdd(19)" )
			)
			( pin "J9L2.73"
				( objectStatus "@baseboard_fab2_lib.baseboard_fab2(sch_1):page86_i55:vdd(20)" )
			)
			( pin "J9L2.70"
				( objectStatus "@baseboard_fab2_lib.baseboard_fab2(sch_1):page86_i55:vdd(21)" )
			)
			( pin "J9L2.67"
				( objectStatus "@baseboard_fab2_lib.baseboard_fab2(sch_1):page86_i55:vdd(22)" )
			)
			( pin "J9L2.64"
				( objectStatus "@baseboard_fab2_lib.baseboard_fab2(sch_1):page86_i55:vdd(23)" )
			)
			( pin "J9L2.61"
				( objectStatus "@baseboard_fab2_lib.baseboard_fab2(sch_1):page86_i55:vdd(24)" )
			)
			( pin "J9L2.59"
				( objectStatus "@baseboard_fab2_lib.baseboard_fab2(sch_1):page86_i55:vdd(25)" )
			)
			( pin "J9L2.287"
				( objectStatus "@baseboard_fab2_lib.baseboard_fab2(sch_1):page86_i55:vpp(0)" )
			)
			( pin "J9L2.286"
				( objectStatus "@baseboard_fab2_lib.baseboard_fab2(sch_1):page86_i55:vpp(1)" )
			)
			( pin "J9L2.288"
				( objectStatus "@baseboard_fab2_lib.baseboard_fab2(sch_1):page86_i55:vpp(2)" )
			)
			( pin "J9L2.143"
				( objectStatus "@baseboard_fab2_lib.baseboard_fab2(sch_1):page86_i55:vpp(3)" )
			)
			( pin "J9L2.142"
				( objectStatus "@baseboard_fab2_lib.baseboard_fab2(sch_1):page86_i55:vpp(4)" )
			)
			( pin "J9L2.221"
				( objectStatus "@baseboard_fab2_lib.baseboard_fab2(sch_1):page86_i55:vtt(0)" )
			)
			( pin "J9L2.77"
				( objectStatus "@baseboard_fab2_lib.baseboard_fab2(sch_1):page86_i55:vtt(1)" )
			)
			( pin "J9L2.152"
				( objectStatus "@baseboard_fab2_lib.baseboard_fab2(sch_1):page86_i100:dqs0n" )
			)
			( pin "J9L2.153"
				( objectStatus "@baseboard_fab2_lib.baseboard_fab2(sch_1):page86_i100:dqs0p" )
			)
			( pin "J9L2.163"
				( objectStatus "@baseboard_fab2_lib.baseboard_fab2(sch_1):page86_i100:dqs1n" )
			)
			( pin "J9L2.164"
				( objectStatus "@baseboard_fab2_lib.baseboard_fab2(sch_1):page86_i100:dqs1p" )
			)
			( pin "J9L2.174"
				( objectStatus "@baseboard_fab2_lib.baseboard_fab2(sch_1):page86_i100:dqs2n" )
			)
			( pin "J9L2.175"
				( objectStatus "@baseboard_fab2_lib.baseboard_fab2(sch_1):page86_i100:dqs2p" )
			)
			( pin "J9L2.185"
				( objectStatus "@baseboard_fab2_lib.baseboard_fab2(sch_1):page86_i100:dqs3n" )
			)
			( pin "J9L2.186"
				( objectStatus "@baseboard_fab2_lib.baseboard_fab2(sch_1):page86_i100:dqs3p" )
			)
			( pin "J9L2.244"
				( objectStatus "@baseboard_fab2_lib.baseboard_fab2(sch_1):page86_i100:dqs4n" )
			)
			( pin "J9L2.245"
				( objectStatus "@baseboard_fab2_lib.baseboard_fab2(sch_1):page86_i100:dqs4p" )
			)
			( pin "J9L2.255"
				( objectStatus "@baseboard_fab2_lib.baseboard_fab2(sch_1):page86_i100:dqs5n" )
			)
			( pin "J9L2.256"
				( objectStatus "@baseboard_fab2_lib.baseboard_fab2(sch_1):page86_i100:dqs5p" )
			)
			( pin "J9L2.266"
				( objectStatus "@baseboard_fab2_lib.baseboard_fab2(sch_1):page86_i100:dqs6n" )
			)
			( pin "J9L2.267"
				( objectStatus "@baseboard_fab2_lib.baseboard_fab2(sch_1):page86_i100:dqs6p" )
			)
			( pin "J9L2.277"
				( objectStatus "@baseboard_fab2_lib.baseboard_fab2(sch_1):page86_i100:dqs7n" )
			)
			( pin "J9L2.278"
				( objectStatus "@baseboard_fab2_lib.baseboard_fab2(sch_1):page86_i100:dqs7p" )
			)
			( pin "J9L2.196"
				( objectStatus "@baseboard_fab2_lib.baseboard_fab2(sch_1):page86_i100:dqs8n" )
			)
			( pin "J9L2.197"
				( objectStatus "@baseboard_fab2_lib.baseboard_fab2(sch_1):page86_i100:dqs8p" )
			)
			( pin "J9L2.8"
				( objectStatus "@baseboard_fab2_lib.baseboard_fab2(sch_1):page86_i100:dqs9n" )
			)
			( pin "J9L2.7"
				( objectStatus "@baseboard_fab2_lib.baseboard_fab2(sch_1):page86_i100:dqs9p" )
			)
			( pin "J9L2.19"
				( objectStatus "@baseboard_fab2_lib.baseboard_fab2(sch_1):page86_i100:dqs10n" )
			)
			( pin "J9L2.18"
				( objectStatus "@baseboard_fab2_lib.baseboard_fab2(sch_1):page86_i100:dqs10p" )
			)
			( pin "J9L2.30"
				( objectStatus "@baseboard_fab2_lib.baseboard_fab2(sch_1):page86_i100:dqs11n" )
			)
			( pin "J9L2.29"
				( objectStatus "@baseboard_fab2_lib.baseboard_fab2(sch_1):page86_i100:dqs11p" )
			)
			( pin "J9L2.41"
				( objectStatus "@baseboard_fab2_lib.baseboard_fab2(sch_1):page86_i100:dqs12n" )
			)
			( pin "J9L2.40"
				( objectStatus "@baseboard_fab2_lib.baseboard_fab2(sch_1):page86_i100:dqs12p" )
			)
			( pin "J9L2.100"
				( objectStatus "@baseboard_fab2_lib.baseboard_fab2(sch_1):page86_i100:dqs13n" )
			)
			( pin "J9L2.99"
				( objectStatus "@baseboard_fab2_lib.baseboard_fab2(sch_1):page86_i100:dqs13p" )
			)
			( pin "J9L2.111"
				( objectStatus "@baseboard_fab2_lib.baseboard_fab2(sch_1):page86_i100:dqs14n" )
			)
			( pin "J9L2.110"
				( objectStatus "@baseboard_fab2_lib.baseboard_fab2(sch_1):page86_i100:dqs14p" )
			)
			( pin "J9L2.122"
				( objectStatus "@baseboard_fab2_lib.baseboard_fab2(sch_1):page86_i100:dqs15n" )
			)
			( pin "J9L2.121"
				( objectStatus "@baseboard_fab2_lib.baseboard_fab2(sch_1):page86_i100:dqs15p" )
			)
			( pin "J9L2.133"
				( objectStatus "@baseboard_fab2_lib.baseboard_fab2(sch_1):page86_i100:dqs16n" )
			)
			( pin "J9L2.132"
				( objectStatus "@baseboard_fab2_lib.baseboard_fab2(sch_1):page86_i100:dqs16p" )
			)
			( pin "J9L2.52"
				( objectStatus "@baseboard_fab2_lib.baseboard_fab2(sch_1):page86_i100:dqs17n" )
			)
			( pin "J9L2.51"
				( objectStatus "@baseboard_fab2_lib.baseboard_fab2(sch_1):page86_i100:dqs17p" )
			)
			( pin "J9L2.283"
				( objectStatus "@baseboard_fab2_lib.baseboard_fab2(sch_1):page86_i138:vss(0)" )
			)
			( pin "J9L2.281"
				( objectStatus "@baseboard_fab2_lib.baseboard_fab2(sch_1):page86_i138:vss(1)" )
			)
			( pin "J9L2.279"
				( objectStatus "@baseboard_fab2_lib.baseboard_fab2(sch_1):page86_i138:vss(2)" )
			)
			( pin "J9L2.276"
				( objectStatus "@baseboard_fab2_lib.baseboard_fab2(sch_1):page86_i138:vss(3)" )
			)
			( pin "J9L2.274"
				( objectStatus "@baseboard_fab2_lib.baseboard_fab2(sch_1):page86_i138:vss(4)" )
			)
			( pin "J9L2.272"
				( objectStatus "@baseboard_fab2_lib.baseboard_fab2(sch_1):page86_i138:vss(5)" )
			)
			( pin "J9L2.270"
				( objectStatus "@baseboard_fab2_lib.baseboard_fab2(sch_1):page86_i138:vss(6)" )
			)
			( pin "J9L2.268"
				( objectStatus "@baseboard_fab2_lib.baseboard_fab2(sch_1):page86_i138:vss(7)" )
			)
			( pin "J9L2.265"
				( objectStatus "@baseboard_fab2_lib.baseboard_fab2(sch_1):page86_i138:vss(8)" )
			)
			( pin "J9L2.263"
				( objectStatus "@baseboard_fab2_lib.baseboard_fab2(sch_1):page86_i138:vss(9)" )
			)
			( pin "J9L2.261"
				( objectStatus "@baseboard_fab2_lib.baseboard_fab2(sch_1):page86_i138:vss(10)" )
			)
			( pin "J9L2.259"
				( objectStatus "@baseboard_fab2_lib.baseboard_fab2(sch_1):page86_i138:vss(11)" )
			)
			( pin "J9L2.257"
				( objectStatus "@baseboard_fab2_lib.baseboard_fab2(sch_1):page86_i138:vss(12)" )
			)
			( pin "J9L2.254"
				( objectStatus "@baseboard_fab2_lib.baseboard_fab2(sch_1):page86_i138:vss(13)" )
			)
			( pin "J9L2.252"
				( objectStatus "@baseboard_fab2_lib.baseboard_fab2(sch_1):page86_i138:vss(14)" )
			)
			( pin "J9L2.250"
				( objectStatus "@baseboard_fab2_lib.baseboard_fab2(sch_1):page86_i138:vss(15)" )
			)
			( pin "J9L2.248"
				( objectStatus "@baseboard_fab2_lib.baseboard_fab2(sch_1):page86_i138:vss(16)" )
			)
			( pin "J9L2.246"
				( objectStatus "@baseboard_fab2_lib.baseboard_fab2(sch_1):page86_i138:vss(17)" )
			)
			( pin "J9L2.243"
				( objectStatus "@baseboard_fab2_lib.baseboard_fab2(sch_1):page86_i138:vss(18)" )
			)
			( pin "J9L2.241"
				( objectStatus "@baseboard_fab2_lib.baseboard_fab2(sch_1):page86_i138:vss(19)" )
			)
			( pin "J9L2.239"
				( objectStatus "@baseboard_fab2_lib.baseboard_fab2(sch_1):page86_i138:vss(20)" )
			)
			( pin "J9L2.202"
				( objectStatus "@baseboard_fab2_lib.baseboard_fab2(sch_1):page86_i138:vss(21)" )
			)
			( pin "J9L2.200"
				( objectStatus "@baseboard_fab2_lib.baseboard_fab2(sch_1):page86_i138:vss(22)" )
			)
			( pin "J9L2.198"
				( objectStatus "@baseboard_fab2_lib.baseboard_fab2(sch_1):page86_i138:vss(23)" )
			)
			( pin "J9L2.195"
				( objectStatus "@baseboard_fab2_lib.baseboard_fab2(sch_1):page86_i138:vss(24)" )
			)
			( pin "J9L2.193"
				( objectStatus "@baseboard_fab2_lib.baseboard_fab2(sch_1):page86_i138:vss(25)" )
			)
			( pin "J9L2.191"
				( objectStatus "@baseboard_fab2_lib.baseboard_fab2(sch_1):page86_i138:vss(26)" )
			)
			( pin "J9L2.189"
				( objectStatus "@baseboard_fab2_lib.baseboard_fab2(sch_1):page86_i138:vss(27)" )
			)
			( pin "J9L2.187"
				( objectStatus "@baseboard_fab2_lib.baseboard_fab2(sch_1):page86_i138:vss(28)" )
			)
			( pin "J9L2.184"
				( objectStatus "@baseboard_fab2_lib.baseboard_fab2(sch_1):page86_i138:vss(29)" )
			)
			( pin "J9L2.182"
				( objectStatus "@baseboard_fab2_lib.baseboard_fab2(sch_1):page86_i138:vss(30)" )
			)
			( pin "J9L2.180"
				( objectStatus "@baseboard_fab2_lib.baseboard_fab2(sch_1):page86_i138:vss(31)" )
			)
			( pin "J9L2.178"
				( objectStatus "@baseboard_fab2_lib.baseboard_fab2(sch_1):page86_i138:vss(32)" )
			)
			( pin "J9L2.176"
				( objectStatus "@baseboard_fab2_lib.baseboard_fab2(sch_1):page86_i138:vss(33)" )
			)
			( pin "J9L2.173"
				( objectStatus "@baseboard_fab2_lib.baseboard_fab2(sch_1):page86_i138:vss(34)" )
			)
			( pin "J9L2.171"
				( objectStatus "@baseboard_fab2_lib.baseboard_fab2(sch_1):page86_i138:vss(35)" )
			)
			( pin "J9L2.169"
				( objectStatus "@baseboard_fab2_lib.baseboard_fab2(sch_1):page86_i138:vss(36)" )
			)
			( pin "J9L2.167"
				( objectStatus "@baseboard_fab2_lib.baseboard_fab2(sch_1):page86_i138:vss(37)" )
			)
			( pin "J9L2.165"
				( objectStatus "@baseboard_fab2_lib.baseboard_fab2(sch_1):page86_i138:vss(38)" )
			)
			( pin "J9L2.162"
				( objectStatus "@baseboard_fab2_lib.baseboard_fab2(sch_1):page86_i138:vss(39)" )
			)
			( pin "J9L2.160"
				( objectStatus "@baseboard_fab2_lib.baseboard_fab2(sch_1):page86_i138:vss(40)" )
			)
			( pin "J9L2.158"
				( objectStatus "@baseboard_fab2_lib.baseboard_fab2(sch_1):page86_i138:vss(41)" )
			)
			( pin "J9L2.156"
				( objectStatus "@baseboard_fab2_lib.baseboard_fab2(sch_1):page86_i138:vss(42)" )
			)
			( pin "J9L2.154"
				( objectStatus "@baseboard_fab2_lib.baseboard_fab2(sch_1):page86_i138:vss(43)" )
			)
			( pin "J9L2.151"
				( objectStatus "@baseboard_fab2_lib.baseboard_fab2(sch_1):page86_i138:vss(44)" )
			)
			( pin "J9L2.149"
				( objectStatus "@baseboard_fab2_lib.baseboard_fab2(sch_1):page86_i138:vss(45)" )
			)
			( pin "J9L2.147"
				( objectStatus "@baseboard_fab2_lib.baseboard_fab2(sch_1):page86_i138:vss(46)" )
			)
			( pin "J9L2.138"
				( objectStatus "@baseboard_fab2_lib.baseboard_fab2(sch_1):page86_i138:vss(47)" )
			)
			( pin "J9L2.136"
				( objectStatus "@baseboard_fab2_lib.baseboard_fab2(sch_1):page86_i138:vss(48)" )
			)
			( pin "J9L2.134"
				( objectStatus "@baseboard_fab2_lib.baseboard_fab2(sch_1):page86_i138:vss(49)" )
			)
			( pin "J9L2.131"
				( objectStatus "@baseboard_fab2_lib.baseboard_fab2(sch_1):page86_i138:vss(50)" )
			)
			( pin "J9L2.129"
				( objectStatus "@baseboard_fab2_lib.baseboard_fab2(sch_1):page86_i138:vss(51)" )
			)
			( pin "J9L2.127"
				( objectStatus "@baseboard_fab2_lib.baseboard_fab2(sch_1):page86_i138:vss(52)" )
			)
			( pin "J9L2.125"
				( objectStatus "@baseboard_fab2_lib.baseboard_fab2(sch_1):page86_i138:vss(53)" )
			)
			( pin "J9L2.123"
				( objectStatus "@baseboard_fab2_lib.baseboard_fab2(sch_1):page86_i138:vss(54)" )
			)
			( pin "J9L2.120"
				( objectStatus "@baseboard_fab2_lib.baseboard_fab2(sch_1):page86_i138:vss(55)" )
			)
			( pin "J9L2.118"
				( objectStatus "@baseboard_fab2_lib.baseboard_fab2(sch_1):page86_i138:vss(56)" )
			)
			( pin "J9L2.116"
				( objectStatus "@baseboard_fab2_lib.baseboard_fab2(sch_1):page86_i138:vss(57)" )
			)
			( pin "J9L2.114"
				( objectStatus "@baseboard_fab2_lib.baseboard_fab2(sch_1):page86_i138:vss(58)" )
			)
			( pin "J9L2.112"
				( objectStatus "@baseboard_fab2_lib.baseboard_fab2(sch_1):page86_i138:vss(59)" )
			)
			( pin "J9L2.109"
				( objectStatus "@baseboard_fab2_lib.baseboard_fab2(sch_1):page86_i138:vss(60)" )
			)
			( pin "J9L2.107"
				( objectStatus "@baseboard_fab2_lib.baseboard_fab2(sch_1):page86_i138:vss(61)" )
			)
			( pin "J9L2.105"
				( objectStatus "@baseboard_fab2_lib.baseboard_fab2(sch_1):page86_i138:vss(62)" )
			)
			( pin "J9L2.103"
				( objectStatus "@baseboard_fab2_lib.baseboard_fab2(sch_1):page86_i138:vss(63)" )
			)
			( pin "J9L2.101"
				( objectStatus "@baseboard_fab2_lib.baseboard_fab2(sch_1):page86_i138:vss(64)" )
			)
			( pin "J9L2.98"
				( objectStatus "@baseboard_fab2_lib.baseboard_fab2(sch_1):page86_i138:vss(65)" )
			)
			( pin "J9L2.96"
				( objectStatus "@baseboard_fab2_lib.baseboard_fab2(sch_1):page86_i138:vss(66)" )
			)
			( pin "J9L2.94"
				( objectStatus "@baseboard_fab2_lib.baseboard_fab2(sch_1):page86_i138:vss(67)" )
			)
			( pin "J9L2.57"
				( objectStatus "@baseboard_fab2_lib.baseboard_fab2(sch_1):page86_i138:vss(68)" )
			)
			( pin "J9L2.55"
				( objectStatus "@baseboard_fab2_lib.baseboard_fab2(sch_1):page86_i138:vss(69)" )
			)
			( pin "J9L2.53"
				( objectStatus "@baseboard_fab2_lib.baseboard_fab2(sch_1):page86_i138:vss(70)" )
			)
			( pin "J9L2.50"
				( objectStatus "@baseboard_fab2_lib.baseboard_fab2(sch_1):page86_i138:vss(71)" )
			)
			( pin "J9L2.48"
				( objectStatus "@baseboard_fab2_lib.baseboard_fab2(sch_1):page86_i138:vss(72)" )
			)
			( pin "J9L2.46"
				( objectStatus "@baseboard_fab2_lib.baseboard_fab2(sch_1):page86_i138:vss(73)" )
			)
			( pin "J9L2.44"
				( objectStatus "@baseboard_fab2_lib.baseboard_fab2(sch_1):page86_i138:vss(74)" )
			)
			( pin "J9L2.42"
				( objectStatus "@baseboard_fab2_lib.baseboard_fab2(sch_1):page86_i138:vss(75)" )
			)
			( pin "J9L2.39"
				( objectStatus "@baseboard_fab2_lib.baseboard_fab2(sch_1):page86_i138:vss(76)" )
			)
			( pin "J9L2.37"
				( objectStatus "@baseboard_fab2_lib.baseboard_fab2(sch_1):page86_i138:vss(77)" )
			)
			( pin "J9L2.35"
				( objectStatus "@baseboard_fab2_lib.baseboard_fab2(sch_1):page86_i138:vss(78)" )
			)
			( pin "J9L2.33"
				( objectStatus "@baseboard_fab2_lib.baseboard_fab2(sch_1):page86_i138:vss(79)" )
			)
			( pin "J9L2.31"
				( objectStatus "@baseboard_fab2_lib.baseboard_fab2(sch_1):page86_i138:vss(80)" )
			)
			( pin "J9L2.28"
				( objectStatus "@baseboard_fab2_lib.baseboard_fab2(sch_1):page86_i138:vss(81)" )
			)
			( pin "J9L2.26"
				( objectStatus "@baseboard_fab2_lib.baseboard_fab2(sch_1):page86_i138:vss(82)" )
			)
			( pin "J9L2.24"
				( objectStatus "@baseboard_fab2_lib.baseboard_fab2(sch_1):page86_i138:vss(83)" )
			)
			( pin "J9L2.22"
				( objectStatus "@baseboard_fab2_lib.baseboard_fab2(sch_1):page86_i138:vss(84)" )
			)
			( pin "J9L2.20"
				( objectStatus "@baseboard_fab2_lib.baseboard_fab2(sch_1):page86_i138:vss(85)" )
			)
			( pin "J9L2.17"
				( objectStatus "@baseboard_fab2_lib.baseboard_fab2(sch_1):page86_i138:vss(86)" )
			)
			( pin "J9L2.15"
				( objectStatus "@baseboard_fab2_lib.baseboard_fab2(sch_1):page86_i138:vss(87)" )
			)
			( pin "J9L2.13"
				( objectStatus "@baseboard_fab2_lib.baseboard_fab2(sch_1):page86_i138:vss(88)" )
			)
			( pin "J9L2.11"
				( objectStatus "@baseboard_fab2_lib.baseboard_fab2(sch_1):page86_i138:vss(89)" )
			)
			( pin "J9L2.9"
				( objectStatus "@baseboard_fab2_lib.baseboard_fab2(sch_1):page86_i138:vss(90)" )
			)
			( pin "J9L2.6"
				( objectStatus "@baseboard_fab2_lib.baseboard_fab2(sch_1):page86_i138:vss(91)" )
			)
			( pin "J9L2.4"
				( objectStatus "@baseboard_fab2_lib.baseboard_fab2(sch_1):page86_i138:vss(92)" )
			)
			( pin "J9L2.2"
				( objectStatus "@baseboard_fab2_lib.baseboard_fab2(sch_1):page86_i138:vss(93)" )
			)
			( pin "C1A17.1"
				( objectStatus "@baseboard_fab2_lib.baseboard_fab2(sch_1):page86_i182:a" )
			)
			( pin "C1A17.2"
				( objectStatus "@baseboard_fab2_lib.baseboard_fab2(sch_1):page86_i182:b" )
			)
			( pin "J1A1.145"
				( objectStatus "@baseboard_fab2_lib.baseboard_fab2(sch_1):page87_i169:\12v\(0)" )
			)
			( pin "J1A1.1"
				( objectStatus "@baseboard_fab2_lib.baseboard_fab2(sch_1):page87_i169:\12v\(1)" )
			)
			( pin "J1A1.236"
				( objectStatus "@baseboard_fab2_lib.baseboard_fab2(sch_1):page87_i169:vdd(0)" )
			)
			( pin "J1A1.233"
				( objectStatus "@baseboard_fab2_lib.baseboard_fab2(sch_1):page87_i169:vdd(1)" )
			)
			( pin "J1A1.231"
				( objectStatus "@baseboard_fab2_lib.baseboard_fab2(sch_1):page87_i169:vdd(2)" )
			)
			( pin "J1A1.229"
				( objectStatus "@baseboard_fab2_lib.baseboard_fab2(sch_1):page87_i169:vdd(3)" )
			)
			( pin "J1A1.226"
				( objectStatus "@baseboard_fab2_lib.baseboard_fab2(sch_1):page87_i169:vdd(4)" )
			)
			( pin "J1A1.223"
				( objectStatus "@baseboard_fab2_lib.baseboard_fab2(sch_1):page87_i169:vdd(5)" )
			)
			( pin "J1A1.220"
				( objectStatus "@baseboard_fab2_lib.baseboard_fab2(sch_1):page87_i169:vdd(6)" )
			)
			( pin "J1A1.217"
				( objectStatus "@baseboard_fab2_lib.baseboard_fab2(sch_1):page87_i169:vdd(7)" )
			)
			( pin "J1A1.215"
				( objectStatus "@baseboard_fab2_lib.baseboard_fab2(sch_1):page87_i169:vdd(8)" )
			)
			( pin "J1A1.212"
				( objectStatus "@baseboard_fab2_lib.baseboard_fab2(sch_1):page87_i169:vdd(9)" )
			)
			( pin "J1A1.209"
				( objectStatus "@baseboard_fab2_lib.baseboard_fab2(sch_1):page87_i169:vdd(10)" )
			)
			( pin "J1A1.206"
				( objectStatus "@baseboard_fab2_lib.baseboard_fab2(sch_1):page87_i169:vdd(11)" )
			)
			( pin "J1A1.204"
				( objectStatus "@baseboard_fab2_lib.baseboard_fab2(sch_1):page87_i169:vdd(12)" )
			)
			( pin "J1A1.92"
				( objectStatus "@baseboard_fab2_lib.baseboard_fab2(sch_1):page87_i169:vdd(13)" )
			)
			( pin "J1A1.90"
				( objectStatus "@baseboard_fab2_lib.baseboard_fab2(sch_1):page87_i169:vdd(14)" )
			)
			( pin "J1A1.88"
				( objectStatus "@baseboard_fab2_lib.baseboard_fab2(sch_1):page87_i169:vdd(15)" )
			)
			( pin "J1A1.85"
				( objectStatus "@baseboard_fab2_lib.baseboard_fab2(sch_1):page87_i169:vdd(16)" )
			)
			( pin "J1A1.83"
				( objectStatus "@baseboard_fab2_lib.baseboard_fab2(sch_1):page87_i169:vdd(17)" )
			)
			( pin "J1A1.80"
				( objectStatus "@baseboard_fab2_lib.baseboard_fab2(sch_1):page87_i169:vdd(18)" )
			)
			( pin "J1A1.76"
				( objectStatus "@baseboard_fab2_lib.baseboard_fab2(sch_1):page87_i169:vdd(19)" )
			)
			( pin "J1A1.73"
				( objectStatus "@baseboard_fab2_lib.baseboard_fab2(sch_1):page87_i169:vdd(20)" )
			)
			( pin "J1A1.70"
				( objectStatus "@baseboard_fab2_lib.baseboard_fab2(sch_1):page87_i169:vdd(21)" )
			)
			( pin "J1A1.67"
				( objectStatus "@baseboard_fab2_lib.baseboard_fab2(sch_1):page87_i169:vdd(22)" )
			)
			( pin "J1A1.64"
				( objectStatus "@baseboard_fab2_lib.baseboard_fab2(sch_1):page87_i169:vdd(23)" )
			)
			( pin "J1A1.61"
				( objectStatus "@baseboard_fab2_lib.baseboard_fab2(sch_1):page87_i169:vdd(24)" )
			)
			( pin "J1A1.59"
				( objectStatus "@baseboard_fab2_lib.baseboard_fab2(sch_1):page87_i169:vdd(25)" )
			)
			( pin "J1A1.287"
				( objectStatus "@baseboard_fab2_lib.baseboard_fab2(sch_1):page87_i169:vpp(0)" )
			)
			( pin "J1A1.286"
				( objectStatus "@baseboard_fab2_lib.baseboard_fab2(sch_1):page87_i169:vpp(1)" )
			)
			( pin "J1A1.288"
				( objectStatus "@baseboard_fab2_lib.baseboard_fab2(sch_1):page87_i169:vpp(2)" )
			)
			( pin "J1A1.143"
				( objectStatus "@baseboard_fab2_lib.baseboard_fab2(sch_1):page87_i169:vpp(3)" )
			)
			( pin "J1A1.142"
				( objectStatus "@baseboard_fab2_lib.baseboard_fab2(sch_1):page87_i169:vpp(4)" )
			)
			( pin "J1A1.221"
				( objectStatus "@baseboard_fab2_lib.baseboard_fab2(sch_1):page87_i169:vtt(0)" )
			)
			( pin "J1A1.77"
				( objectStatus "@baseboard_fab2_lib.baseboard_fab2(sch_1):page87_i169:vtt(1)" )
			)
			( pin "C1A5.1"
				( objectStatus "@baseboard_fab2_lib.baseboard_fab2(sch_1):page87_i178:a" )
			)
			( pin "C1A5.2"
				( objectStatus "@baseboard_fab2_lib.baseboard_fab2(sch_1):page87_i178:b" )
			)
			( pin "J1A1.283"
				( objectStatus "@baseboard_fab2_lib.baseboard_fab2(sch_1):page87_i185:vss(0)" )
			)
			( pin "J1A1.281"
				( objectStatus "@baseboard_fab2_lib.baseboard_fab2(sch_1):page87_i185:vss(1)" )
			)
			( pin "J1A1.279"
				( objectStatus "@baseboard_fab2_lib.baseboard_fab2(sch_1):page87_i185:vss(2)" )
			)
			( pin "J1A1.276"
				( objectStatus "@baseboard_fab2_lib.baseboard_fab2(sch_1):page87_i185:vss(3)" )
			)
			( pin "J1A1.274"
				( objectStatus "@baseboard_fab2_lib.baseboard_fab2(sch_1):page87_i185:vss(4)" )
			)
			( pin "J1A1.272"
				( objectStatus "@baseboard_fab2_lib.baseboard_fab2(sch_1):page87_i185:vss(5)" )
			)
			( pin "J1A1.270"
				( objectStatus "@baseboard_fab2_lib.baseboard_fab2(sch_1):page87_i185:vss(6)" )
			)
			( pin "J1A1.268"
				( objectStatus "@baseboard_fab2_lib.baseboard_fab2(sch_1):page87_i185:vss(7)" )
			)
			( pin "J1A1.265"
				( objectStatus "@baseboard_fab2_lib.baseboard_fab2(sch_1):page87_i185:vss(8)" )
			)
			( pin "J1A1.263"
				( objectStatus "@baseboard_fab2_lib.baseboard_fab2(sch_1):page87_i185:vss(9)" )
			)
			( pin "J1A1.261"
				( objectStatus "@baseboard_fab2_lib.baseboard_fab2(sch_1):page87_i185:vss(10)" )
			)
			( pin "J1A1.259"
				( objectStatus "@baseboard_fab2_lib.baseboard_fab2(sch_1):page87_i185:vss(11)" )
			)
			( pin "J1A1.257"
				( objectStatus "@baseboard_fab2_lib.baseboard_fab2(sch_1):page87_i185:vss(12)" )
			)
			( pin "J1A1.254"
				( objectStatus "@baseboard_fab2_lib.baseboard_fab2(sch_1):page87_i185:vss(13)" )
			)
			( pin "J1A1.252"
				( objectStatus "@baseboard_fab2_lib.baseboard_fab2(sch_1):page87_i185:vss(14)" )
			)
			( pin "J1A1.250"
				( objectStatus "@baseboard_fab2_lib.baseboard_fab2(sch_1):page87_i185:vss(15)" )
			)
			( pin "J1A1.248"
				( objectStatus "@baseboard_fab2_lib.baseboard_fab2(sch_1):page87_i185:vss(16)" )
			)
			( pin "J1A1.246"
				( objectStatus "@baseboard_fab2_lib.baseboard_fab2(sch_1):page87_i185:vss(17)" )
			)
			( pin "J1A1.243"
				( objectStatus "@baseboard_fab2_lib.baseboard_fab2(sch_1):page87_i185:vss(18)" )
			)
			( pin "J1A1.241"
				( objectStatus "@baseboard_fab2_lib.baseboard_fab2(sch_1):page87_i185:vss(19)" )
			)
			( pin "J1A1.239"
				( objectStatus "@baseboard_fab2_lib.baseboard_fab2(sch_1):page87_i185:vss(20)" )
			)
			( pin "J1A1.202"
				( objectStatus "@baseboard_fab2_lib.baseboard_fab2(sch_1):page87_i185:vss(21)" )
			)
			( pin "J1A1.200"
				( objectStatus "@baseboard_fab2_lib.baseboard_fab2(sch_1):page87_i185:vss(22)" )
			)
			( pin "J1A1.198"
				( objectStatus "@baseboard_fab2_lib.baseboard_fab2(sch_1):page87_i185:vss(23)" )
			)
			( pin "J1A1.195"
				( objectStatus "@baseboard_fab2_lib.baseboard_fab2(sch_1):page87_i185:vss(24)" )
			)
			( pin "J1A1.193"
				( objectStatus "@baseboard_fab2_lib.baseboard_fab2(sch_1):page87_i185:vss(25)" )
			)
			( pin "J1A1.191"
				( objectStatus "@baseboard_fab2_lib.baseboard_fab2(sch_1):page87_i185:vss(26)" )
			)
			( pin "J1A1.189"
				( objectStatus "@baseboard_fab2_lib.baseboard_fab2(sch_1):page87_i185:vss(27)" )
			)
			( pin "J1A1.187"
				( objectStatus "@baseboard_fab2_lib.baseboard_fab2(sch_1):page87_i185:vss(28)" )
			)
			( pin "J1A1.184"
				( objectStatus "@baseboard_fab2_lib.baseboard_fab2(sch_1):page87_i185:vss(29)" )
			)
			( pin "J1A1.182"
				( objectStatus "@baseboard_fab2_lib.baseboard_fab2(sch_1):page87_i185:vss(30)" )
			)
			( pin "J1A1.180"
				( objectStatus "@baseboard_fab2_lib.baseboard_fab2(sch_1):page87_i185:vss(31)" )
			)
			( pin "J1A1.178"
				( objectStatus "@baseboard_fab2_lib.baseboard_fab2(sch_1):page87_i185:vss(32)" )
			)
			( pin "J1A1.176"
				( objectStatus "@baseboard_fab2_lib.baseboard_fab2(sch_1):page87_i185:vss(33)" )
			)
			( pin "J1A1.173"
				( objectStatus "@baseboard_fab2_lib.baseboard_fab2(sch_1):page87_i185:vss(34)" )
			)
			( pin "J1A1.171"
				( objectStatus "@baseboard_fab2_lib.baseboard_fab2(sch_1):page87_i185:vss(35)" )
			)
			( pin "J1A1.169"
				( objectStatus "@baseboard_fab2_lib.baseboard_fab2(sch_1):page87_i185:vss(36)" )
			)
			( pin "J1A1.167"
				( objectStatus "@baseboard_fab2_lib.baseboard_fab2(sch_1):page87_i185:vss(37)" )
			)
			( pin "J1A1.165"
				( objectStatus "@baseboard_fab2_lib.baseboard_fab2(sch_1):page87_i185:vss(38)" )
			)
			( pin "J1A1.162"
				( objectStatus "@baseboard_fab2_lib.baseboard_fab2(sch_1):page87_i185:vss(39)" )
			)
			( pin "J1A1.160"
				( objectStatus "@baseboard_fab2_lib.baseboard_fab2(sch_1):page87_i185:vss(40)" )
			)
			( pin "J1A1.158"
				( objectStatus "@baseboard_fab2_lib.baseboard_fab2(sch_1):page87_i185:vss(41)" )
			)
			( pin "J1A1.156"
				( objectStatus "@baseboard_fab2_lib.baseboard_fab2(sch_1):page87_i185:vss(42)" )
			)
			( pin "J1A1.154"
				( objectStatus "@baseboard_fab2_lib.baseboard_fab2(sch_1):page87_i185:vss(43)" )
			)
			( pin "J1A1.151"
				( objectStatus "@baseboard_fab2_lib.baseboard_fab2(sch_1):page87_i185:vss(44)" )
			)
			( pin "J1A1.149"
				( objectStatus "@baseboard_fab2_lib.baseboard_fab2(sch_1):page87_i185:vss(45)" )
			)
			( pin "J1A1.147"
				( objectStatus "@baseboard_fab2_lib.baseboard_fab2(sch_1):page87_i185:vss(46)" )
			)
			( pin "J1A1.138"
				( objectStatus "@baseboard_fab2_lib.baseboard_fab2(sch_1):page87_i185:vss(47)" )
			)
			( pin "J1A1.136"
				( objectStatus "@baseboard_fab2_lib.baseboard_fab2(sch_1):page87_i185:vss(48)" )
			)
			( pin "J1A1.134"
				( objectStatus "@baseboard_fab2_lib.baseboard_fab2(sch_1):page87_i185:vss(49)" )
			)
			( pin "J1A1.131"
				( objectStatus "@baseboard_fab2_lib.baseboard_fab2(sch_1):page87_i185:vss(50)" )
			)
			( pin "J1A1.129"
				( objectStatus "@baseboard_fab2_lib.baseboard_fab2(sch_1):page87_i185:vss(51)" )
			)
			( pin "J1A1.127"
				( objectStatus "@baseboard_fab2_lib.baseboard_fab2(sch_1):page87_i185:vss(52)" )
			)
			( pin "J1A1.125"
				( objectStatus "@baseboard_fab2_lib.baseboard_fab2(sch_1):page87_i185:vss(53)" )
			)
			( pin "J1A1.123"
				( objectStatus "@baseboard_fab2_lib.baseboard_fab2(sch_1):page87_i185:vss(54)" )
			)
			( pin "J1A1.120"
				( objectStatus "@baseboard_fab2_lib.baseboard_fab2(sch_1):page87_i185:vss(55)" )
			)
			( pin "J1A1.118"
				( objectStatus "@baseboard_fab2_lib.baseboard_fab2(sch_1):page87_i185:vss(56)" )
			)
			( pin "J1A1.116"
				( objectStatus "@baseboard_fab2_lib.baseboard_fab2(sch_1):page87_i185:vss(57)" )
			)
			( pin "J1A1.114"
				( objectStatus "@baseboard_fab2_lib.baseboard_fab2(sch_1):page87_i185:vss(58)" )
			)
			( pin "J1A1.112"
				( objectStatus "@baseboard_fab2_lib.baseboard_fab2(sch_1):page87_i185:vss(59)" )
			)
			( pin "J1A1.109"
				( objectStatus "@baseboard_fab2_lib.baseboard_fab2(sch_1):page87_i185:vss(60)" )
			)
			( pin "J1A1.107"
				( objectStatus "@baseboard_fab2_lib.baseboard_fab2(sch_1):page87_i185:vss(61)" )
			)
			( pin "J1A1.105"
				( objectStatus "@baseboard_fab2_lib.baseboard_fab2(sch_1):page87_i185:vss(62)" )
			)
			( pin "J1A1.103"
				( objectStatus "@baseboard_fab2_lib.baseboard_fab2(sch_1):page87_i185:vss(63)" )
			)
			( pin "J1A1.101"
				( objectStatus "@baseboard_fab2_lib.baseboard_fab2(sch_1):page87_i185:vss(64)" )
			)
			( pin "J1A1.98"
				( objectStatus "@baseboard_fab2_lib.baseboard_fab2(sch_1):page87_i185:vss(65)" )
			)
			( pin "J1A1.96"
				( objectStatus "@baseboard_fab2_lib.baseboard_fab2(sch_1):page87_i185:vss(66)" )
			)
			( pin "J1A1.94"
				( objectStatus "@baseboard_fab2_lib.baseboard_fab2(sch_1):page87_i185:vss(67)" )
			)
			( pin "J1A1.57"
				( objectStatus "@baseboard_fab2_lib.baseboard_fab2(sch_1):page87_i185:vss(68)" )
			)
			( pin "J1A1.55"
				( objectStatus "@baseboard_fab2_lib.baseboard_fab2(sch_1):page87_i185:vss(69)" )
			)
			( pin "J1A1.53"
				( objectStatus "@baseboard_fab2_lib.baseboard_fab2(sch_1):page87_i185:vss(70)" )
			)
			( pin "J1A1.50"
				( objectStatus "@baseboard_fab2_lib.baseboard_fab2(sch_1):page87_i185:vss(71)" )
			)
			( pin "J1A1.48"
				( objectStatus "@baseboard_fab2_lib.baseboard_fab2(sch_1):page87_i185:vss(72)" )
			)
			( pin "J1A1.46"
				( objectStatus "@baseboard_fab2_lib.baseboard_fab2(sch_1):page87_i185:vss(73)" )
			)
			( pin "J1A1.44"
				( objectStatus "@baseboard_fab2_lib.baseboard_fab2(sch_1):page87_i185:vss(74)" )
			)
			( pin "J1A1.42"
				( objectStatus "@baseboard_fab2_lib.baseboard_fab2(sch_1):page87_i185:vss(75)" )
			)
			( pin "J1A1.39"
				( objectStatus "@baseboard_fab2_lib.baseboard_fab2(sch_1):page87_i185:vss(76)" )
			)
			( pin "J1A1.37"
				( objectStatus "@baseboard_fab2_lib.baseboard_fab2(sch_1):page87_i185:vss(77)" )
			)
			( pin "J1A1.35"
				( objectStatus "@baseboard_fab2_lib.baseboard_fab2(sch_1):page87_i185:vss(78)" )
			)
			( pin "J1A1.33"
				( objectStatus "@baseboard_fab2_lib.baseboard_fab2(sch_1):page87_i185:vss(79)" )
			)
			( pin "J1A1.31"
				( objectStatus "@baseboard_fab2_lib.baseboard_fab2(sch_1):page87_i185:vss(80)" )
			)
			( pin "J1A1.28"
				( objectStatus "@baseboard_fab2_lib.baseboard_fab2(sch_1):page87_i185:vss(81)" )
			)
			( pin "J1A1.26"
				( objectStatus "@baseboard_fab2_lib.baseboard_fab2(sch_1):page87_i185:vss(82)" )
			)
			( pin "J1A1.24"
				( objectStatus "@baseboard_fab2_lib.baseboard_fab2(sch_1):page87_i185:vss(83)" )
			)
			( pin "J1A1.22"
				( objectStatus "@baseboard_fab2_lib.baseboard_fab2(sch_1):page87_i185:vss(84)" )
			)
			( pin "J1A1.20"
				( objectStatus "@baseboard_fab2_lib.baseboard_fab2(sch_1):page87_i185:vss(85)" )
			)
			( pin "J1A1.17"
				( objectStatus "@baseboard_fab2_lib.baseboard_fab2(sch_1):page87_i185:vss(86)" )
			)
			( pin "J1A1.15"
				( objectStatus "@baseboard_fab2_lib.baseboard_fab2(sch_1):page87_i185:vss(87)" )
			)
			( pin "J1A1.13"
				( objectStatus "@baseboard_fab2_lib.baseboard_fab2(sch_1):page87_i185:vss(88)" )
			)
			( pin "J1A1.11"
				( objectStatus "@baseboard_fab2_lib.baseboard_fab2(sch_1):page87_i185:vss(89)" )
			)
			( pin "J1A1.9"
				( objectStatus "@baseboard_fab2_lib.baseboard_fab2(sch_1):page87_i185:vss(90)" )
			)
			( pin "J1A1.6"
				( objectStatus "@baseboard_fab2_lib.baseboard_fab2(sch_1):page87_i185:vss(91)" )
			)
			( pin "J1A1.4"
				( objectStatus "@baseboard_fab2_lib.baseboard_fab2(sch_1):page87_i185:vss(92)" )
			)
			( pin "J1A1.2"
				( objectStatus "@baseboard_fab2_lib.baseboard_fab2(sch_1):page87_i185:vss(93)" )
			)
			( pin "J1A1.79"
				( objectStatus "@baseboard_fab2_lib.baseboard_fab2(sch_1):page87_i186:a0" )
			)
			( pin "J1A1.72"
				( objectStatus "@baseboard_fab2_lib.baseboard_fab2(sch_1):page87_i186:a1" )
			)
			( pin "J1A1.216"
				( objectStatus "@baseboard_fab2_lib.baseboard_fab2(sch_1):page87_i186:a2" )
			)
			( pin "J1A1.71"
				( objectStatus "@baseboard_fab2_lib.baseboard_fab2(sch_1):page87_i186:a3" )
			)
			( pin "J1A1.214"
				( objectStatus "@baseboard_fab2_lib.baseboard_fab2(sch_1):page87_i186:a4" )
			)
			( pin "J1A1.213"
				( objectStatus "@baseboard_fab2_lib.baseboard_fab2(sch_1):page87_i186:a5" )
			)
			( pin "J1A1.69"
				( objectStatus "@baseboard_fab2_lib.baseboard_fab2(sch_1):page87_i186:a6" )
			)
			( pin "J1A1.211"
				( objectStatus "@baseboard_fab2_lib.baseboard_fab2(sch_1):page87_i186:a7" )
			)
			( pin "J1A1.68"
				( objectStatus "@baseboard_fab2_lib.baseboard_fab2(sch_1):page87_i186:a8" )
			)
			( pin "J1A1.66"
				( objectStatus "@baseboard_fab2_lib.baseboard_fab2(sch_1):page87_i186:a9" )
			)
			( pin "J1A1.225"
				( objectStatus "@baseboard_fab2_lib.baseboard_fab2(sch_1):page87_i186:a10" )
			)
			( pin "J1A1.210"
				( objectStatus "@baseboard_fab2_lib.baseboard_fab2(sch_1):page87_i186:a11" )
			)
			( pin "J1A1.65"
				( objectStatus "@baseboard_fab2_lib.baseboard_fab2(sch_1):page87_i186:a12" )
			)
			( pin "J1A1.232"
				( objectStatus "@baseboard_fab2_lib.baseboard_fab2(sch_1):page87_i186:a13" )
			)
			( pin "J1A1.228"
				( objectStatus "@baseboard_fab2_lib.baseboard_fab2(sch_1):page87_i186:a14_we_n" )
			)
			( pin "J1A1.86"
				( objectStatus "@baseboard_fab2_lib.baseboard_fab2(sch_1):page87_i186:a15_cas_n" )
			)
			( pin "J1A1.82"
				( objectStatus "@baseboard_fab2_lib.baseboard_fab2(sch_1):page87_i186:a16_ras_n" )
			)
			( pin "J1A1.234"
				( objectStatus "@baseboard_fab2_lib.baseboard_fab2(sch_1):page87_i186:a17" )
			)
			( pin "J1A1.62"
				( objectStatus "@baseboard_fab2_lib.baseboard_fab2(sch_1):page87_i186:act_n" )
			)
			( pin "J1A1.208"
				( objectStatus "@baseboard_fab2_lib.baseboard_fab2(sch_1):page87_i186:alert_n" )
			)
			( pin "J1A1.81"
				( objectStatus "@baseboard_fab2_lib.baseboard_fab2(sch_1):page87_i186:ba(0)" )
			)
			( pin "J1A1.224"
				( objectStatus "@baseboard_fab2_lib.baseboard_fab2(sch_1):page87_i186:ba(1)" )
			)
			( pin "J1A1.63"
				( objectStatus "@baseboard_fab2_lib.baseboard_fab2(sch_1):page87_i186:bg(0)" )
			)
			( pin "J1A1.207"
				( objectStatus "@baseboard_fab2_lib.baseboard_fab2(sch_1):page87_i186:bg(1)" )
			)
			( pin "J1A1.235"
				( objectStatus "@baseboard_fab2_lib.baseboard_fab2(sch_1):page87_i186:c(2)" )
			)
			( pin "J1A1.49"
				( objectStatus "@baseboard_fab2_lib.baseboard_fab2(sch_1):page87_i186:cb(0)" )
			)
			( pin "J1A1.194"
				( objectStatus "@baseboard_fab2_lib.baseboard_fab2(sch_1):page87_i186:cb(1)" )
			)
			( pin "J1A1.56"
				( objectStatus "@baseboard_fab2_lib.baseboard_fab2(sch_1):page87_i186:cb(2)" )
			)
			( pin "J1A1.201"
				( objectStatus "@baseboard_fab2_lib.baseboard_fab2(sch_1):page87_i186:cb(3)" )
			)
			( pin "J1A1.47"
				( objectStatus "@baseboard_fab2_lib.baseboard_fab2(sch_1):page87_i186:cb(4)" )
			)
			( pin "J1A1.192"
				( objectStatus "@baseboard_fab2_lib.baseboard_fab2(sch_1):page87_i186:cb(5)" )
			)
			( pin "J1A1.54"
				( objectStatus "@baseboard_fab2_lib.baseboard_fab2(sch_1):page87_i186:cb(6)" )
			)
			( pin "J1A1.199"
				( objectStatus "@baseboard_fab2_lib.baseboard_fab2(sch_1):page87_i186:cb(7)" )
			)
			( pin "J1A1.75"
				( objectStatus "@baseboard_fab2_lib.baseboard_fab2(sch_1):page87_i186:ck0n" )
			)
			( pin "J1A1.74"
				( objectStatus "@baseboard_fab2_lib.baseboard_fab2(sch_1):page87_i186:ck0p" )
			)
			( pin "J1A1.219"
				( objectStatus "@baseboard_fab2_lib.baseboard_fab2(sch_1):page87_i186:ck1n" )
			)
			( pin "J1A1.218"
				( objectStatus "@baseboard_fab2_lib.baseboard_fab2(sch_1):page87_i186:ck1p" )
			)
			( pin "J1A1.60"
				( objectStatus "@baseboard_fab2_lib.baseboard_fab2(sch_1):page87_i186:cke(0)" )
			)
			( pin "J1A1.203"
				( objectStatus "@baseboard_fab2_lib.baseboard_fab2(sch_1):page87_i186:cke(1)" )
			)
			( pin "J1A1.5"
				( objectStatus "@baseboard_fab2_lib.baseboard_fab2(sch_1):page87_i186:dq(0)" )
			)
			( pin "J1A1.150"
				( objectStatus "@baseboard_fab2_lib.baseboard_fab2(sch_1):page87_i186:dq(1)" )
			)
			( pin "J1A1.12"
				( objectStatus "@baseboard_fab2_lib.baseboard_fab2(sch_1):page87_i186:dq(2)" )
			)
			( pin "J1A1.157"
				( objectStatus "@baseboard_fab2_lib.baseboard_fab2(sch_1):page87_i186:dq(3)" )
			)
			( pin "J1A1.3"
				( objectStatus "@baseboard_fab2_lib.baseboard_fab2(sch_1):page87_i186:dq(4)" )
			)
			( pin "J1A1.148"
				( objectStatus "@baseboard_fab2_lib.baseboard_fab2(sch_1):page87_i186:dq(5)" )
			)
			( pin "J1A1.10"
				( objectStatus "@baseboard_fab2_lib.baseboard_fab2(sch_1):page87_i186:dq(6)" )
			)
			( pin "J1A1.155"
				( objectStatus "@baseboard_fab2_lib.baseboard_fab2(sch_1):page87_i186:dq(7)" )
			)
			( pin "J1A1.16"
				( objectStatus "@baseboard_fab2_lib.baseboard_fab2(sch_1):page87_i186:dq(8)" )
			)
			( pin "J1A1.161"
				( objectStatus "@baseboard_fab2_lib.baseboard_fab2(sch_1):page87_i186:dq(9)" )
			)
			( pin "J1A1.23"
				( objectStatus "@baseboard_fab2_lib.baseboard_fab2(sch_1):page87_i186:dq(10)" )
			)
			( pin "J1A1.168"
				( objectStatus "@baseboard_fab2_lib.baseboard_fab2(sch_1):page87_i186:dq(11)" )
			)
			( pin "J1A1.14"
				( objectStatus "@baseboard_fab2_lib.baseboard_fab2(sch_1):page87_i186:dq(12)" )
			)
			( pin "J1A1.159"
				( objectStatus "@baseboard_fab2_lib.baseboard_fab2(sch_1):page87_i186:dq(13)" )
			)
			( pin "J1A1.21"
				( objectStatus "@baseboard_fab2_lib.baseboard_fab2(sch_1):page87_i186:dq(14)" )
			)
			( pin "J1A1.166"
				( objectStatus "@baseboard_fab2_lib.baseboard_fab2(sch_1):page87_i186:dq(15)" )
			)
			( pin "J1A1.27"
				( objectStatus "@baseboard_fab2_lib.baseboard_fab2(sch_1):page87_i186:dq(16)" )
			)
			( pin "J1A1.172"
				( objectStatus "@baseboard_fab2_lib.baseboard_fab2(sch_1):page87_i186:dq(17)" )
			)
			( pin "J1A1.34"
				( objectStatus "@baseboard_fab2_lib.baseboard_fab2(sch_1):page87_i186:dq(18)" )
			)
			( pin "J1A1.179"
				( objectStatus "@baseboard_fab2_lib.baseboard_fab2(sch_1):page87_i186:dq(19)" )
			)
			( pin "J1A1.25"
				( objectStatus "@baseboard_fab2_lib.baseboard_fab2(sch_1):page87_i186:dq(20)" )
			)
			( pin "J1A1.170"
				( objectStatus "@baseboard_fab2_lib.baseboard_fab2(sch_1):page87_i186:dq(21)" )
			)
			( pin "J1A1.32"
				( objectStatus "@baseboard_fab2_lib.baseboard_fab2(sch_1):page87_i186:dq(22)" )
			)
			( pin "J1A1.177"
				( objectStatus "@baseboard_fab2_lib.baseboard_fab2(sch_1):page87_i186:dq(23)" )
			)
			( pin "J1A1.38"
				( objectStatus "@baseboard_fab2_lib.baseboard_fab2(sch_1):page87_i186:dq(24)" )
			)
			( pin "J1A1.183"
				( objectStatus "@baseboard_fab2_lib.baseboard_fab2(sch_1):page87_i186:dq(25)" )
			)
			( pin "J1A1.45"
				( objectStatus "@baseboard_fab2_lib.baseboard_fab2(sch_1):page87_i186:dq(26)" )
			)
			( pin "J1A1.190"
				( objectStatus "@baseboard_fab2_lib.baseboard_fab2(sch_1):page87_i186:dq(27)" )
			)
			( pin "J1A1.36"
				( objectStatus "@baseboard_fab2_lib.baseboard_fab2(sch_1):page87_i186:dq(28)" )
			)
			( pin "J1A1.181"
				( objectStatus "@baseboard_fab2_lib.baseboard_fab2(sch_1):page87_i186:dq(29)" )
			)
			( pin "J1A1.43"
				( objectStatus "@baseboard_fab2_lib.baseboard_fab2(sch_1):page87_i186:dq(30)" )
			)
			( pin "J1A1.188"
				( objectStatus "@baseboard_fab2_lib.baseboard_fab2(sch_1):page87_i186:dq(31)" )
			)
			( pin "J1A1.97"
				( objectStatus "@baseboard_fab2_lib.baseboard_fab2(sch_1):page87_i186:dq(32)" )
			)
			( pin "J1A1.242"
				( objectStatus "@baseboard_fab2_lib.baseboard_fab2(sch_1):page87_i186:dq(33)" )
			)
			( pin "J1A1.104"
				( objectStatus "@baseboard_fab2_lib.baseboard_fab2(sch_1):page87_i186:dq(34)" )
			)
			( pin "J1A1.249"
				( objectStatus "@baseboard_fab2_lib.baseboard_fab2(sch_1):page87_i186:dq(35)" )
			)
			( pin "J1A1.95"
				( objectStatus "@baseboard_fab2_lib.baseboard_fab2(sch_1):page87_i186:dq(36)" )
			)
			( pin "J1A1.240"
				( objectStatus "@baseboard_fab2_lib.baseboard_fab2(sch_1):page87_i186:dq(37)" )
			)
			( pin "J1A1.102"
				( objectStatus "@baseboard_fab2_lib.baseboard_fab2(sch_1):page87_i186:dq(38)" )
			)
			( pin "J1A1.247"
				( objectStatus "@baseboard_fab2_lib.baseboard_fab2(sch_1):page87_i186:dq(39)" )
			)
			( pin "J1A1.108"
				( objectStatus "@baseboard_fab2_lib.baseboard_fab2(sch_1):page87_i186:dq(40)" )
			)
			( pin "J1A1.253"
				( objectStatus "@baseboard_fab2_lib.baseboard_fab2(sch_1):page87_i186:dq(41)" )
			)
			( pin "J1A1.115"
				( objectStatus "@baseboard_fab2_lib.baseboard_fab2(sch_1):page87_i186:dq(42)" )
			)
			( pin "J1A1.260"
				( objectStatus "@baseboard_fab2_lib.baseboard_fab2(sch_1):page87_i186:dq(43)" )
			)
			( pin "J1A1.106"
				( objectStatus "@baseboard_fab2_lib.baseboard_fab2(sch_1):page87_i186:dq(44)" )
			)
			( pin "J1A1.251"
				( objectStatus "@baseboard_fab2_lib.baseboard_fab2(sch_1):page87_i186:dq(45)" )
			)
			( pin "J1A1.113"
				( objectStatus "@baseboard_fab2_lib.baseboard_fab2(sch_1):page87_i186:dq(46)" )
			)
			( pin "J1A1.258"
				( objectStatus "@baseboard_fab2_lib.baseboard_fab2(sch_1):page87_i186:dq(47)" )
			)
			( pin "J1A1.119"
				( objectStatus "@baseboard_fab2_lib.baseboard_fab2(sch_1):page87_i186:dq(48)" )
			)
			( pin "J1A1.264"
				( objectStatus "@baseboard_fab2_lib.baseboard_fab2(sch_1):page87_i186:dq(49)" )
			)
			( pin "J1A1.126"
				( objectStatus "@baseboard_fab2_lib.baseboard_fab2(sch_1):page87_i186:dq(50)" )
			)
			( pin "J1A1.271"
				( objectStatus "@baseboard_fab2_lib.baseboard_fab2(sch_1):page87_i186:dq(51)" )
			)
			( pin "J1A1.117"
				( objectStatus "@baseboard_fab2_lib.baseboard_fab2(sch_1):page87_i186:dq(52)" )
			)
			( pin "J1A1.262"
				( objectStatus "@baseboard_fab2_lib.baseboard_fab2(sch_1):page87_i186:dq(53)" )
			)
			( pin "J1A1.124"
				( objectStatus "@baseboard_fab2_lib.baseboard_fab2(sch_1):page87_i186:dq(54)" )
			)
			( pin "J1A1.269"
				( objectStatus "@baseboard_fab2_lib.baseboard_fab2(sch_1):page87_i186:dq(55)" )
			)
			( pin "J1A1.130"
				( objectStatus "@baseboard_fab2_lib.baseboard_fab2(sch_1):page87_i186:dq(56)" )
			)
			( pin "J1A1.275"
				( objectStatus "@baseboard_fab2_lib.baseboard_fab2(sch_1):page87_i186:dq(57)" )
			)
			( pin "J1A1.137"
				( objectStatus "@baseboard_fab2_lib.baseboard_fab2(sch_1):page87_i186:dq(58)" )
			)
			( pin "J1A1.282"
				( objectStatus "@baseboard_fab2_lib.baseboard_fab2(sch_1):page87_i186:dq(59)" )
			)
			( pin "J1A1.128"
				( objectStatus "@baseboard_fab2_lib.baseboard_fab2(sch_1):page87_i186:dq(60)" )
			)
			( pin "J1A1.273"
				( objectStatus "@baseboard_fab2_lib.baseboard_fab2(sch_1):page87_i186:dq(61)" )
			)
			( pin "J1A1.135"
				( objectStatus "@baseboard_fab2_lib.baseboard_fab2(sch_1):page87_i186:dq(62)" )
			)
			( pin "J1A1.280"
				( objectStatus "@baseboard_fab2_lib.baseboard_fab2(sch_1):page87_i186:dq(63)" )
			)
			( pin "J1A1.78"
				( objectStatus "@baseboard_fab2_lib.baseboard_fab2(sch_1):page87_i186:event_n" )
			)
			( pin "J1A1.87"
				( objectStatus "@baseboard_fab2_lib.baseboard_fab2(sch_1):page87_i186:odt(0)" )
			)
			( pin "J1A1.91"
				( objectStatus "@baseboard_fab2_lib.baseboard_fab2(sch_1):page87_i186:odt(1)" )
			)
			( pin "J1A1.222"
				( objectStatus "@baseboard_fab2_lib.baseboard_fab2(sch_1):page87_i186:par" )
			)
			( pin "J1A1.58"
				( objectStatus "@baseboard_fab2_lib.baseboard_fab2(sch_1):page87_i186:reset_n" )
			)
			( pin "J1A1.205"
				( objectStatus "@baseboard_fab2_lib.baseboard_fab2(sch_1):page87_i186:rfu(0)" )
			)
			( pin "J1A1.227"
				( objectStatus "@baseboard_fab2_lib.baseboard_fab2(sch_1):page87_i186:rfu(1)" )
			)
			( pin "J1A1.144"
				( objectStatus "@baseboard_fab2_lib.baseboard_fab2(sch_1):page87_i186:rfu(2)" )
			)
			( pin "J1A1.84"
				( objectStatus "@baseboard_fab2_lib.baseboard_fab2(sch_1):page87_i186:s0_n" )
			)
			( pin "J1A1.89"
				( objectStatus "@baseboard_fab2_lib.baseboard_fab2(sch_1):page87_i186:s1_n" )
			)
			( pin "J1A1.93"
				( objectStatus "@baseboard_fab2_lib.baseboard_fab2(sch_1):page87_i186:s2_n_c(0)" )
			)
			( pin "J1A1.237"
				( objectStatus "@baseboard_fab2_lib.baseboard_fab2(sch_1):page87_i186:s3_n_c(1)" )
			)
			( pin "J1A1.139"
				( objectStatus "@baseboard_fab2_lib.baseboard_fab2(sch_1):page87_i186:sa(0)" )
			)
			( pin "J1A1.140"
				( objectStatus "@baseboard_fab2_lib.baseboard_fab2(sch_1):page87_i186:sa(1)" )
			)
			( pin "J1A1.238"
				( objectStatus "@baseboard_fab2_lib.baseboard_fab2(sch_1):page87_i186:sa(2)" )
			)
			( pin "J1A1.230"
				( objectStatus "@baseboard_fab2_lib.baseboard_fab2(sch_1):page87_i186:save_n_nc" )
			)
			( pin "J1A1.141"
				( objectStatus "@baseboard_fab2_lib.baseboard_fab2(sch_1):page87_i186:scl" )
			)
			( pin "J1A1.285"
				( objectStatus "@baseboard_fab2_lib.baseboard_fab2(sch_1):page87_i186:sda" )
			)
			( pin "J1A1.284"
				( objectStatus "@baseboard_fab2_lib.baseboard_fab2(sch_1):page87_i186:vddspd" )
			)
			( pin "J1A1.146"
				( objectStatus "@baseboard_fab2_lib.baseboard_fab2(sch_1):page87_i186:vrefca" )
			)
			( pin "J1A1.152"
				( objectStatus "@baseboard_fab2_lib.baseboard_fab2(sch_1):page87_i187:dqs0n" )
			)
			( pin "J1A1.153"
				( objectStatus "@baseboard_fab2_lib.baseboard_fab2(sch_1):page87_i187:dqs0p" )
			)
			( pin "J1A1.163"
				( objectStatus "@baseboard_fab2_lib.baseboard_fab2(sch_1):page87_i187:dqs1n" )
			)
			( pin "J1A1.164"
				( objectStatus "@baseboard_fab2_lib.baseboard_fab2(sch_1):page87_i187:dqs1p" )
			)
			( pin "J1A1.174"
				( objectStatus "@baseboard_fab2_lib.baseboard_fab2(sch_1):page87_i187:dqs2n" )
			)
			( pin "J1A1.175"
				( objectStatus "@baseboard_fab2_lib.baseboard_fab2(sch_1):page87_i187:dqs2p" )
			)
			( pin "J1A1.185"
				( objectStatus "@baseboard_fab2_lib.baseboard_fab2(sch_1):page87_i187:dqs3n" )
			)
			( pin "J1A1.186"
				( objectStatus "@baseboard_fab2_lib.baseboard_fab2(sch_1):page87_i187:dqs3p" )
			)
			( pin "J1A1.244"
				( objectStatus "@baseboard_fab2_lib.baseboard_fab2(sch_1):page87_i187:dqs4n" )
			)
			( pin "J1A1.245"
				( objectStatus "@baseboard_fab2_lib.baseboard_fab2(sch_1):page87_i187:dqs4p" )
			)
			( pin "J1A1.255"
				( objectStatus "@baseboard_fab2_lib.baseboard_fab2(sch_1):page87_i187:dqs5n" )
			)
			( pin "J1A1.256"
				( objectStatus "@baseboard_fab2_lib.baseboard_fab2(sch_1):page87_i187:dqs5p" )
			)
			( pin "J1A1.266"
				( objectStatus "@baseboard_fab2_lib.baseboard_fab2(sch_1):page87_i187:dqs6n" )
			)
			( pin "J1A1.267"
				( objectStatus "@baseboard_fab2_lib.baseboard_fab2(sch_1):page87_i187:dqs6p" )
			)
			( pin "J1A1.277"
				( objectStatus "@baseboard_fab2_lib.baseboard_fab2(sch_1):page87_i187:dqs7n" )
			)
			( pin "J1A1.278"
				( objectStatus "@baseboard_fab2_lib.baseboard_fab2(sch_1):page87_i187:dqs7p" )
			)
			( pin "J1A1.196"
				( objectStatus "@baseboard_fab2_lib.baseboard_fab2(sch_1):page87_i187:dqs8n" )
			)
			( pin "J1A1.197"
				( objectStatus "@baseboard_fab2_lib.baseboard_fab2(sch_1):page87_i187:dqs8p" )
			)
			( pin "J1A1.8"
				( objectStatus "@baseboard_fab2_lib.baseboard_fab2(sch_1):page87_i187:dqs9n" )
			)
			( pin "J1A1.7"
				( objectStatus "@baseboard_fab2_lib.baseboard_fab2(sch_1):page87_i187:dqs9p" )
			)
			( pin "J1A1.19"
				( objectStatus "@baseboard_fab2_lib.baseboard_fab2(sch_1):page87_i187:dqs10n" )
			)
			( pin "J1A1.18"
				( objectStatus "@baseboard_fab2_lib.baseboard_fab2(sch_1):page87_i187:dqs10p" )
			)
			( pin "J1A1.30"
				( objectStatus "@baseboard_fab2_lib.baseboard_fab2(sch_1):page87_i187:dqs11n" )
			)
			( pin "J1A1.29"
				( objectStatus "@baseboard_fab2_lib.baseboard_fab2(sch_1):page87_i187:dqs11p" )
			)
			( pin "J1A1.41"
				( objectStatus "@baseboard_fab2_lib.baseboard_fab2(sch_1):page87_i187:dqs12n" )
			)
			( pin "J1A1.40"
				( objectStatus "@baseboard_fab2_lib.baseboard_fab2(sch_1):page87_i187:dqs12p" )
			)
			( pin "J1A1.100"
				( objectStatus "@baseboard_fab2_lib.baseboard_fab2(sch_1):page87_i187:dqs13n" )
			)
			( pin "J1A1.99"
				( objectStatus "@baseboard_fab2_lib.baseboard_fab2(sch_1):page87_i187:dqs13p" )
			)
			( pin "J1A1.111"
				( objectStatus "@baseboard_fab2_lib.baseboard_fab2(sch_1):page87_i187:dqs14n" )
			)
			( pin "J1A1.110"
				( objectStatus "@baseboard_fab2_lib.baseboard_fab2(sch_1):page87_i187:dqs14p" )
			)
			( pin "J1A1.122"
				( objectStatus "@baseboard_fab2_lib.baseboard_fab2(sch_1):page87_i187:dqs15n" )
			)
			( pin "J1A1.121"
				( objectStatus "@baseboard_fab2_lib.baseboard_fab2(sch_1):page87_i187:dqs15p" )
			)
			( pin "J1A1.133"
				( objectStatus "@baseboard_fab2_lib.baseboard_fab2(sch_1):page87_i187:dqs16n" )
			)
			( pin "J1A1.132"
				( objectStatus "@baseboard_fab2_lib.baseboard_fab2(sch_1):page87_i187:dqs16p" )
			)
			( pin "J1A1.52"
				( objectStatus "@baseboard_fab2_lib.baseboard_fab2(sch_1):page87_i187:dqs17n" )
			)
			( pin "J1A1.51"
				( objectStatus "@baseboard_fab2_lib.baseboard_fab2(sch_1):page87_i187:dqs17p" )
			)
			( pin "J9L1.283"
				( objectStatus "@baseboard_fab2_lib.baseboard_fab2(sch_1):page88_i25:vss(0)" )
			)
			( pin "J9L1.281"
				( objectStatus "@baseboard_fab2_lib.baseboard_fab2(sch_1):page88_i25:vss(1)" )
			)
			( pin "J9L1.279"
				( objectStatus "@baseboard_fab2_lib.baseboard_fab2(sch_1):page88_i25:vss(2)" )
			)
			( pin "J9L1.276"
				( objectStatus "@baseboard_fab2_lib.baseboard_fab2(sch_1):page88_i25:vss(3)" )
			)
			( pin "J9L1.274"
				( objectStatus "@baseboard_fab2_lib.baseboard_fab2(sch_1):page88_i25:vss(4)" )
			)
			( pin "J9L1.272"
				( objectStatus "@baseboard_fab2_lib.baseboard_fab2(sch_1):page88_i25:vss(5)" )
			)
			( pin "J9L1.270"
				( objectStatus "@baseboard_fab2_lib.baseboard_fab2(sch_1):page88_i25:vss(6)" )
			)
			( pin "J9L1.268"
				( objectStatus "@baseboard_fab2_lib.baseboard_fab2(sch_1):page88_i25:vss(7)" )
			)
			( pin "J9L1.265"
				( objectStatus "@baseboard_fab2_lib.baseboard_fab2(sch_1):page88_i25:vss(8)" )
			)
			( pin "J9L1.263"
				( objectStatus "@baseboard_fab2_lib.baseboard_fab2(sch_1):page88_i25:vss(9)" )
			)
			( pin "J9L1.261"
				( objectStatus "@baseboard_fab2_lib.baseboard_fab2(sch_1):page88_i25:vss(10)" )
			)
			( pin "J9L1.259"
				( objectStatus "@baseboard_fab2_lib.baseboard_fab2(sch_1):page88_i25:vss(11)" )
			)
			( pin "J9L1.257"
				( objectStatus "@baseboard_fab2_lib.baseboard_fab2(sch_1):page88_i25:vss(12)" )
			)
			( pin "J9L1.254"
				( objectStatus "@baseboard_fab2_lib.baseboard_fab2(sch_1):page88_i25:vss(13)" )
			)
			( pin "J9L1.252"
				( objectStatus "@baseboard_fab2_lib.baseboard_fab2(sch_1):page88_i25:vss(14)" )
			)
			( pin "J9L1.250"
				( objectStatus "@baseboard_fab2_lib.baseboard_fab2(sch_1):page88_i25:vss(15)" )
			)
			( pin "J9L1.248"
				( objectStatus "@baseboard_fab2_lib.baseboard_fab2(sch_1):page88_i25:vss(16)" )
			)
			( pin "J9L1.246"
				( objectStatus "@baseboard_fab2_lib.baseboard_fab2(sch_1):page88_i25:vss(17)" )
			)
			( pin "J9L1.243"
				( objectStatus "@baseboard_fab2_lib.baseboard_fab2(sch_1):page88_i25:vss(18)" )
			)
			( pin "J9L1.241"
				( objectStatus "@baseboard_fab2_lib.baseboard_fab2(sch_1):page88_i25:vss(19)" )
			)
			( pin "J9L1.239"
				( objectStatus "@baseboard_fab2_lib.baseboard_fab2(sch_1):page88_i25:vss(20)" )
			)
			( pin "J9L1.202"
				( objectStatus "@baseboard_fab2_lib.baseboard_fab2(sch_1):page88_i25:vss(21)" )
			)
			( pin "J9L1.200"
				( objectStatus "@baseboard_fab2_lib.baseboard_fab2(sch_1):page88_i25:vss(22)" )
			)
			( pin "J9L1.198"
				( objectStatus "@baseboard_fab2_lib.baseboard_fab2(sch_1):page88_i25:vss(23)" )
			)
			( pin "J9L1.195"
				( objectStatus "@baseboard_fab2_lib.baseboard_fab2(sch_1):page88_i25:vss(24)" )
			)
			( pin "J9L1.193"
				( objectStatus "@baseboard_fab2_lib.baseboard_fab2(sch_1):page88_i25:vss(25)" )
			)
			( pin "J9L1.191"
				( objectStatus "@baseboard_fab2_lib.baseboard_fab2(sch_1):page88_i25:vss(26)" )
			)
			( pin "J9L1.189"
				( objectStatus "@baseboard_fab2_lib.baseboard_fab2(sch_1):page88_i25:vss(27)" )
			)
			( pin "J9L1.187"
				( objectStatus "@baseboard_fab2_lib.baseboard_fab2(sch_1):page88_i25:vss(28)" )
			)
			( pin "J9L1.184"
				( objectStatus "@baseboard_fab2_lib.baseboard_fab2(sch_1):page88_i25:vss(29)" )
			)
			( pin "J9L1.182"
				( objectStatus "@baseboard_fab2_lib.baseboard_fab2(sch_1):page88_i25:vss(30)" )
			)
			( pin "J9L1.180"
				( objectStatus "@baseboard_fab2_lib.baseboard_fab2(sch_1):page88_i25:vss(31)" )
			)
			( pin "J9L1.178"
				( objectStatus "@baseboard_fab2_lib.baseboard_fab2(sch_1):page88_i25:vss(32)" )
			)
			( pin "J9L1.176"
				( objectStatus "@baseboard_fab2_lib.baseboard_fab2(sch_1):page88_i25:vss(33)" )
			)
			( pin "J9L1.173"
				( objectStatus "@baseboard_fab2_lib.baseboard_fab2(sch_1):page88_i25:vss(34)" )
			)
			( pin "J9L1.171"
				( objectStatus "@baseboard_fab2_lib.baseboard_fab2(sch_1):page88_i25:vss(35)" )
			)
			( pin "J9L1.169"
				( objectStatus "@baseboard_fab2_lib.baseboard_fab2(sch_1):page88_i25:vss(36)" )
			)
			( pin "J9L1.167"
				( objectStatus "@baseboard_fab2_lib.baseboard_fab2(sch_1):page88_i25:vss(37)" )
			)
			( pin "J9L1.165"
				( objectStatus "@baseboard_fab2_lib.baseboard_fab2(sch_1):page88_i25:vss(38)" )
			)
			( pin "J9L1.162"
				( objectStatus "@baseboard_fab2_lib.baseboard_fab2(sch_1):page88_i25:vss(39)" )
			)
			( pin "J9L1.160"
				( objectStatus "@baseboard_fab2_lib.baseboard_fab2(sch_1):page88_i25:vss(40)" )
			)
			( pin "J9L1.158"
				( objectStatus "@baseboard_fab2_lib.baseboard_fab2(sch_1):page88_i25:vss(41)" )
			)
			( pin "J9L1.156"
				( objectStatus "@baseboard_fab2_lib.baseboard_fab2(sch_1):page88_i25:vss(42)" )
			)
			( pin "J9L1.154"
				( objectStatus "@baseboard_fab2_lib.baseboard_fab2(sch_1):page88_i25:vss(43)" )
			)
			( pin "J9L1.151"
				( objectStatus "@baseboard_fab2_lib.baseboard_fab2(sch_1):page88_i25:vss(44)" )
			)
			( pin "J9L1.149"
				( objectStatus "@baseboard_fab2_lib.baseboard_fab2(sch_1):page88_i25:vss(45)" )
			)
			( pin "J9L1.147"
				( objectStatus "@baseboard_fab2_lib.baseboard_fab2(sch_1):page88_i25:vss(46)" )
			)
			( pin "J9L1.138"
				( objectStatus "@baseboard_fab2_lib.baseboard_fab2(sch_1):page88_i25:vss(47)" )
			)
			( pin "J9L1.136"
				( objectStatus "@baseboard_fab2_lib.baseboard_fab2(sch_1):page88_i25:vss(48)" )
			)
			( pin "J9L1.134"
				( objectStatus "@baseboard_fab2_lib.baseboard_fab2(sch_1):page88_i25:vss(49)" )
			)
			( pin "J9L1.131"
				( objectStatus "@baseboard_fab2_lib.baseboard_fab2(sch_1):page88_i25:vss(50)" )
			)
			( pin "J9L1.129"
				( objectStatus "@baseboard_fab2_lib.baseboard_fab2(sch_1):page88_i25:vss(51)" )
			)
			( pin "J9L1.127"
				( objectStatus "@baseboard_fab2_lib.baseboard_fab2(sch_1):page88_i25:vss(52)" )
			)
			( pin "J9L1.125"
				( objectStatus "@baseboard_fab2_lib.baseboard_fab2(sch_1):page88_i25:vss(53)" )
			)
			( pin "J9L1.123"
				( objectStatus "@baseboard_fab2_lib.baseboard_fab2(sch_1):page88_i25:vss(54)" )
			)
			( pin "J9L1.120"
				( objectStatus "@baseboard_fab2_lib.baseboard_fab2(sch_1):page88_i25:vss(55)" )
			)
			( pin "J9L1.118"
				( objectStatus "@baseboard_fab2_lib.baseboard_fab2(sch_1):page88_i25:vss(56)" )
			)
			( pin "J9L1.116"
				( objectStatus "@baseboard_fab2_lib.baseboard_fab2(sch_1):page88_i25:vss(57)" )
			)
			( pin "J9L1.114"
				( objectStatus "@baseboard_fab2_lib.baseboard_fab2(sch_1):page88_i25:vss(58)" )
			)
			( pin "J9L1.112"
				( objectStatus "@baseboard_fab2_lib.baseboard_fab2(sch_1):page88_i25:vss(59)" )
			)
			( pin "J9L1.109"
				( objectStatus "@baseboard_fab2_lib.baseboard_fab2(sch_1):page88_i25:vss(60)" )
			)
			( pin "J9L1.107"
				( objectStatus "@baseboard_fab2_lib.baseboard_fab2(sch_1):page88_i25:vss(61)" )
			)
			( pin "J9L1.105"
				( objectStatus "@baseboard_fab2_lib.baseboard_fab2(sch_1):page88_i25:vss(62)" )
			)
			( pin "J9L1.103"
				( objectStatus "@baseboard_fab2_lib.baseboard_fab2(sch_1):page88_i25:vss(63)" )
			)
			( pin "J9L1.101"
				( objectStatus "@baseboard_fab2_lib.baseboard_fab2(sch_1):page88_i25:vss(64)" )
			)
			( pin "J9L1.98"
				( objectStatus "@baseboard_fab2_lib.baseboard_fab2(sch_1):page88_i25:vss(65)" )
			)
			( pin "J9L1.96"
				( objectStatus "@baseboard_fab2_lib.baseboard_fab2(sch_1):page88_i25:vss(66)" )
			)
			( pin "J9L1.94"
				( objectStatus "@baseboard_fab2_lib.baseboard_fab2(sch_1):page88_i25:vss(67)" )
			)
			( pin "J9L1.57"
				( objectStatus "@baseboard_fab2_lib.baseboard_fab2(sch_1):page88_i25:vss(68)" )
			)
			( pin "J9L1.55"
				( objectStatus "@baseboard_fab2_lib.baseboard_fab2(sch_1):page88_i25:vss(69)" )
			)
			( pin "J9L1.53"
				( objectStatus "@baseboard_fab2_lib.baseboard_fab2(sch_1):page88_i25:vss(70)" )
			)
			( pin "J9L1.50"
				( objectStatus "@baseboard_fab2_lib.baseboard_fab2(sch_1):page88_i25:vss(71)" )
			)
			( pin "J9L1.48"
				( objectStatus "@baseboard_fab2_lib.baseboard_fab2(sch_1):page88_i25:vss(72)" )
			)
			( pin "J9L1.46"
				( objectStatus "@baseboard_fab2_lib.baseboard_fab2(sch_1):page88_i25:vss(73)" )
			)
			( pin "J9L1.44"
				( objectStatus "@baseboard_fab2_lib.baseboard_fab2(sch_1):page88_i25:vss(74)" )
			)
			( pin "J9L1.42"
				( objectStatus "@baseboard_fab2_lib.baseboard_fab2(sch_1):page88_i25:vss(75)" )
			)
			( pin "J9L1.39"
				( objectStatus "@baseboard_fab2_lib.baseboard_fab2(sch_1):page88_i25:vss(76)" )
			)
			( pin "J9L1.37"
				( objectStatus "@baseboard_fab2_lib.baseboard_fab2(sch_1):page88_i25:vss(77)" )
			)
			( pin "J9L1.35"
				( objectStatus "@baseboard_fab2_lib.baseboard_fab2(sch_1):page88_i25:vss(78)" )
			)
			( pin "J9L1.33"
				( objectStatus "@baseboard_fab2_lib.baseboard_fab2(sch_1):page88_i25:vss(79)" )
			)
			( pin "J9L1.31"
				( objectStatus "@baseboard_fab2_lib.baseboard_fab2(sch_1):page88_i25:vss(80)" )
			)
			( pin "J9L1.28"
				( objectStatus "@baseboard_fab2_lib.baseboard_fab2(sch_1):page88_i25:vss(81)" )
			)
			( pin "J9L1.26"
				( objectStatus "@baseboard_fab2_lib.baseboard_fab2(sch_1):page88_i25:vss(82)" )
			)
			( pin "J9L1.24"
				( objectStatus "@baseboard_fab2_lib.baseboard_fab2(sch_1):page88_i25:vss(83)" )
			)
			( pin "J9L1.22"
				( objectStatus "@baseboard_fab2_lib.baseboard_fab2(sch_1):page88_i25:vss(84)" )
			)
			( pin "J9L1.20"
				( objectStatus "@baseboard_fab2_lib.baseboard_fab2(sch_1):page88_i25:vss(85)" )
			)
			( pin "J9L1.17"
				( objectStatus "@baseboard_fab2_lib.baseboard_fab2(sch_1):page88_i25:vss(86)" )
			)
			( pin "J9L1.15"
				( objectStatus "@baseboard_fab2_lib.baseboard_fab2(sch_1):page88_i25:vss(87)" )
			)
			( pin "J9L1.13"
				( objectStatus "@baseboard_fab2_lib.baseboard_fab2(sch_1):page88_i25:vss(88)" )
			)
			( pin "J9L1.11"
				( objectStatus "@baseboard_fab2_lib.baseboard_fab2(sch_1):page88_i25:vss(89)" )
			)
			( pin "J9L1.9"
				( objectStatus "@baseboard_fab2_lib.baseboard_fab2(sch_1):page88_i25:vss(90)" )
			)
			( pin "J9L1.6"
				( objectStatus "@baseboard_fab2_lib.baseboard_fab2(sch_1):page88_i25:vss(91)" )
			)
			( pin "J9L1.4"
				( objectStatus "@baseboard_fab2_lib.baseboard_fab2(sch_1):page88_i25:vss(92)" )
			)
			( pin "J9L1.2"
				( objectStatus "@baseboard_fab2_lib.baseboard_fab2(sch_1):page88_i25:vss(93)" )
			)
			( pin "J9L1.152"
				( objectStatus "@baseboard_fab2_lib.baseboard_fab2(sch_1):page88_i87:dqs0n" )
			)
			( pin "J9L1.153"
				( objectStatus "@baseboard_fab2_lib.baseboard_fab2(sch_1):page88_i87:dqs0p" )
			)
			( pin "J9L1.163"
				( objectStatus "@baseboard_fab2_lib.baseboard_fab2(sch_1):page88_i87:dqs1n" )
			)
			( pin "J9L1.164"
				( objectStatus "@baseboard_fab2_lib.baseboard_fab2(sch_1):page88_i87:dqs1p" )
			)
			( pin "J9L1.174"
				( objectStatus "@baseboard_fab2_lib.baseboard_fab2(sch_1):page88_i87:dqs2n" )
			)
			( pin "J9L1.175"
				( objectStatus "@baseboard_fab2_lib.baseboard_fab2(sch_1):page88_i87:dqs2p" )
			)
			( pin "J9L1.185"
				( objectStatus "@baseboard_fab2_lib.baseboard_fab2(sch_1):page88_i87:dqs3n" )
			)
			( pin "J9L1.186"
				( objectStatus "@baseboard_fab2_lib.baseboard_fab2(sch_1):page88_i87:dqs3p" )
			)
			( pin "J9L1.244"
				( objectStatus "@baseboard_fab2_lib.baseboard_fab2(sch_1):page88_i87:dqs4n" )
			)
			( pin "J9L1.245"
				( objectStatus "@baseboard_fab2_lib.baseboard_fab2(sch_1):page88_i87:dqs4p" )
			)
			( pin "J9L1.255"
				( objectStatus "@baseboard_fab2_lib.baseboard_fab2(sch_1):page88_i87:dqs5n" )
			)
			( pin "J9L1.256"
				( objectStatus "@baseboard_fab2_lib.baseboard_fab2(sch_1):page88_i87:dqs5p" )
			)
			( pin "J9L1.266"
				( objectStatus "@baseboard_fab2_lib.baseboard_fab2(sch_1):page88_i87:dqs6n" )
			)
			( pin "J9L1.267"
				( objectStatus "@baseboard_fab2_lib.baseboard_fab2(sch_1):page88_i87:dqs6p" )
			)
			( pin "J9L1.277"
				( objectStatus "@baseboard_fab2_lib.baseboard_fab2(sch_1):page88_i87:dqs7n" )
			)
			( pin "J9L1.278"
				( objectStatus "@baseboard_fab2_lib.baseboard_fab2(sch_1):page88_i87:dqs7p" )
			)
			( pin "J9L1.196"
				( objectStatus "@baseboard_fab2_lib.baseboard_fab2(sch_1):page88_i87:dqs8n" )
			)
			( pin "J9L1.197"
				( objectStatus "@baseboard_fab2_lib.baseboard_fab2(sch_1):page88_i87:dqs8p" )
			)
			( pin "J9L1.8"
				( objectStatus "@baseboard_fab2_lib.baseboard_fab2(sch_1):page88_i87:dqs9n" )
			)
			( pin "J9L1.7"
				( objectStatus "@baseboard_fab2_lib.baseboard_fab2(sch_1):page88_i87:dqs9p" )
			)
			( pin "J9L1.19"
				( objectStatus "@baseboard_fab2_lib.baseboard_fab2(sch_1):page88_i87:dqs10n" )
			)
			( pin "J9L1.18"
				( objectStatus "@baseboard_fab2_lib.baseboard_fab2(sch_1):page88_i87:dqs10p" )
			)
			( pin "J9L1.30"
				( objectStatus "@baseboard_fab2_lib.baseboard_fab2(sch_1):page88_i87:dqs11n" )
			)
			( pin "J9L1.29"
				( objectStatus "@baseboard_fab2_lib.baseboard_fab2(sch_1):page88_i87:dqs11p" )
			)
			( pin "J9L1.41"
				( objectStatus "@baseboard_fab2_lib.baseboard_fab2(sch_1):page88_i87:dqs12n" )
			)
			( pin "J9L1.40"
				( objectStatus "@baseboard_fab2_lib.baseboard_fab2(sch_1):page88_i87:dqs12p" )
			)
			( pin "J9L1.100"
				( objectStatus "@baseboard_fab2_lib.baseboard_fab2(sch_1):page88_i87:dqs13n" )
			)
			( pin "J9L1.99"
				( objectStatus "@baseboard_fab2_lib.baseboard_fab2(sch_1):page88_i87:dqs13p" )
			)
			( pin "J9L1.111"
				( objectStatus "@baseboard_fab2_lib.baseboard_fab2(sch_1):page88_i87:dqs14n" )
			)
			( pin "J9L1.110"
				( objectStatus "@baseboard_fab2_lib.baseboard_fab2(sch_1):page88_i87:dqs14p" )
			)
			( pin "J9L1.122"
				( objectStatus "@baseboard_fab2_lib.baseboard_fab2(sch_1):page88_i87:dqs15n" )
			)
			( pin "J9L1.121"
				( objectStatus "@baseboard_fab2_lib.baseboard_fab2(sch_1):page88_i87:dqs15p" )
			)
			( pin "J9L1.133"
				( objectStatus "@baseboard_fab2_lib.baseboard_fab2(sch_1):page88_i87:dqs16n" )
			)
			( pin "J9L1.132"
				( objectStatus "@baseboard_fab2_lib.baseboard_fab2(sch_1):page88_i87:dqs16p" )
			)
			( pin "J9L1.52"
				( objectStatus "@baseboard_fab2_lib.baseboard_fab2(sch_1):page88_i87:dqs17n" )
			)
			( pin "J9L1.51"
				( objectStatus "@baseboard_fab2_lib.baseboard_fab2(sch_1):page88_i87:dqs17p" )
			)
			( pin "J9L1.79"
				( objectStatus "@baseboard_fab2_lib.baseboard_fab2(sch_1):page88_i111:a0" )
			)
			( pin "J9L1.72"
				( objectStatus "@baseboard_fab2_lib.baseboard_fab2(sch_1):page88_i111:a1" )
			)
			( pin "J9L1.216"
				( objectStatus "@baseboard_fab2_lib.baseboard_fab2(sch_1):page88_i111:a2" )
			)
			( pin "J9L1.71"
				( objectStatus "@baseboard_fab2_lib.baseboard_fab2(sch_1):page88_i111:a3" )
			)
			( pin "J9L1.214"
				( objectStatus "@baseboard_fab2_lib.baseboard_fab2(sch_1):page88_i111:a4" )
			)
			( pin "J9L1.213"
				( objectStatus "@baseboard_fab2_lib.baseboard_fab2(sch_1):page88_i111:a5" )
			)
			( pin "J9L1.69"
				( objectStatus "@baseboard_fab2_lib.baseboard_fab2(sch_1):page88_i111:a6" )
			)
			( pin "J9L1.211"
				( objectStatus "@baseboard_fab2_lib.baseboard_fab2(sch_1):page88_i111:a7" )
			)
			( pin "J9L1.68"
				( objectStatus "@baseboard_fab2_lib.baseboard_fab2(sch_1):page88_i111:a8" )
			)
			( pin "J9L1.66"
				( objectStatus "@baseboard_fab2_lib.baseboard_fab2(sch_1):page88_i111:a9" )
			)
			( pin "J9L1.225"
				( objectStatus "@baseboard_fab2_lib.baseboard_fab2(sch_1):page88_i111:a10" )
			)
			( pin "J9L1.210"
				( objectStatus "@baseboard_fab2_lib.baseboard_fab2(sch_1):page88_i111:a11" )
			)
			( pin "J9L1.65"
				( objectStatus "@baseboard_fab2_lib.baseboard_fab2(sch_1):page88_i111:a12" )
			)
			( pin "J9L1.232"
				( objectStatus "@baseboard_fab2_lib.baseboard_fab2(sch_1):page88_i111:a13" )
			)
			( pin "J9L1.228"
				( objectStatus "@baseboard_fab2_lib.baseboard_fab2(sch_1):page88_i111:a14_we_n" )
			)
			( pin "J9L1.86"
				( objectStatus "@baseboard_fab2_lib.baseboard_fab2(sch_1):page88_i111:a15_cas_n" )
			)
			( pin "J9L1.82"
				( objectStatus "@baseboard_fab2_lib.baseboard_fab2(sch_1):page88_i111:a16_ras_n" )
			)
			( pin "J9L1.234"
				( objectStatus "@baseboard_fab2_lib.baseboard_fab2(sch_1):page88_i111:a17" )
			)
			( pin "J9L1.62"
				( objectStatus "@baseboard_fab2_lib.baseboard_fab2(sch_1):page88_i111:act_n" )
			)
			( pin "J9L1.208"
				( objectStatus "@baseboard_fab2_lib.baseboard_fab2(sch_1):page88_i111:alert_n" )
			)
			( pin "J9L1.81"
				( objectStatus "@baseboard_fab2_lib.baseboard_fab2(sch_1):page88_i111:ba(0)" )
			)
			( pin "J9L1.224"
				( objectStatus "@baseboard_fab2_lib.baseboard_fab2(sch_1):page88_i111:ba(1)" )
			)
			( pin "J9L1.63"
				( objectStatus "@baseboard_fab2_lib.baseboard_fab2(sch_1):page88_i111:bg(0)" )
			)
			( pin "J9L1.207"
				( objectStatus "@baseboard_fab2_lib.baseboard_fab2(sch_1):page88_i111:bg(1)" )
			)
			( pin "J9L1.235"
				( objectStatus "@baseboard_fab2_lib.baseboard_fab2(sch_1):page88_i111:c(2)" )
			)
			( pin "J9L1.49"
				( objectStatus "@baseboard_fab2_lib.baseboard_fab2(sch_1):page88_i111:cb(0)" )
			)
			( pin "J9L1.194"
				( objectStatus "@baseboard_fab2_lib.baseboard_fab2(sch_1):page88_i111:cb(1)" )
			)
			( pin "J9L1.56"
				( objectStatus "@baseboard_fab2_lib.baseboard_fab2(sch_1):page88_i111:cb(2)" )
			)
			( pin "J9L1.201"
				( objectStatus "@baseboard_fab2_lib.baseboard_fab2(sch_1):page88_i111:cb(3)" )
			)
			( pin "J9L1.47"
				( objectStatus "@baseboard_fab2_lib.baseboard_fab2(sch_1):page88_i111:cb(4)" )
			)
			( pin "J9L1.192"
				( objectStatus "@baseboard_fab2_lib.baseboard_fab2(sch_1):page88_i111:cb(5)" )
			)
			( pin "J9L1.54"
				( objectStatus "@baseboard_fab2_lib.baseboard_fab2(sch_1):page88_i111:cb(6)" )
			)
			( pin "J9L1.199"
				( objectStatus "@baseboard_fab2_lib.baseboard_fab2(sch_1):page88_i111:cb(7)" )
			)
			( pin "J9L1.75"
				( objectStatus "@baseboard_fab2_lib.baseboard_fab2(sch_1):page88_i111:ck0n" )
			)
			( pin "J9L1.74"
				( objectStatus "@baseboard_fab2_lib.baseboard_fab2(sch_1):page88_i111:ck0p" )
			)
			( pin "J9L1.219"
				( objectStatus "@baseboard_fab2_lib.baseboard_fab2(sch_1):page88_i111:ck1n" )
			)
			( pin "J9L1.218"
				( objectStatus "@baseboard_fab2_lib.baseboard_fab2(sch_1):page88_i111:ck1p" )
			)
			( pin "J9L1.60"
				( objectStatus "@baseboard_fab2_lib.baseboard_fab2(sch_1):page88_i111:cke(0)" )
			)
			( pin "J9L1.203"
				( objectStatus "@baseboard_fab2_lib.baseboard_fab2(sch_1):page88_i111:cke(1)" )
			)
			( pin "J9L1.5"
				( objectStatus "@baseboard_fab2_lib.baseboard_fab2(sch_1):page88_i111:dq(0)" )
			)
			( pin "J9L1.150"
				( objectStatus "@baseboard_fab2_lib.baseboard_fab2(sch_1):page88_i111:dq(1)" )
			)
			( pin "J9L1.12"
				( objectStatus "@baseboard_fab2_lib.baseboard_fab2(sch_1):page88_i111:dq(2)" )
			)
			( pin "J9L1.157"
				( objectStatus "@baseboard_fab2_lib.baseboard_fab2(sch_1):page88_i111:dq(3)" )
			)
			( pin "J9L1.3"
				( objectStatus "@baseboard_fab2_lib.baseboard_fab2(sch_1):page88_i111:dq(4)" )
			)
			( pin "J9L1.148"
				( objectStatus "@baseboard_fab2_lib.baseboard_fab2(sch_1):page88_i111:dq(5)" )
			)
			( pin "J9L1.10"
				( objectStatus "@baseboard_fab2_lib.baseboard_fab2(sch_1):page88_i111:dq(6)" )
			)
			( pin "J9L1.155"
				( objectStatus "@baseboard_fab2_lib.baseboard_fab2(sch_1):page88_i111:dq(7)" )
			)
			( pin "J9L1.16"
				( objectStatus "@baseboard_fab2_lib.baseboard_fab2(sch_1):page88_i111:dq(8)" )
			)
			( pin "J9L1.161"
				( objectStatus "@baseboard_fab2_lib.baseboard_fab2(sch_1):page88_i111:dq(9)" )
			)
			( pin "J9L1.23"
				( objectStatus "@baseboard_fab2_lib.baseboard_fab2(sch_1):page88_i111:dq(10)" )
			)
			( pin "J9L1.168"
				( objectStatus "@baseboard_fab2_lib.baseboard_fab2(sch_1):page88_i111:dq(11)" )
			)
			( pin "J9L1.14"
				( objectStatus "@baseboard_fab2_lib.baseboard_fab2(sch_1):page88_i111:dq(12)" )
			)
			( pin "J9L1.159"
				( objectStatus "@baseboard_fab2_lib.baseboard_fab2(sch_1):page88_i111:dq(13)" )
			)
			( pin "J9L1.21"
				( objectStatus "@baseboard_fab2_lib.baseboard_fab2(sch_1):page88_i111:dq(14)" )
			)
			( pin "J9L1.166"
				( objectStatus "@baseboard_fab2_lib.baseboard_fab2(sch_1):page88_i111:dq(15)" )
			)
			( pin "J9L1.27"
				( objectStatus "@baseboard_fab2_lib.baseboard_fab2(sch_1):page88_i111:dq(16)" )
			)
			( pin "J9L1.172"
				( objectStatus "@baseboard_fab2_lib.baseboard_fab2(sch_1):page88_i111:dq(17)" )
			)
			( pin "J9L1.34"
				( objectStatus "@baseboard_fab2_lib.baseboard_fab2(sch_1):page88_i111:dq(18)" )
			)
			( pin "J9L1.179"
				( objectStatus "@baseboard_fab2_lib.baseboard_fab2(sch_1):page88_i111:dq(19)" )
			)
			( pin "J9L1.25"
				( objectStatus "@baseboard_fab2_lib.baseboard_fab2(sch_1):page88_i111:dq(20)" )
			)
			( pin "J9L1.170"
				( objectStatus "@baseboard_fab2_lib.baseboard_fab2(sch_1):page88_i111:dq(21)" )
			)
			( pin "J9L1.32"
				( objectStatus "@baseboard_fab2_lib.baseboard_fab2(sch_1):page88_i111:dq(22)" )
			)
			( pin "J9L1.177"
				( objectStatus "@baseboard_fab2_lib.baseboard_fab2(sch_1):page88_i111:dq(23)" )
			)
			( pin "J9L1.38"
				( objectStatus "@baseboard_fab2_lib.baseboard_fab2(sch_1):page88_i111:dq(24)" )
			)
			( pin "J9L1.183"
				( objectStatus "@baseboard_fab2_lib.baseboard_fab2(sch_1):page88_i111:dq(25)" )
			)
			( pin "J9L1.45"
				( objectStatus "@baseboard_fab2_lib.baseboard_fab2(sch_1):page88_i111:dq(26)" )
			)
			( pin "J9L1.190"
				( objectStatus "@baseboard_fab2_lib.baseboard_fab2(sch_1):page88_i111:dq(27)" )
			)
			( pin "J9L1.36"
				( objectStatus "@baseboard_fab2_lib.baseboard_fab2(sch_1):page88_i111:dq(28)" )
			)
			( pin "J9L1.181"
				( objectStatus "@baseboard_fab2_lib.baseboard_fab2(sch_1):page88_i111:dq(29)" )
			)
			( pin "J9L1.43"
				( objectStatus "@baseboard_fab2_lib.baseboard_fab2(sch_1):page88_i111:dq(30)" )
			)
			( pin "J9L1.188"
				( objectStatus "@baseboard_fab2_lib.baseboard_fab2(sch_1):page88_i111:dq(31)" )
			)
			( pin "J9L1.97"
				( objectStatus "@baseboard_fab2_lib.baseboard_fab2(sch_1):page88_i111:dq(32)" )
			)
			( pin "J9L1.242"
				( objectStatus "@baseboard_fab2_lib.baseboard_fab2(sch_1):page88_i111:dq(33)" )
			)
			( pin "J9L1.104"
				( objectStatus "@baseboard_fab2_lib.baseboard_fab2(sch_1):page88_i111:dq(34)" )
			)
			( pin "J9L1.249"
				( objectStatus "@baseboard_fab2_lib.baseboard_fab2(sch_1):page88_i111:dq(35)" )
			)
			( pin "J9L1.95"
				( objectStatus "@baseboard_fab2_lib.baseboard_fab2(sch_1):page88_i111:dq(36)" )
			)
			( pin "J9L1.240"
				( objectStatus "@baseboard_fab2_lib.baseboard_fab2(sch_1):page88_i111:dq(37)" )
			)
			( pin "J9L1.102"
				( objectStatus "@baseboard_fab2_lib.baseboard_fab2(sch_1):page88_i111:dq(38)" )
			)
			( pin "J9L1.247"
				( objectStatus "@baseboard_fab2_lib.baseboard_fab2(sch_1):page88_i111:dq(39)" )
			)
			( pin "J9L1.108"
				( objectStatus "@baseboard_fab2_lib.baseboard_fab2(sch_1):page88_i111:dq(40)" )
			)
			( pin "J9L1.253"
				( objectStatus "@baseboard_fab2_lib.baseboard_fab2(sch_1):page88_i111:dq(41)" )
			)
			( pin "J9L1.115"
				( objectStatus "@baseboard_fab2_lib.baseboard_fab2(sch_1):page88_i111:dq(42)" )
			)
			( pin "J9L1.260"
				( objectStatus "@baseboard_fab2_lib.baseboard_fab2(sch_1):page88_i111:dq(43)" )
			)
			( pin "J9L1.106"
				( objectStatus "@baseboard_fab2_lib.baseboard_fab2(sch_1):page88_i111:dq(44)" )
			)
			( pin "J9L1.251"
				( objectStatus "@baseboard_fab2_lib.baseboard_fab2(sch_1):page88_i111:dq(45)" )
			)
			( pin "J9L1.113"
				( objectStatus "@baseboard_fab2_lib.baseboard_fab2(sch_1):page88_i111:dq(46)" )
			)
			( pin "J9L1.258"
				( objectStatus "@baseboard_fab2_lib.baseboard_fab2(sch_1):page88_i111:dq(47)" )
			)
			( pin "J9L1.119"
				( objectStatus "@baseboard_fab2_lib.baseboard_fab2(sch_1):page88_i111:dq(48)" )
			)
			( pin "J9L1.264"
				( objectStatus "@baseboard_fab2_lib.baseboard_fab2(sch_1):page88_i111:dq(49)" )
			)
			( pin "J9L1.126"
				( objectStatus "@baseboard_fab2_lib.baseboard_fab2(sch_1):page88_i111:dq(50)" )
			)
			( pin "J9L1.271"
				( objectStatus "@baseboard_fab2_lib.baseboard_fab2(sch_1):page88_i111:dq(51)" )
			)
			( pin "J9L1.117"
				( objectStatus "@baseboard_fab2_lib.baseboard_fab2(sch_1):page88_i111:dq(52)" )
			)
			( pin "J9L1.262"
				( objectStatus "@baseboard_fab2_lib.baseboard_fab2(sch_1):page88_i111:dq(53)" )
			)
			( pin "J9L1.124"
				( objectStatus "@baseboard_fab2_lib.baseboard_fab2(sch_1):page88_i111:dq(54)" )
			)
			( pin "J9L1.269"
				( objectStatus "@baseboard_fab2_lib.baseboard_fab2(sch_1):page88_i111:dq(55)" )
			)
			( pin "J9L1.130"
				( objectStatus "@baseboard_fab2_lib.baseboard_fab2(sch_1):page88_i111:dq(56)" )
			)
			( pin "J9L1.275"
				( objectStatus "@baseboard_fab2_lib.baseboard_fab2(sch_1):page88_i111:dq(57)" )
			)
			( pin "J9L1.137"
				( objectStatus "@baseboard_fab2_lib.baseboard_fab2(sch_1):page88_i111:dq(58)" )
			)
			( pin "J9L1.282"
				( objectStatus "@baseboard_fab2_lib.baseboard_fab2(sch_1):page88_i111:dq(59)" )
			)
			( pin "J9L1.128"
				( objectStatus "@baseboard_fab2_lib.baseboard_fab2(sch_1):page88_i111:dq(60)" )
			)
			( pin "J9L1.273"
				( objectStatus "@baseboard_fab2_lib.baseboard_fab2(sch_1):page88_i111:dq(61)" )
			)
			( pin "J9L1.135"
				( objectStatus "@baseboard_fab2_lib.baseboard_fab2(sch_1):page88_i111:dq(62)" )
			)
			( pin "J9L1.280"
				( objectStatus "@baseboard_fab2_lib.baseboard_fab2(sch_1):page88_i111:dq(63)" )
			)
			( pin "J9L1.78"
				( objectStatus "@baseboard_fab2_lib.baseboard_fab2(sch_1):page88_i111:event_n" )
			)
			( pin "J9L1.87"
				( objectStatus "@baseboard_fab2_lib.baseboard_fab2(sch_1):page88_i111:odt(0)" )
			)
			( pin "J9L1.91"
				( objectStatus "@baseboard_fab2_lib.baseboard_fab2(sch_1):page88_i111:odt(1)" )
			)
			( pin "J9L1.222"
				( objectStatus "@baseboard_fab2_lib.baseboard_fab2(sch_1):page88_i111:par" )
			)
			( pin "J9L1.58"
				( objectStatus "@baseboard_fab2_lib.baseboard_fab2(sch_1):page88_i111:reset_n" )
			)
			( pin "J9L1.205"
				( objectStatus "@baseboard_fab2_lib.baseboard_fab2(sch_1):page88_i111:rfu(0)" )
			)
			( pin "J9L1.227"
				( objectStatus "@baseboard_fab2_lib.baseboard_fab2(sch_1):page88_i111:rfu(1)" )
			)
			( pin "J9L1.144"
				( objectStatus "@baseboard_fab2_lib.baseboard_fab2(sch_1):page88_i111:rfu(2)" )
			)
			( pin "J9L1.84"
				( objectStatus "@baseboard_fab2_lib.baseboard_fab2(sch_1):page88_i111:s0_n" )
			)
			( pin "J9L1.89"
				( objectStatus "@baseboard_fab2_lib.baseboard_fab2(sch_1):page88_i111:s1_n" )
			)
			( pin "J9L1.93"
				( objectStatus "@baseboard_fab2_lib.baseboard_fab2(sch_1):page88_i111:s2_n_c(0)" )
			)
			( pin "J9L1.237"
				( objectStatus "@baseboard_fab2_lib.baseboard_fab2(sch_1):page88_i111:s3_n_c(1)" )
			)
			( pin "J9L1.139"
				( objectStatus "@baseboard_fab2_lib.baseboard_fab2(sch_1):page88_i111:sa(0)" )
			)
			( pin "J9L1.140"
				( objectStatus "@baseboard_fab2_lib.baseboard_fab2(sch_1):page88_i111:sa(1)" )
			)
			( pin "J9L1.238"
				( objectStatus "@baseboard_fab2_lib.baseboard_fab2(sch_1):page88_i111:sa(2)" )
			)
			( pin "J9L1.230"
				( objectStatus "@baseboard_fab2_lib.baseboard_fab2(sch_1):page88_i111:save_n_nc" )
			)
			( pin "J9L1.141"
				( objectStatus "@baseboard_fab2_lib.baseboard_fab2(sch_1):page88_i111:scl" )
			)
			( pin "J9L1.285"
				( objectStatus "@baseboard_fab2_lib.baseboard_fab2(sch_1):page88_i111:sda" )
			)
			( pin "J9L1.284"
				( objectStatus "@baseboard_fab2_lib.baseboard_fab2(sch_1):page88_i111:vddspd" )
			)
			( pin "J9L1.146"
				( objectStatus "@baseboard_fab2_lib.baseboard_fab2(sch_1):page88_i111:vrefca" )
			)
			( pin "J9L1.145"
				( objectStatus "@baseboard_fab2_lib.baseboard_fab2(sch_1):page88_i168:\12v\(0)" )
			)
			( pin "J9L1.1"
				( objectStatus "@baseboard_fab2_lib.baseboard_fab2(sch_1):page88_i168:\12v\(1)" )
			)
			( pin "J9L1.236"
				( objectStatus "@baseboard_fab2_lib.baseboard_fab2(sch_1):page88_i168:vdd(0)" )
			)
			( pin "J9L1.233"
				( objectStatus "@baseboard_fab2_lib.baseboard_fab2(sch_1):page88_i168:vdd(1)" )
			)
			( pin "J9L1.231"
				( objectStatus "@baseboard_fab2_lib.baseboard_fab2(sch_1):page88_i168:vdd(2)" )
			)
			( pin "J9L1.229"
				( objectStatus "@baseboard_fab2_lib.baseboard_fab2(sch_1):page88_i168:vdd(3)" )
			)
			( pin "J9L1.226"
				( objectStatus "@baseboard_fab2_lib.baseboard_fab2(sch_1):page88_i168:vdd(4)" )
			)
			( pin "J9L1.223"
				( objectStatus "@baseboard_fab2_lib.baseboard_fab2(sch_1):page88_i168:vdd(5)" )
			)
			( pin "J9L1.220"
				( objectStatus "@baseboard_fab2_lib.baseboard_fab2(sch_1):page88_i168:vdd(6)" )
			)
			( pin "J9L1.217"
				( objectStatus "@baseboard_fab2_lib.baseboard_fab2(sch_1):page88_i168:vdd(7)" )
			)
			( pin "J9L1.215"
				( objectStatus "@baseboard_fab2_lib.baseboard_fab2(sch_1):page88_i168:vdd(8)" )
			)
			( pin "J9L1.212"
				( objectStatus "@baseboard_fab2_lib.baseboard_fab2(sch_1):page88_i168:vdd(9)" )
			)
			( pin "J9L1.209"
				( objectStatus "@baseboard_fab2_lib.baseboard_fab2(sch_1):page88_i168:vdd(10)" )
			)
			( pin "J9L1.206"
				( objectStatus "@baseboard_fab2_lib.baseboard_fab2(sch_1):page88_i168:vdd(11)" )
			)
			( pin "J9L1.204"
				( objectStatus "@baseboard_fab2_lib.baseboard_fab2(sch_1):page88_i168:vdd(12)" )
			)
			( pin "J9L1.92"
				( objectStatus "@baseboard_fab2_lib.baseboard_fab2(sch_1):page88_i168:vdd(13)" )
			)
			( pin "J9L1.90"
				( objectStatus "@baseboard_fab2_lib.baseboard_fab2(sch_1):page88_i168:vdd(14)" )
			)
			( pin "J9L1.88"
				( objectStatus "@baseboard_fab2_lib.baseboard_fab2(sch_1):page88_i168:vdd(15)" )
			)
			( pin "J9L1.85"
				( objectStatus "@baseboard_fab2_lib.baseboard_fab2(sch_1):page88_i168:vdd(16)" )
			)
			( pin "J9L1.83"
				( objectStatus "@baseboard_fab2_lib.baseboard_fab2(sch_1):page88_i168:vdd(17)" )
			)
			( pin "J9L1.80"
				( objectStatus "@baseboard_fab2_lib.baseboard_fab2(sch_1):page88_i168:vdd(18)" )
			)
			( pin "J9L1.76"
				( objectStatus "@baseboard_fab2_lib.baseboard_fab2(sch_1):page88_i168:vdd(19)" )
			)
			( pin "J9L1.73"
				( objectStatus "@baseboard_fab2_lib.baseboard_fab2(sch_1):page88_i168:vdd(20)" )
			)
			( pin "J9L1.70"
				( objectStatus "@baseboard_fab2_lib.baseboard_fab2(sch_1):page88_i168:vdd(21)" )
			)
			( pin "J9L1.67"
				( objectStatus "@baseboard_fab2_lib.baseboard_fab2(sch_1):page88_i168:vdd(22)" )
			)
			( pin "J9L1.64"
				( objectStatus "@baseboard_fab2_lib.baseboard_fab2(sch_1):page88_i168:vdd(23)" )
			)
			( pin "J9L1.61"
				( objectStatus "@baseboard_fab2_lib.baseboard_fab2(sch_1):page88_i168:vdd(24)" )
			)
			( pin "J9L1.59"
				( objectStatus "@baseboard_fab2_lib.baseboard_fab2(sch_1):page88_i168:vdd(25)" )
			)
			( pin "J9L1.287"
				( objectStatus "@baseboard_fab2_lib.baseboard_fab2(sch_1):page88_i168:vpp(0)" )
			)
			( pin "J9L1.286"
				( objectStatus "@baseboard_fab2_lib.baseboard_fab2(sch_1):page88_i168:vpp(1)" )
			)
			( pin "J9L1.288"
				( objectStatus "@baseboard_fab2_lib.baseboard_fab2(sch_1):page88_i168:vpp(2)" )
			)
			( pin "J9L1.143"
				( objectStatus "@baseboard_fab2_lib.baseboard_fab2(sch_1):page88_i168:vpp(3)" )
			)
			( pin "J9L1.142"
				( objectStatus "@baseboard_fab2_lib.baseboard_fab2(sch_1):page88_i168:vpp(4)" )
			)
			( pin "J9L1.221"
				( objectStatus "@baseboard_fab2_lib.baseboard_fab2(sch_1):page88_i168:vtt(0)" )
			)
			( pin "J9L1.77"
				( objectStatus "@baseboard_fab2_lib.baseboard_fab2(sch_1):page88_i168:vtt(1)" )
			)
			( pin "C9L1.1"
				( objectStatus "@baseboard_fab2_lib.baseboard_fab2(sch_1):page88_i177:a" )
			)
			( pin "C9L1.2"
				( objectStatus "@baseboard_fab2_lib.baseboard_fab2(sch_1):page88_i177:b" )
			)
			( pin "R4T2.1"
				( objectStatus "@baseboard_fab2_lib.baseboard_fab2(sch_1):page89_i1:a" )
			)
			( pin "R4T2.2"
				( objectStatus "@baseboard_fab2_lib.baseboard_fab2(sch_1):page89_i1:b" )
			)
			( pin "R4T1.1"
				( objectStatus "@baseboard_fab2_lib.baseboard_fab2(sch_1):page89_i2:a" )
			)
			( pin "R4T1.2"
				( objectStatus "@baseboard_fab2_lib.baseboard_fab2(sch_1):page89_i2:b" )
			)
			( pin "R6F4.1"
				( objectStatus "@baseboard_fab2_lib.baseboard_fab2(sch_1):page89_i3:a" )
			)
			( pin "R6F4.2"
				( objectStatus "@baseboard_fab2_lib.baseboard_fab2(sch_1):page89_i3:b" )
			)
			( pin "R6F1.1"
				( objectStatus "@baseboard_fab2_lib.baseboard_fab2(sch_1):page89_i4:a" )
			)
			( pin "R6F1.2"
				( objectStatus "@baseboard_fab2_lib.baseboard_fab2(sch_1):page89_i4:b" )
			)
			( pin "R6F5.1"
				( objectStatus "@baseboard_fab2_lib.baseboard_fab2(sch_1):page89_i5:a" )
			)
			( pin "R6F5.2"
				( objectStatus "@baseboard_fab2_lib.baseboard_fab2(sch_1):page89_i5:b" )
			)
			( pin "R6F2.1"
				( objectStatus "@baseboard_fab2_lib.baseboard_fab2(sch_1):page89_i6:a" )
			)
			( pin "R6F2.2"
				( objectStatus "@baseboard_fab2_lib.baseboard_fab2(sch_1):page89_i6:b" )
			)
			( pin "R6F3.1"
				( objectStatus "@baseboard_fab2_lib.baseboard_fab2(sch_1):page89_i7:a" )
			)
			( pin "R6F3.2"
				( objectStatus "@baseboard_fab2_lib.baseboard_fab2(sch_1):page89_i7:b" )
			)
			( pin "Q6F1.3"
				( objectStatus "@baseboard_fab2_lib.baseboard_fab2(sch_1):page89_i18:drn" )
			)
			( pin "Q6F1.1"
				( objectStatus "@baseboard_fab2_lib.baseboard_fab2(sch_1):page89_i18:gate" )
			)
			( pin "Q6F1.2"
				( objectStatus "@baseboard_fab2_lib.baseboard_fab2(sch_1):page89_i18:src" )
			)
			( pin "R2P12.1"
				( objectStatus "@baseboard_fab2_lib.baseboard_fab2(sch_1):page89_i23:a" )
			)
			( pin "R2P12.2"
				( objectStatus "@baseboard_fab2_lib.baseboard_fab2(sch_1):page89_i23:b" )
			)
			( pin "R8D29.1"
				( objectStatus "@baseboard_fab2_lib.baseboard_fab2(sch_1):page89_i26:a" )
			)
			( pin "R8D29.2"
				( objectStatus "@baseboard_fab2_lib.baseboard_fab2(sch_1):page89_i26:b" )
			)
			( pin "R8D31.1"
				( objectStatus "@baseboard_fab2_lib.baseboard_fab2(sch_1):page89_i27:a" )
			)
			( pin "R8D31.2"
				( objectStatus "@baseboard_fab2_lib.baseboard_fab2(sch_1):page89_i27:b" )
			)
			( pin "R8D30.1"
				( objectStatus "@baseboard_fab2_lib.baseboard_fab2(sch_1):page89_i34:a" )
			)
			( pin "R8D30.2"
				( objectStatus "@baseboard_fab2_lib.baseboard_fab2(sch_1):page89_i34:b" )
			)
			( pin "Q8D1.5"
				( objectStatus "@baseboard_fab2_lib.baseboard_fab2(sch_1):page89_i35:b(0)" )
			)
			( pin "Q8D1.3"
				( objectStatus "@baseboard_fab2_lib.baseboard_fab2(sch_1):page89_i35:c(0)" )
			)
			( pin "Q8D1.4"
				( objectStatus "@baseboard_fab2_lib.baseboard_fab2(sch_1):page89_i35:e(0)" )
			)
			( pin "Q8D1.2"
				( objectStatus "@baseboard_fab2_lib.baseboard_fab2(sch_1):page89_i36:b(0)" )
			)
			( pin "Q8D1.6"
				( objectStatus "@baseboard_fab2_lib.baseboard_fab2(sch_1):page89_i36:c(0)" )
			)
			( pin "Q8D1.1"
				( objectStatus "@baseboard_fab2_lib.baseboard_fab2(sch_1):page89_i36:e(0)" )
			)
			( pin "R6D6.1"
				( objectStatus "@baseboard_fab2_lib.baseboard_fab2(sch_1):page90_i3:a" )
			)
			( pin "R6D6.2"
				( objectStatus "@baseboard_fab2_lib.baseboard_fab2(sch_1):page90_i3:b" )
			)
			( pin "R4P1.1"
				( objectStatus "@baseboard_fab2_lib.baseboard_fab2(sch_1):page90_i4:a" )
			)
			( pin "R4P1.2"
				( objectStatus "@baseboard_fab2_lib.baseboard_fab2(sch_1):page90_i4:b" )
			)
			( pin "R3D12.1"
				( objectStatus "@baseboard_fab2_lib.baseboard_fab2(sch_1):page90_i11:a" )
			)
			( pin "R3D12.2"
				( objectStatus "@baseboard_fab2_lib.baseboard_fab2(sch_1):page90_i11:b" )
			)
			( pin "R3D13.1"
				( objectStatus "@baseboard_fab2_lib.baseboard_fab2(sch_1):page90_i12:a" )
			)
			( pin "R3D13.2"
				( objectStatus "@baseboard_fab2_lib.baseboard_fab2(sch_1):page90_i12:b" )
			)
			( pin "R3D22.1"
				( objectStatus "@baseboard_fab2_lib.baseboard_fab2(sch_1):page90_i17:a" )
			)
			( pin "R3D22.2"
				( objectStatus "@baseboard_fab2_lib.baseboard_fab2(sch_1):page90_i17:b" )
			)
			( pin "R3D16.1"
				( objectStatus "@baseboard_fab2_lib.baseboard_fab2(sch_1):page90_i24:a" )
			)
			( pin "R3D16.2"
				( objectStatus "@baseboard_fab2_lib.baseboard_fab2(sch_1):page90_i24:b" )
			)
			( pin "R3D23.1"
				( objectStatus "@baseboard_fab2_lib.baseboard_fab2(sch_1):page90_i25:a" )
			)
			( pin "R3D23.2"
				( objectStatus "@baseboard_fab2_lib.baseboard_fab2(sch_1):page90_i25:b" )
			)
			( pin "R3D26.1"
				( objectStatus "@baseboard_fab2_lib.baseboard_fab2(sch_1):page90_i28:a" )
			)
			( pin "R3D26.2"
				( objectStatus "@baseboard_fab2_lib.baseboard_fab2(sch_1):page90_i28:b" )
			)
			( pin "R5D3.1"
				( objectStatus "@baseboard_fab2_lib.baseboard_fab2(sch_1):page90_i29:a" )
			)
			( pin "R5D3.2"
				( objectStatus "@baseboard_fab2_lib.baseboard_fab2(sch_1):page90_i29:b" )
			)
			( pin "R6D7.1"
				( objectStatus "@baseboard_fab2_lib.baseboard_fab2(sch_1):page90_i31:a" )
			)
			( pin "R6D7.2"
				( objectStatus "@baseboard_fab2_lib.baseboard_fab2(sch_1):page90_i31:b" )
			)
			( pin "R5D4.1"
				( objectStatus "@baseboard_fab2_lib.baseboard_fab2(sch_1):page90_i32:a" )
			)
			( pin "R5D4.2"
				( objectStatus "@baseboard_fab2_lib.baseboard_fab2(sch_1):page90_i32:b" )
			)
			( pin "R6D13.1"
				( objectStatus "@baseboard_fab2_lib.baseboard_fab2(sch_1):page90_i33:a" )
			)
			( pin "R6D13.2"
				( objectStatus "@baseboard_fab2_lib.baseboard_fab2(sch_1):page90_i33:b" )
			)
			( pin "R6D15.1"
				( objectStatus "@baseboard_fab2_lib.baseboard_fab2(sch_1):page90_i48:a" )
			)
			( pin "R6D15.2"
				( objectStatus "@baseboard_fab2_lib.baseboard_fab2(sch_1):page90_i48:b" )
			)
			( pin "R6D10.1"
				( objectStatus "@baseboard_fab2_lib.baseboard_fab2(sch_1):page90_i49:a" )
			)
			( pin "R6D10.2"
				( objectStatus "@baseboard_fab2_lib.baseboard_fab2(sch_1):page90_i49:b" )
			)
			( pin "R6D14.1"
				( objectStatus "@baseboard_fab2_lib.baseboard_fab2(sch_1):page90_i52:a" )
			)
			( pin "R6D14.2"
				( objectStatus "@baseboard_fab2_lib.baseboard_fab2(sch_1):page90_i52:b" )
			)
			( pin "R4P14.1"
				( objectStatus "@baseboard_fab2_lib.baseboard_fab2(sch_1):page90_i53:a" )
			)
			( pin "R4P14.2"
				( objectStatus "@baseboard_fab2_lib.baseboard_fab2(sch_1):page90_i53:b" )
			)
			( pin "R3D24.1"
				( objectStatus "@baseboard_fab2_lib.baseboard_fab2(sch_1):page90_i59:a" )
			)
			( pin "R3D24.2"
				( objectStatus "@baseboard_fab2_lib.baseboard_fab2(sch_1):page90_i59:b" )
			)
			( pin "R3D17.1"
				( objectStatus "@baseboard_fab2_lib.baseboard_fab2(sch_1):page90_i60:a" )
			)
			( pin "R3D17.2"
				( objectStatus "@baseboard_fab2_lib.baseboard_fab2(sch_1):page90_i60:b" )
			)
			( pin "R3D25.1"
				( objectStatus "@baseboard_fab2_lib.baseboard_fab2(sch_1):page90_i66:a" )
			)
			( pin "R3D25.2"
				( objectStatus "@baseboard_fab2_lib.baseboard_fab2(sch_1):page90_i66:b" )
			)
			( pin "R4P6.1"
				( objectStatus "@baseboard_fab2_lib.baseboard_fab2(sch_1):page90_i68:a" )
			)
			( pin "R4P6.2"
				( objectStatus "@baseboard_fab2_lib.baseboard_fab2(sch_1):page90_i68:b" )
			)
			( pin "R7P14.1"
				( objectStatus "@baseboard_fab2_lib.baseboard_fab2(sch_1):page90_i70:a" )
			)
			( pin "R7P14.2"
				( objectStatus "@baseboard_fab2_lib.baseboard_fab2(sch_1):page90_i70:b" )
			)
			( pin "R4P7.1"
				( objectStatus "@baseboard_fab2_lib.baseboard_fab2(sch_1):page90_i72:a" )
			)
			( pin "R4P7.2"
				( objectStatus "@baseboard_fab2_lib.baseboard_fab2(sch_1):page90_i72:b" )
			)
			( pin "R7P15.1"
				( objectStatus "@baseboard_fab2_lib.baseboard_fab2(sch_1):page90_i74:a" )
			)
			( pin "R7P15.2"
				( objectStatus "@baseboard_fab2_lib.baseboard_fab2(sch_1):page90_i74:b" )
			)
			( pin "R7P22.1"
				( objectStatus "@baseboard_fab2_lib.baseboard_fab2(sch_1):page90_i76:a" )
			)
			( pin "R7P22.2"
				( objectStatus "@baseboard_fab2_lib.baseboard_fab2(sch_1):page90_i76:b" )
			)
			( pin "R5P2.1"
				( objectStatus "@baseboard_fab2_lib.baseboard_fab2(sch_1):page90_i79:a" )
			)
			( pin "R5P2.2"
				( objectStatus "@baseboard_fab2_lib.baseboard_fab2(sch_1):page90_i79:b" )
			)
			( pin "R5P3.1"
				( objectStatus "@baseboard_fab2_lib.baseboard_fab2(sch_1):page90_i80:a" )
			)
			( pin "R5P3.2"
				( objectStatus "@baseboard_fab2_lib.baseboard_fab2(sch_1):page90_i80:b" )
			)
			( pin "R6D5.1"
				( objectStatus "@baseboard_fab2_lib.baseboard_fab2(sch_1):page90_i81:a" )
			)
			( pin "R6D5.2"
				( objectStatus "@baseboard_fab2_lib.baseboard_fab2(sch_1):page90_i81:b" )
			)
			( pin "R8P1.1"
				( objectStatus "@baseboard_fab2_lib.baseboard_fab2(sch_1):page90_i85:a" )
			)
			( pin "R8P1.2"
				( objectStatus "@baseboard_fab2_lib.baseboard_fab2(sch_1):page90_i85:b" )
			)
			( pin "R8P2.1"
				( objectStatus "@baseboard_fab2_lib.baseboard_fab2(sch_1):page90_i86:a" )
			)
			( pin "R8P2.2"
				( objectStatus "@baseboard_fab2_lib.baseboard_fab2(sch_1):page90_i86:b" )
			)
			( pin "R3D9.1"
				( objectStatus "@baseboard_fab2_lib.baseboard_fab2(sch_1):page90_i88:a" )
			)
			( pin "R3D9.2"
				( objectStatus "@baseboard_fab2_lib.baseboard_fab2(sch_1):page90_i88:b" )
			)
			( pin "J8B1.1"
				( objectStatus "@baseboard_fab2_lib.baseboard_fab2(sch_1):page91_i1:io1" )
			)
			( pin "J8B1.2"
				( objectStatus "@baseboard_fab2_lib.baseboard_fab2(sch_1):page91_i1:io2" )
			)
			( pin "J8B1.3"
				( objectStatus "@baseboard_fab2_lib.baseboard_fab2(sch_1):page91_i1:io3" )
			)
			( pin "J8B1.4"
				( objectStatus "@baseboard_fab2_lib.baseboard_fab2(sch_1):page91_i1:io4" )
			)
			( pin "J8B1.5"
				( objectStatus "@baseboard_fab2_lib.baseboard_fab2(sch_1):page91_i1:io5" )
			)
			( pin "J8B1.6"
				( objectStatus "@baseboard_fab2_lib.baseboard_fab2(sch_1):page91_i1:io6" )
			)
			( pin "J8B1.7"
				( objectStatus "@baseboard_fab2_lib.baseboard_fab2(sch_1):page91_i1:io7" )
			)
			( pin "J8B1.8"
				( objectStatus "@baseboard_fab2_lib.baseboard_fab2(sch_1):page91_i1:io8" )
			)
			( pin "J8B1.9"
				( objectStatus "@baseboard_fab2_lib.baseboard_fab2(sch_1):page91_i1:io9" )
			)
			( pin "J8B1.10"
				( objectStatus "@baseboard_fab2_lib.baseboard_fab2(sch_1):page91_i1:io10" )
			)
			( pin "J8B1.11"
				( objectStatus "@baseboard_fab2_lib.baseboard_fab2(sch_1):page91_i1:io11" )
			)
			( pin "J8B1.12"
				( objectStatus "@baseboard_fab2_lib.baseboard_fab2(sch_1):page91_i1:io12" )
			)
			( pin "J8B1.13"
				( objectStatus "@baseboard_fab2_lib.baseboard_fab2(sch_1):page91_i1:io13" )
			)
			( pin "J8B1.14"
				( objectStatus "@baseboard_fab2_lib.baseboard_fab2(sch_1):page91_i1:io14" )
			)
			( pin "J8B1.15"
				( objectStatus "@baseboard_fab2_lib.baseboard_fab2(sch_1):page91_i1:io15" )
			)
			( pin "J8B1.16"
				( objectStatus "@baseboard_fab2_lib.baseboard_fab2(sch_1):page91_i1:io16" )
			)
			( pin "J8B1.17"
				( objectStatus "@baseboard_fab2_lib.baseboard_fab2(sch_1):page91_i1:io17" )
			)
			( pin "J8B1.18"
				( objectStatus "@baseboard_fab2_lib.baseboard_fab2(sch_1):page91_i1:io18" )
			)
			( pin "J8B1.19"
				( objectStatus "@baseboard_fab2_lib.baseboard_fab2(sch_1):page91_i1:io19" )
			)
			( pin "J8B1.20"
				( objectStatus "@baseboard_fab2_lib.baseboard_fab2(sch_1):page91_i1:io20" )
			)
			( pin "J8B1.21"
				( objectStatus "@baseboard_fab2_lib.baseboard_fab2(sch_1):page91_i1:io21" )
			)
			( pin "J8B1.22"
				( objectStatus "@baseboard_fab2_lib.baseboard_fab2(sch_1):page91_i1:io22" )
			)
			( pin "J8B1.23"
				( objectStatus "@baseboard_fab2_lib.baseboard_fab2(sch_1):page91_i1:io23" )
			)
			( pin "J8B1.24"
				( objectStatus "@baseboard_fab2_lib.baseboard_fab2(sch_1):page91_i1:io24" )
			)
			( pin "J8B1.MP1"
				( objectStatus "@baseboard_fab2_lib.baseboard_fab2(sch_1):page91_i1:mp1" )
			)
			( pin "J8B1.MP2"
				( objectStatus "@baseboard_fab2_lib.baseboard_fab2(sch_1):page91_i1:mp2" )
			)
			( pin "R8B8.1"
				( objectStatus "@baseboard_fab2_lib.baseboard_fab2(sch_1):page91_i14:a" )
			)
			( pin "R8B8.2"
				( objectStatus "@baseboard_fab2_lib.baseboard_fab2(sch_1):page91_i14:b" )
			)
			( pin "R8B10.1"
				( objectStatus "@baseboard_fab2_lib.baseboard_fab2(sch_1):page91_i16:a" )
			)
			( pin "R8B10.2"
				( objectStatus "@baseboard_fab2_lib.baseboard_fab2(sch_1):page91_i16:b" )
			)
			( pin "R8B16.1"
				( objectStatus "@baseboard_fab2_lib.baseboard_fab2(sch_1):page91_i17:a" )
			)
			( pin "R8B16.2"
				( objectStatus "@baseboard_fab2_lib.baseboard_fab2(sch_1):page91_i17:b" )
			)
			( pin "R8B17.1"
				( objectStatus "@baseboard_fab2_lib.baseboard_fab2(sch_1):page91_i18:a" )
			)
			( pin "R8B17.2"
				( objectStatus "@baseboard_fab2_lib.baseboard_fab2(sch_1):page91_i18:b" )
			)
			( pin "R8B18.1"
				( objectStatus "@baseboard_fab2_lib.baseboard_fab2(sch_1):page91_i20:a" )
			)
			( pin "R8B18.2"
				( objectStatus "@baseboard_fab2_lib.baseboard_fab2(sch_1):page91_i20:b" )
			)
			( pin "R8B19.1"
				( objectStatus "@baseboard_fab2_lib.baseboard_fab2(sch_1):page91_i21:a" )
			)
			( pin "R8B19.2"
				( objectStatus "@baseboard_fab2_lib.baseboard_fab2(sch_1):page91_i21:b" )
			)
			( pin "R8B5.1"
				( objectStatus "@baseboard_fab2_lib.baseboard_fab2(sch_1):page91_i22:a" )
			)
			( pin "R8B5.2"
				( objectStatus "@baseboard_fab2_lib.baseboard_fab2(sch_1):page91_i22:b" )
			)
			( pin "R8B3.1"
				( objectStatus "@baseboard_fab2_lib.baseboard_fab2(sch_1):page91_i24:a" )
			)
			( pin "R8B3.2"
				( objectStatus "@baseboard_fab2_lib.baseboard_fab2(sch_1):page91_i24:b" )
			)
			( pin "R8B13.1"
				( objectStatus "@baseboard_fab2_lib.baseboard_fab2(sch_1):page91_i34:a" )
			)
			( pin "R8B13.2"
				( objectStatus "@baseboard_fab2_lib.baseboard_fab2(sch_1):page91_i34:b" )
			)
			( pin "R8B11.1"
				( objectStatus "@baseboard_fab2_lib.baseboard_fab2(sch_1):page91_i35:a" )
			)
			( pin "R8B11.2"
				( objectStatus "@baseboard_fab2_lib.baseboard_fab2(sch_1):page91_i35:b" )
			)
			( pin "R8B7.1"
				( objectStatus "@baseboard_fab2_lib.baseboard_fab2(sch_1):page91_i36:a" )
			)
			( pin "R8B7.2"
				( objectStatus "@baseboard_fab2_lib.baseboard_fab2(sch_1):page91_i36:b" )
			)
			( pin "R8B6.1"
				( objectStatus "@baseboard_fab2_lib.baseboard_fab2(sch_1):page91_i37:a" )
			)
			( pin "R8B6.2"
				( objectStatus "@baseboard_fab2_lib.baseboard_fab2(sch_1):page91_i37:b" )
			)
			( pin "U3P2.13"
				( objectStatus "@baseboard_fab2_lib.baseboard_fab2(sch_1):page92_i1:a0" )
			)
			( pin "U3P2.12"
				( objectStatus "@baseboard_fab2_lib.baseboard_fab2(sch_1):page92_i1:a1" )
			)
			( pin "U3P2.10"
				( objectStatus "@baseboard_fab2_lib.baseboard_fab2(sch_1):page92_i1:a2" )
			)
			( pin "U3P2.9"
				( objectStatus "@baseboard_fab2_lib.baseboard_fab2(sch_1):page92_i1:a3" )
			)
			( pin "U3P2.2"
				( objectStatus "@baseboard_fab2_lib.baseboard_fab2(sch_1):page92_i1:b0" )
			)
			( pin "U3P2.3"
				( objectStatus "@baseboard_fab2_lib.baseboard_fab2(sch_1):page92_i1:b1" )
			)
			( pin "U3P2.5"
				( objectStatus "@baseboard_fab2_lib.baseboard_fab2(sch_1):page92_i1:b2" )
			)
			( pin "U3P2.6"
				( objectStatus "@baseboard_fab2_lib.baseboard_fab2(sch_1):page92_i1:b3" )
			)
			( pin "U3P2.1"
				( objectStatus "@baseboard_fab2_lib.baseboard_fab2(sch_1):page92_i1:dir" )
			)
			( pin "U3P2.7"
				( objectStatus "@baseboard_fab2_lib.baseboard_fab2(sch_1):page92_i1:gnd(0)" )
			)
			( pin "U3P2.8"
				( objectStatus "@baseboard_fab2_lib.baseboard_fab2(sch_1):page92_i1:gnd(1)" )
			)
			( pin "U3P2.11"
				( objectStatus "@baseboard_fab2_lib.baseboard_fab2(sch_1):page92_i1:gnd(2)" )
			)
			( pin "U3P2.14"
				( objectStatus "@baseboard_fab2_lib.baseboard_fab2(sch_1):page92_i1:vcc" )
			)
			( pin "U3P2.4"
				( objectStatus "@baseboard_fab2_lib.baseboard_fab2(sch_1):page92_i1:vref" )
			)
			( pin "R3P41.1"
				( objectStatus "@baseboard_fab2_lib.baseboard_fab2(sch_1):page92_i9:a" )
			)
			( pin "R3P41.2"
				( objectStatus "@baseboard_fab2_lib.baseboard_fab2(sch_1):page92_i9:b" )
			)
			( pin "R3P46.1"
				( objectStatus "@baseboard_fab2_lib.baseboard_fab2(sch_1):page92_i12:a" )
			)
			( pin "R3P46.2"
				( objectStatus "@baseboard_fab2_lib.baseboard_fab2(sch_1):page92_i12:b" )
			)
			( pin "R3P43.1"
				( objectStatus "@baseboard_fab2_lib.baseboard_fab2(sch_1):page92_i13:a" )
			)
			( pin "R3P43.2"
				( objectStatus "@baseboard_fab2_lib.baseboard_fab2(sch_1):page92_i13:b" )
			)
			( pin "R3P42.1"
				( objectStatus "@baseboard_fab2_lib.baseboard_fab2(sch_1):page92_i14:a" )
			)
			( pin "R3P42.2"
				( objectStatus "@baseboard_fab2_lib.baseboard_fab2(sch_1):page92_i14:b" )
			)
			( pin "R7E2.1"
				( objectStatus "@baseboard_fab2_lib.baseboard_fab2(sch_1):page92_i19:a" )
			)
			( pin "R7E2.2"
				( objectStatus "@baseboard_fab2_lib.baseboard_fab2(sch_1):page92_i19:b" )
			)
			( pin "R7D34.1"
				( objectStatus "@baseboard_fab2_lib.baseboard_fab2(sch_1):page92_i24:a" )
			)
			( pin "R7D34.2"
				( objectStatus "@baseboard_fab2_lib.baseboard_fab2(sch_1):page92_i24:b" )
			)
			( pin "R7D31.1"
				( objectStatus "@baseboard_fab2_lib.baseboard_fab2(sch_1):page92_i29:a" )
			)
			( pin "R7D31.2"
				( objectStatus "@baseboard_fab2_lib.baseboard_fab2(sch_1):page92_i29:b" )
			)
			( pin "R7D29.1"
				( objectStatus "@baseboard_fab2_lib.baseboard_fab2(sch_1):page92_i30:a" )
			)
			( pin "R7D29.2"
				( objectStatus "@baseboard_fab2_lib.baseboard_fab2(sch_1):page92_i30:b" )
			)
			( pin "U7D2.13"
				( objectStatus "@baseboard_fab2_lib.baseboard_fab2(sch_1):page92_i32:a0" )
			)
			( pin "U7D2.12"
				( objectStatus "@baseboard_fab2_lib.baseboard_fab2(sch_1):page92_i32:a1" )
			)
			( pin "U7D2.10"
				( objectStatus "@baseboard_fab2_lib.baseboard_fab2(sch_1):page92_i32:a2" )
			)
			( pin "U7D2.9"
				( objectStatus "@baseboard_fab2_lib.baseboard_fab2(sch_1):page92_i32:a3" )
			)
			( pin "U7D2.2"
				( objectStatus "@baseboard_fab2_lib.baseboard_fab2(sch_1):page92_i32:b0" )
			)
			( pin "U7D2.3"
				( objectStatus "@baseboard_fab2_lib.baseboard_fab2(sch_1):page92_i32:b1" )
			)
			( pin "U7D2.5"
				( objectStatus "@baseboard_fab2_lib.baseboard_fab2(sch_1):page92_i32:b2" )
			)
			( pin "U7D2.6"
				( objectStatus "@baseboard_fab2_lib.baseboard_fab2(sch_1):page92_i32:b3" )
			)
			( pin "U7D2.1"
				( objectStatus "@baseboard_fab2_lib.baseboard_fab2(sch_1):page92_i32:dir" )
			)
			( pin "U7D2.7"
				( objectStatus "@baseboard_fab2_lib.baseboard_fab2(sch_1):page92_i32:gnd(0)" )
			)
			( pin "U7D2.8"
				( objectStatus "@baseboard_fab2_lib.baseboard_fab2(sch_1):page92_i32:gnd(1)" )
			)
			( pin "U7D2.11"
				( objectStatus "@baseboard_fab2_lib.baseboard_fab2(sch_1):page92_i32:gnd(2)" )
			)
			( pin "U7D2.14"
				( objectStatus "@baseboard_fab2_lib.baseboard_fab2(sch_1):page92_i32:vcc" )
			)
			( pin "U7D2.4"
				( objectStatus "@baseboard_fab2_lib.baseboard_fab2(sch_1):page92_i32:vref" )
			)
			( pin "C3P49.1"
				( objectStatus "@baseboard_fab2_lib.baseboard_fab2(sch_1):page92_i37:a" )
			)
			( pin "C3P49.2"
				( objectStatus "@baseboard_fab2_lib.baseboard_fab2(sch_1):page92_i37:b" )
			)
			( pin "R3P49.1"
				( objectStatus "@baseboard_fab2_lib.baseboard_fab2(sch_1):page92_i38:a" )
			)
			( pin "R3P49.2"
				( objectStatus "@baseboard_fab2_lib.baseboard_fab2(sch_1):page92_i38:b" )
			)
			( pin "R3P45.1"
				( objectStatus "@baseboard_fab2_lib.baseboard_fab2(sch_1):page92_i39:a" )
			)
			( pin "R3P45.2"
				( objectStatus "@baseboard_fab2_lib.baseboard_fab2(sch_1):page92_i39:b" )
			)
			( pin "R3R1.1"
				( objectStatus "@baseboard_fab2_lib.baseboard_fab2(sch_1):page92_i46:a" )
			)
			( pin "R3R1.2"
				( objectStatus "@baseboard_fab2_lib.baseboard_fab2(sch_1):page92_i46:b" )
			)
			( pin "R7D32.1"
				( objectStatus "@baseboard_fab2_lib.baseboard_fab2(sch_1):page92_i48:a" )
			)
			( pin "R7D32.2"
				( objectStatus "@baseboard_fab2_lib.baseboard_fab2(sch_1):page92_i48:b" )
			)
			( pin "R7D33.1"
				( objectStatus "@baseboard_fab2_lib.baseboard_fab2(sch_1):page92_i51:a" )
			)
			( pin "R7D33.2"
				( objectStatus "@baseboard_fab2_lib.baseboard_fab2(sch_1):page92_i51:b" )
			)
			( pin "C7D5.1"
				( objectStatus "@baseboard_fab2_lib.baseboard_fab2(sch_1):page92_i52:a" )
			)
			( pin "C7D5.2"
				( objectStatus "@baseboard_fab2_lib.baseboard_fab2(sch_1):page92_i52:b" )
			)
			( pin "R7D26.1"
				( objectStatus "@baseboard_fab2_lib.baseboard_fab2(sch_1):page92_i54:a" )
			)
			( pin "R7D26.2"
				( objectStatus "@baseboard_fab2_lib.baseboard_fab2(sch_1):page92_i54:b" )
			)
			( pin "R3R3.1"
				( objectStatus "@baseboard_fab2_lib.baseboard_fab2(sch_1):page92_i61:a" )
			)
			( pin "R3R3.2"
				( objectStatus "@baseboard_fab2_lib.baseboard_fab2(sch_1):page92_i61:b" )
			)
			( pin "R6D9.1"
				( objectStatus "@baseboard_fab2_lib.baseboard_fab2(sch_1):page92_i64:a" )
			)
			( pin "R6D9.2"
				( objectStatus "@baseboard_fab2_lib.baseboard_fab2(sch_1):page92_i64:b" )
			)
			( pin "R7P27.1"
				( objectStatus "@baseboard_fab2_lib.baseboard_fab2(sch_1):page92_i65:a" )
			)
			( pin "R7P27.2"
				( objectStatus "@baseboard_fab2_lib.baseboard_fab2(sch_1):page92_i65:b" )
			)
			( pin "R7D28.1"
				( objectStatus "@baseboard_fab2_lib.baseboard_fab2(sch_1):page92_i67:a" )
			)
			( pin "R7D28.2"
				( objectStatus "@baseboard_fab2_lib.baseboard_fab2(sch_1):page92_i67:b" )
			)
			( pin "R7D27.1"
				( objectStatus "@baseboard_fab2_lib.baseboard_fab2(sch_1):page92_i68:a" )
			)
			( pin "R7D27.2"
				( objectStatus "@baseboard_fab2_lib.baseboard_fab2(sch_1):page92_i68:b" )
			)
			( pin "R7D25.1"
				( objectStatus "@baseboard_fab2_lib.baseboard_fab2(sch_1):page92_i70:a" )
			)
			( pin "R7D25.2"
				( objectStatus "@baseboard_fab2_lib.baseboard_fab2(sch_1):page92_i70:b" )
			)
			( pin "R3R2.1"
				( objectStatus "@baseboard_fab2_lib.baseboard_fab2(sch_1):page92_i75:a" )
			)
			( pin "R3R2.2"
				( objectStatus "@baseboard_fab2_lib.baseboard_fab2(sch_1):page92_i75:b" )
			)
			( pin "C7D4.1"
				( objectStatus "@baseboard_fab2_lib.baseboard_fab2(sch_1):page92_i79:a" )
			)
			( pin "C7D4.2"
				( objectStatus "@baseboard_fab2_lib.baseboard_fab2(sch_1):page92_i79:b" )
			)
			( pin "C3P50.1"
				( objectStatus "@baseboard_fab2_lib.baseboard_fab2(sch_1):page92_i84:a" )
			)
			( pin "C3P50.2"
				( objectStatus "@baseboard_fab2_lib.baseboard_fab2(sch_1):page92_i84:b" )
			)
			( pin "R2T44.1"
				( objectStatus "@baseboard_fab2_lib.baseboard_fab2(sch_1):page92_i92:a" )
			)
			( pin "R2T44.2"
				( objectStatus "@baseboard_fab2_lib.baseboard_fab2(sch_1):page92_i92:b" )
			)
			( pin "R2T40.1"
				( objectStatus "@baseboard_fab2_lib.baseboard_fab2(sch_1):page92_i93:a" )
			)
			( pin "R2T40.2"
				( objectStatus "@baseboard_fab2_lib.baseboard_fab2(sch_1):page92_i93:b" )
			)
			( pin "R2T37.1"
				( objectStatus "@baseboard_fab2_lib.baseboard_fab2(sch_1):page92_i94:a" )
			)
			( pin "R2T37.2"
				( objectStatus "@baseboard_fab2_lib.baseboard_fab2(sch_1):page92_i94:b" )
			)
			( pin "R2T43.1"
				( objectStatus "@baseboard_fab2_lib.baseboard_fab2(sch_1):page92_i96:a" )
			)
			( pin "R2T43.2"
				( objectStatus "@baseboard_fab2_lib.baseboard_fab2(sch_1):page92_i96:b" )
			)
			( pin "R3P59.1"
				( objectStatus "@baseboard_fab2_lib.baseboard_fab2(sch_1):page92_i97:a" )
			)
			( pin "R3P59.2"
				( objectStatus "@baseboard_fab2_lib.baseboard_fab2(sch_1):page92_i97:b" )
			)
			( pin "R3P58.1"
				( objectStatus "@baseboard_fab2_lib.baseboard_fab2(sch_1):page92_i98:a" )
			)
			( pin "R3P58.2"
				( objectStatus "@baseboard_fab2_lib.baseboard_fab2(sch_1):page92_i98:b" )
			)
			( pin "R7P18.1"
				( objectStatus "@baseboard_fab2_lib.baseboard_fab2(sch_1):page92_i100:a" )
			)
			( pin "R7P18.2"
				( objectStatus "@baseboard_fab2_lib.baseboard_fab2(sch_1):page92_i100:b" )
			)
			( pin "R4R2.1"
				( objectStatus "@baseboard_fab2_lib.baseboard_fab2(sch_1):page92_i101:a" )
			)
			( pin "R4R2.2"
				( objectStatus "@baseboard_fab2_lib.baseboard_fab2(sch_1):page92_i101:b" )
			)
			( pin "R2T27.1"
				( objectStatus "@baseboard_fab2_lib.baseboard_fab2(sch_1):page93_i13:a" )
			)
			( pin "R2T27.2"
				( objectStatus "@baseboard_fab2_lib.baseboard_fab2(sch_1):page93_i13:b" )
			)
			( pin "R2T32.1"
				( objectStatus "@baseboard_fab2_lib.baseboard_fab2(sch_1):page93_i15:a" )
			)
			( pin "R2T32.2"
				( objectStatus "@baseboard_fab2_lib.baseboard_fab2(sch_1):page93_i15:b" )
			)
			( pin "R2T20.1"
				( objectStatus "@baseboard_fab2_lib.baseboard_fab2(sch_1):page93_i16:a" )
			)
			( pin "R2T20.2"
				( objectStatus "@baseboard_fab2_lib.baseboard_fab2(sch_1):page93_i16:b" )
			)
			( pin "R2T17.1"
				( objectStatus "@baseboard_fab2_lib.baseboard_fab2(sch_1):page93_i23:a" )
			)
			( pin "R2T17.2"
				( objectStatus "@baseboard_fab2_lib.baseboard_fab2(sch_1):page93_i23:b" )
			)
			( pin "U2T4.13"
				( objectStatus "@baseboard_fab2_lib.baseboard_fab2(sch_1):page93_i30:a0" )
			)
			( pin "U2T4.12"
				( objectStatus "@baseboard_fab2_lib.baseboard_fab2(sch_1):page93_i30:a1" )
			)
			( pin "U2T4.10"
				( objectStatus "@baseboard_fab2_lib.baseboard_fab2(sch_1):page93_i30:a2" )
			)
			( pin "U2T4.9"
				( objectStatus "@baseboard_fab2_lib.baseboard_fab2(sch_1):page93_i30:a3" )
			)
			( pin "U2T4.2"
				( objectStatus "@baseboard_fab2_lib.baseboard_fab2(sch_1):page93_i30:b0" )
			)
			( pin "U2T4.3"
				( objectStatus "@baseboard_fab2_lib.baseboard_fab2(sch_1):page93_i30:b1" )
			)
			( pin "U2T4.5"
				( objectStatus "@baseboard_fab2_lib.baseboard_fab2(sch_1):page93_i30:b2" )
			)
			( pin "U2T4.6"
				( objectStatus "@baseboard_fab2_lib.baseboard_fab2(sch_1):page93_i30:b3" )
			)
			( pin "U2T4.1"
				( objectStatus "@baseboard_fab2_lib.baseboard_fab2(sch_1):page93_i30:dir" )
			)
			( pin "U2T4.7"
				( objectStatus "@baseboard_fab2_lib.baseboard_fab2(sch_1):page93_i30:gnd(0)" )
			)
			( pin "U2T4.8"
				( objectStatus "@baseboard_fab2_lib.baseboard_fab2(sch_1):page93_i30:gnd(1)" )
			)
			( pin "U2T4.11"
				( objectStatus "@baseboard_fab2_lib.baseboard_fab2(sch_1):page93_i30:gnd(2)" )
			)
			( pin "U2T4.14"
				( objectStatus "@baseboard_fab2_lib.baseboard_fab2(sch_1):page93_i30:vcc" )
			)
			( pin "U2T4.4"
				( objectStatus "@baseboard_fab2_lib.baseboard_fab2(sch_1):page93_i30:vref" )
			)
			( pin "R2T38.1"
				( objectStatus "@baseboard_fab2_lib.baseboard_fab2(sch_1):page93_i39:a" )
			)
			( pin "R2T38.2"
				( objectStatus "@baseboard_fab2_lib.baseboard_fab2(sch_1):page93_i39:b" )
			)
			( pin "R2T33.1"
				( objectStatus "@baseboard_fab2_lib.baseboard_fab2(sch_1):page93_i40:a" )
			)
			( pin "R2T33.2"
				( objectStatus "@baseboard_fab2_lib.baseboard_fab2(sch_1):page93_i40:b" )
			)
			( pin "R2T30.1"
				( objectStatus "@baseboard_fab2_lib.baseboard_fab2(sch_1):page93_i42:a" )
			)
			( pin "R2T30.2"
				( objectStatus "@baseboard_fab2_lib.baseboard_fab2(sch_1):page93_i42:b" )
			)
			( pin "R7D24.1"
				( objectStatus "@baseboard_fab2_lib.baseboard_fab2(sch_1):page93_i62:a" )
			)
			( pin "R7D24.2"
				( objectStatus "@baseboard_fab2_lib.baseboard_fab2(sch_1):page93_i62:b" )
			)
			( pin "R2T19.1"
				( objectStatus "@baseboard_fab2_lib.baseboard_fab2(sch_1):page93_i63:a" )
			)
			( pin "R2T19.2"
				( objectStatus "@baseboard_fab2_lib.baseboard_fab2(sch_1):page93_i63:b" )
			)
			( pin "R2T16.1"
				( objectStatus "@baseboard_fab2_lib.baseboard_fab2(sch_1):page93_i67:a" )
			)
			( pin "R2T16.2"
				( objectStatus "@baseboard_fab2_lib.baseboard_fab2(sch_1):page93_i67:b" )
			)
			( pin "R2T31.1"
				( objectStatus "@baseboard_fab2_lib.baseboard_fab2(sch_1):page93_i68:a" )
			)
			( pin "R2T31.2"
				( objectStatus "@baseboard_fab2_lib.baseboard_fab2(sch_1):page93_i68:b" )
			)
			( pin "C2T33.1"
				( objectStatus "@baseboard_fab2_lib.baseboard_fab2(sch_1):page93_i72:a" )
			)
			( pin "C2T33.2"
				( objectStatus "@baseboard_fab2_lib.baseboard_fab2(sch_1):page93_i72:b" )
			)
			( pin "R4R3.1"
				( objectStatus "@baseboard_fab2_lib.baseboard_fab2(sch_1):page93_i79:a" )
			)
			( pin "R4R3.2"
				( objectStatus "@baseboard_fab2_lib.baseboard_fab2(sch_1):page93_i79:b" )
			)
			( pin "R2T26.1"
				( objectStatus "@baseboard_fab2_lib.baseboard_fab2(sch_1):page93_i87:a" )
			)
			( pin "R2T26.2"
				( objectStatus "@baseboard_fab2_lib.baseboard_fab2(sch_1):page93_i87:b" )
			)
			( pin "R2T57.1"
				( objectStatus "@baseboard_fab2_lib.baseboard_fab2(sch_1):page93_i88:a" )
			)
			( pin "R2T57.2"
				( objectStatus "@baseboard_fab2_lib.baseboard_fab2(sch_1):page93_i88:b" )
			)
			( pin "R2T61.1"
				( objectStatus "@baseboard_fab2_lib.baseboard_fab2(sch_1):page93_i89:a" )
			)
			( pin "R2T61.2"
				( objectStatus "@baseboard_fab2_lib.baseboard_fab2(sch_1):page93_i89:b" )
			)
			( pin "R2T62.1"
				( objectStatus "@baseboard_fab2_lib.baseboard_fab2(sch_1):page93_i93:a" )
			)
			( pin "R2T62.2"
				( objectStatus "@baseboard_fab2_lib.baseboard_fab2(sch_1):page93_i93:b" )
			)
			( pin "R2T58.1"
				( objectStatus "@baseboard_fab2_lib.baseboard_fab2(sch_1):page93_i94:a" )
			)
			( pin "R2T58.2"
				( objectStatus "@baseboard_fab2_lib.baseboard_fab2(sch_1):page93_i94:b" )
			)
			( pin "C2T32.1"
				( objectStatus "@baseboard_fab2_lib.baseboard_fab2(sch_1):page93_i95:a" )
			)
			( pin "C2T32.2"
				( objectStatus "@baseboard_fab2_lib.baseboard_fab2(sch_1):page93_i95:b" )
			)
			( pin "R2T36.1"
				( objectStatus "@baseboard_fab2_lib.baseboard_fab2(sch_1):page93_i97:a" )
			)
			( pin "R2T36.2"
				( objectStatus "@baseboard_fab2_lib.baseboard_fab2(sch_1):page93_i97:b" )
			)
			( pin "R2T39.1"
				( objectStatus "@baseboard_fab2_lib.baseboard_fab2(sch_1):page93_i98:a" )
			)
			( pin "R2T39.2"
				( objectStatus "@baseboard_fab2_lib.baseboard_fab2(sch_1):page93_i98:b" )
			)
			( pin "R2T68.1"
				( objectStatus "@baseboard_fab2_lib.baseboard_fab2(sch_1):page93_i102:a" )
			)
			( pin "R2T68.2"
				( objectStatus "@baseboard_fab2_lib.baseboard_fab2(sch_1):page93_i102:b" )
			)
			( pin "R2T60.1"
				( objectStatus "@baseboard_fab2_lib.baseboard_fab2(sch_1):page93_i103:a" )
			)
			( pin "R2T60.2"
				( objectStatus "@baseboard_fab2_lib.baseboard_fab2(sch_1):page93_i103:b" )
			)
			( pin "R7P28.1"
				( objectStatus "@baseboard_fab2_lib.baseboard_fab2(sch_1):page93_i106:a" )
			)
			( pin "R7P28.2"
				( objectStatus "@baseboard_fab2_lib.baseboard_fab2(sch_1):page93_i106:b" )
			)
			( pin "R2T59.1"
				( objectStatus "@baseboard_fab2_lib.baseboard_fab2(sch_1):page93_i107:a" )
			)
			( pin "R2T59.2"
				( objectStatus "@baseboard_fab2_lib.baseboard_fab2(sch_1):page93_i107:b" )
			)
			( pin "R2T69.1"
				( objectStatus "@baseboard_fab2_lib.baseboard_fab2(sch_1):page93_i108:a" )
			)
			( pin "R2T69.2"
				( objectStatus "@baseboard_fab2_lib.baseboard_fab2(sch_1):page93_i108:b" )
			)
			( pin "R2T71.1"
				( objectStatus "@baseboard_fab2_lib.baseboard_fab2(sch_1):page93_i109:a" )
			)
			( pin "R2T71.2"
				( objectStatus "@baseboard_fab2_lib.baseboard_fab2(sch_1):page93_i109:b" )
			)
			( pin "R7D43.1"
				( objectStatus "@baseboard_fab2_lib.baseboard_fab2(sch_1):page93_i110:a" )
			)
			( pin "R7D43.2"
				( objectStatus "@baseboard_fab2_lib.baseboard_fab2(sch_1):page93_i110:b" )
			)
			( pin "R2T65.1"
				( objectStatus "@baseboard_fab2_lib.baseboard_fab2(sch_1):page93_i111:a" )
			)
			( pin "R2T65.2"
				( objectStatus "@baseboard_fab2_lib.baseboard_fab2(sch_1):page93_i111:b" )
			)
			( pin "R2T66.1"
				( objectStatus "@baseboard_fab2_lib.baseboard_fab2(sch_1):page93_i112:a" )
			)
			( pin "R2T66.2"
				( objectStatus "@baseboard_fab2_lib.baseboard_fab2(sch_1):page93_i112:b" )
			)
			( pin "R2T67.1"
				( objectStatus "@baseboard_fab2_lib.baseboard_fab2(sch_1):page93_i113:a" )
			)
			( pin "R2T67.2"
				( objectStatus "@baseboard_fab2_lib.baseboard_fab2(sch_1):page93_i113:b" )
			)
			( pin "R7D41.1"
				( objectStatus "@baseboard_fab2_lib.baseboard_fab2(sch_1):page93_i114:a" )
			)
			( pin "R7D41.2"
				( objectStatus "@baseboard_fab2_lib.baseboard_fab2(sch_1):page93_i114:b" )
			)
			( pin "R8F38.1"
				( objectStatus "@baseboard_fab2_lib.baseboard_fab2(sch_1):page93_i119:a" )
			)
			( pin "R8F38.2"
				( objectStatus "@baseboard_fab2_lib.baseboard_fab2(sch_1):page93_i119:b" )
			)
			( pin "R2T64.1"
				( objectStatus "@baseboard_fab2_lib.baseboard_fab2(sch_1):page93_i121:a" )
			)
			( pin "R2T64.2"
				( objectStatus "@baseboard_fab2_lib.baseboard_fab2(sch_1):page93_i121:b" )
			)
			( pin "R1T36.1"
				( objectStatus "@baseboard_fab2_lib.baseboard_fab2(sch_1):page93_i122:a" )
			)
			( pin "R1T36.2"
				( objectStatus "@baseboard_fab2_lib.baseboard_fab2(sch_1):page93_i122:b" )
			)
			( pin "R1T37.1"
				( objectStatus "@baseboard_fab2_lib.baseboard_fab2(sch_1):page93_i123:a" )
			)
			( pin "R1T37.2"
				( objectStatus "@baseboard_fab2_lib.baseboard_fab2(sch_1):page93_i123:b" )
			)
			( pin "R2T50.1"
				( objectStatus "@baseboard_fab2_lib.baseboard_fab2(sch_1):page93_i127:a" )
			)
			( pin "R2T50.2"
				( objectStatus "@baseboard_fab2_lib.baseboard_fab2(sch_1):page93_i127:b" )
			)
			( pin "R8F37.1"
				( objectStatus "@baseboard_fab2_lib.baseboard_fab2(sch_1):page93_i131:a" )
			)
			( pin "R8F37.2"
				( objectStatus "@baseboard_fab2_lib.baseboard_fab2(sch_1):page93_i131:b" )
			)
			( pin "R2T63.1"
				( objectStatus "@baseboard_fab2_lib.baseboard_fab2(sch_1):page93_i133:a" )
			)
			( pin "R2T63.2"
				( objectStatus "@baseboard_fab2_lib.baseboard_fab2(sch_1):page93_i133:b" )
			)
			( pin "R1T35.1"
				( objectStatus "@baseboard_fab2_lib.baseboard_fab2(sch_1):page93_i135:a" )
			)
			( pin "R1T35.2"
				( objectStatus "@baseboard_fab2_lib.baseboard_fab2(sch_1):page93_i135:b" )
			)
			( pin "R1T38.1"
				( objectStatus "@baseboard_fab2_lib.baseboard_fab2(sch_1):page93_i137:a" )
			)
			( pin "R1T38.2"
				( objectStatus "@baseboard_fab2_lib.baseboard_fab2(sch_1):page93_i137:b" )
			)
			( pin "R2T72.1"
				( objectStatus "@baseboard_fab2_lib.baseboard_fab2(sch_1):page93_i143:a" )
			)
			( pin "R2T72.2"
				( objectStatus "@baseboard_fab2_lib.baseboard_fab2(sch_1):page93_i143:b" )
			)
			( pin "R2T73.1"
				( objectStatus "@baseboard_fab2_lib.baseboard_fab2(sch_1):page93_i144:a" )
			)
			( pin "R2T73.2"
				( objectStatus "@baseboard_fab2_lib.baseboard_fab2(sch_1):page93_i144:b" )
			)
			( pin "Q3U1.6"
				( objectStatus "@baseboard_fab2_lib.baseboard_fab2(sch_1):page94_i49:drain(0)" )
			)
			( pin "Q3U1.2"
				( objectStatus "@baseboard_fab2_lib.baseboard_fab2(sch_1):page94_i49:gate(0)" )
			)
			( pin "Q3U1.1"
				( objectStatus "@baseboard_fab2_lib.baseboard_fab2(sch_1):page94_i49:source(0)" )
			)
			( pin "R7G7.1"
				( objectStatus "@baseboard_fab2_lib.baseboard_fab2(sch_1):page94_i51:a" )
			)
			( pin "R7G7.2"
				( objectStatus "@baseboard_fab2_lib.baseboard_fab2(sch_1):page94_i51:b" )
			)
			( pin "Q7E1.6"
				( objectStatus "@baseboard_fab2_lib.baseboard_fab2(sch_1):page94_i60:drain(0)" )
			)
			( pin "Q7E1.2"
				( objectStatus "@baseboard_fab2_lib.baseboard_fab2(sch_1):page94_i60:gate(0)" )
			)
			( pin "Q7E1.1"
				( objectStatus "@baseboard_fab2_lib.baseboard_fab2(sch_1):page94_i60:source(0)" )
			)
			( pin "Q7E1.3"
				( objectStatus "@baseboard_fab2_lib.baseboard_fab2(sch_1):page94_i64:drain(0)" )
			)
			( pin "Q7E1.5"
				( objectStatus "@baseboard_fab2_lib.baseboard_fab2(sch_1):page94_i64:gate(0)" )
			)
			( pin "Q7E1.4"
				( objectStatus "@baseboard_fab2_lib.baseboard_fab2(sch_1):page94_i64:source(0)" )
			)
			( pin "R3R4.1"
				( objectStatus "@baseboard_fab2_lib.baseboard_fab2(sch_1):page94_i66:a" )
			)
			( pin "R3R4.2"
				( objectStatus "@baseboard_fab2_lib.baseboard_fab2(sch_1):page94_i66:b" )
			)
			( pin "Q7E2.6"
				( objectStatus "@baseboard_fab2_lib.baseboard_fab2(sch_1):page94_i69:drain(0)" )
			)
			( pin "Q7E2.2"
				( objectStatus "@baseboard_fab2_lib.baseboard_fab2(sch_1):page94_i69:gate(0)" )
			)
			( pin "Q7E2.1"
				( objectStatus "@baseboard_fab2_lib.baseboard_fab2(sch_1):page94_i69:source(0)" )
			)
			( pin "Q7E2.3"
				( objectStatus "@baseboard_fab2_lib.baseboard_fab2(sch_1):page94_i75:drain(0)" )
			)
			( pin "Q7E2.5"
				( objectStatus "@baseboard_fab2_lib.baseboard_fab2(sch_1):page94_i75:gate(0)" )
			)
			( pin "Q7E2.4"
				( objectStatus "@baseboard_fab2_lib.baseboard_fab2(sch_1):page94_i75:source(0)" )
			)
			( pin "Q4B1.3"
				( objectStatus "@baseboard_fab2_lib.baseboard_fab2(sch_1):page94_i77:drain(0)" )
			)
			( pin "Q4B1.5"
				( objectStatus "@baseboard_fab2_lib.baseboard_fab2(sch_1):page94_i77:gate(0)" )
			)
			( pin "Q4B1.4"
				( objectStatus "@baseboard_fab2_lib.baseboard_fab2(sch_1):page94_i77:source(0)" )
			)
			( pin "R3R10.1"
				( objectStatus "@baseboard_fab2_lib.baseboard_fab2(sch_1):page94_i79:a" )
			)
			( pin "R3R10.2"
				( objectStatus "@baseboard_fab2_lib.baseboard_fab2(sch_1):page94_i79:b" )
			)
			( pin "R6M4.1"
				( objectStatus "@baseboard_fab2_lib.baseboard_fab2(sch_1):page94_i82:a" )
			)
			( pin "R6M4.2"
				( objectStatus "@baseboard_fab2_lib.baseboard_fab2(sch_1):page94_i82:b" )
			)
			( pin "Q4B1.6"
				( objectStatus "@baseboard_fab2_lib.baseboard_fab2(sch_1):page94_i84:drain(0)" )
			)
			( pin "Q4B1.2"
				( objectStatus "@baseboard_fab2_lib.baseboard_fab2(sch_1):page94_i84:gate(0)" )
			)
			( pin "Q4B1.1"
				( objectStatus "@baseboard_fab2_lib.baseboard_fab2(sch_1):page94_i84:source(0)" )
			)
			( pin "Q3U1.3"
				( objectStatus "@baseboard_fab2_lib.baseboard_fab2(sch_1):page94_i89:drain(0)" )
			)
			( pin "Q3U1.5"
				( objectStatus "@baseboard_fab2_lib.baseboard_fab2(sch_1):page94_i89:gate(0)" )
			)
			( pin "Q3U1.4"
				( objectStatus "@baseboard_fab2_lib.baseboard_fab2(sch_1):page94_i89:source(0)" )
			)
			( pin "R4U1.1"
				( objectStatus "@baseboard_fab2_lib.baseboard_fab2(sch_1):page94_i91:a" )
			)
			( pin "R4U1.2"
				( objectStatus "@baseboard_fab2_lib.baseboard_fab2(sch_1):page94_i91:b" )
			)
			( pin "R4U3.1"
				( objectStatus "@baseboard_fab2_lib.baseboard_fab2(sch_1):page94_i94:a" )
			)
			( pin "R4U3.2"
				( objectStatus "@baseboard_fab2_lib.baseboard_fab2(sch_1):page94_i94:b" )
			)
			( pin "Q4U1.6"
				( objectStatus "@baseboard_fab2_lib.baseboard_fab2(sch_1):page94_i98:drain(0)" )
			)
			( pin "Q4U1.2"
				( objectStatus "@baseboard_fab2_lib.baseboard_fab2(sch_1):page94_i98:gate(0)" )
			)
			( pin "Q4U1.1"
				( objectStatus "@baseboard_fab2_lib.baseboard_fab2(sch_1):page94_i98:source(0)" )
			)
			( pin "R4U2.1"
				( objectStatus "@baseboard_fab2_lib.baseboard_fab2(sch_1):page94_i100:a" )
			)
			( pin "R4U2.2"
				( objectStatus "@baseboard_fab2_lib.baseboard_fab2(sch_1):page94_i100:b" )
			)
			( pin "Q4U1.3"
				( objectStatus "@baseboard_fab2_lib.baseboard_fab2(sch_1):page94_i102:drain(0)" )
			)
			( pin "Q4U1.5"
				( objectStatus "@baseboard_fab2_lib.baseboard_fab2(sch_1):page94_i102:gate(0)" )
			)
			( pin "Q4U1.4"
				( objectStatus "@baseboard_fab2_lib.baseboard_fab2(sch_1):page94_i102:source(0)" )
			)
			( pin "R4U4.1"
				( objectStatus "@baseboard_fab2_lib.baseboard_fab2(sch_1):page94_i104:a" )
			)
			( pin "R4U4.2"
				( objectStatus "@baseboard_fab2_lib.baseboard_fab2(sch_1):page94_i104:b" )
			)
			( pin "Q2U1.6"
				( objectStatus "@baseboard_fab2_lib.baseboard_fab2(sch_1):page95_i28:drain(0)" )
			)
			( pin "Q2U1.2"
				( objectStatus "@baseboard_fab2_lib.baseboard_fab2(sch_1):page95_i28:gate(0)" )
			)
			( pin "Q2U1.1"
				( objectStatus "@baseboard_fab2_lib.baseboard_fab2(sch_1):page95_i28:source(0)" )
			)
			( pin "Q4B2.6"
				( objectStatus "@baseboard_fab2_lib.baseboard_fab2(sch_1):page95_i32:drain(0)" )
			)
			( pin "Q4B2.2"
				( objectStatus "@baseboard_fab2_lib.baseboard_fab2(sch_1):page95_i32:gate(0)" )
			)
			( pin "Q4B2.1"
				( objectStatus "@baseboard_fab2_lib.baseboard_fab2(sch_1):page95_i32:source(0)" )
			)
			( pin "Q4B2.3"
				( objectStatus "@baseboard_fab2_lib.baseboard_fab2(sch_1):page95_i33:drain(0)" )
			)
			( pin "Q4B2.5"
				( objectStatus "@baseboard_fab2_lib.baseboard_fab2(sch_1):page95_i33:gate(0)" )
			)
			( pin "Q4B2.4"
				( objectStatus "@baseboard_fab2_lib.baseboard_fab2(sch_1):page95_i33:source(0)" )
			)
			( pin "Q7E3.3"
				( objectStatus "@baseboard_fab2_lib.baseboard_fab2(sch_1):page95_i51:drain(0)" )
			)
			( pin "Q7E3.5"
				( objectStatus "@baseboard_fab2_lib.baseboard_fab2(sch_1):page95_i51:gate(0)" )
			)
			( pin "Q7E3.4"
				( objectStatus "@baseboard_fab2_lib.baseboard_fab2(sch_1):page95_i51:source(0)" )
			)
			( pin "Q7E3.6"
				( objectStatus "@baseboard_fab2_lib.baseboard_fab2(sch_1):page95_i52:drain(0)" )
			)
			( pin "Q7E3.2"
				( objectStatus "@baseboard_fab2_lib.baseboard_fab2(sch_1):page95_i52:gate(0)" )
			)
			( pin "Q7E3.1"
				( objectStatus "@baseboard_fab2_lib.baseboard_fab2(sch_1):page95_i52:source(0)" )
			)
			( pin "Q7E5.3"
				( objectStatus "@baseboard_fab2_lib.baseboard_fab2(sch_1):page95_i59:drain(0)" )
			)
			( pin "Q7E5.5"
				( objectStatus "@baseboard_fab2_lib.baseboard_fab2(sch_1):page95_i59:gate(0)" )
			)
			( pin "Q7E5.4"
				( objectStatus "@baseboard_fab2_lib.baseboard_fab2(sch_1):page95_i59:source(0)" )
			)
			( pin "R7E10.1"
				( objectStatus "@baseboard_fab2_lib.baseboard_fab2(sch_1):page95_i62:a" )
			)
			( pin "R7E10.2"
				( objectStatus "@baseboard_fab2_lib.baseboard_fab2(sch_1):page95_i62:b" )
			)
			( pin "Q7E6.3"
				( objectStatus "@baseboard_fab2_lib.baseboard_fab2(sch_1):page95_i69:drain(0)" )
			)
			( pin "Q7E6.5"
				( objectStatus "@baseboard_fab2_lib.baseboard_fab2(sch_1):page95_i69:gate(0)" )
			)
			( pin "Q7E6.4"
				( objectStatus "@baseboard_fab2_lib.baseboard_fab2(sch_1):page95_i69:source(0)" )
			)
			( pin "R7E11.1"
				( objectStatus "@baseboard_fab2_lib.baseboard_fab2(sch_1):page95_i72:a" )
			)
			( pin "R7E11.2"
				( objectStatus "@baseboard_fab2_lib.baseboard_fab2(sch_1):page95_i72:b" )
			)
			( pin "C7E3.1"
				( objectStatus "@baseboard_fab2_lib.baseboard_fab2(sch_1):page95_i92:a" )
			)
			( pin "C7E3.2"
				( objectStatus "@baseboard_fab2_lib.baseboard_fab2(sch_1):page95_i92:b" )
			)
			( pin "Q7E4.3"
				( objectStatus "@baseboard_fab2_lib.baseboard_fab2(sch_1):page95_i104:drn" )
			)
			( pin "Q7E4.1"
				( objectStatus "@baseboard_fab2_lib.baseboard_fab2(sch_1):page95_i104:gate" )
			)
			( pin "Q7E4.2"
				( objectStatus "@baseboard_fab2_lib.baseboard_fab2(sch_1):page95_i104:src" )
			)
			( pin "R7E7.1"
				( objectStatus "@baseboard_fab2_lib.baseboard_fab2(sch_1):page95_i106:a" )
			)
			( pin "R7E7.2"
				( objectStatus "@baseboard_fab2_lib.baseboard_fab2(sch_1):page95_i106:b" )
			)
			( pin "R7E9.1"
				( objectStatus "@baseboard_fab2_lib.baseboard_fab2(sch_1):page95_i108:a" )
			)
			( pin "R7E9.2"
				( objectStatus "@baseboard_fab2_lib.baseboard_fab2(sch_1):page95_i108:b" )
			)
			( pin "Q7E5.6"
				( objectStatus "@baseboard_fab2_lib.baseboard_fab2(sch_1):page95_i111:drain(0)" )
			)
			( pin "Q7E5.2"
				( objectStatus "@baseboard_fab2_lib.baseboard_fab2(sch_1):page95_i111:gate(0)" )
			)
			( pin "Q7E5.1"
				( objectStatus "@baseboard_fab2_lib.baseboard_fab2(sch_1):page95_i111:source(0)" )
			)
			( pin "Q7E6.6"
				( objectStatus "@baseboard_fab2_lib.baseboard_fab2(sch_1):page95_i112:drain(0)" )
			)
			( pin "Q7E6.2"
				( objectStatus "@baseboard_fab2_lib.baseboard_fab2(sch_1):page95_i112:gate(0)" )
			)
			( pin "Q7E6.1"
				( objectStatus "@baseboard_fab2_lib.baseboard_fab2(sch_1):page95_i112:source(0)" )
			)
			( pin "Q2U1.3"
				( objectStatus "@baseboard_fab2_lib.baseboard_fab2(sch_1):page95_i113:drain(0)" )
			)
			( pin "Q2U1.5"
				( objectStatus "@baseboard_fab2_lib.baseboard_fab2(sch_1):page95_i113:gate(0)" )
			)
			( pin "Q2U1.4"
				( objectStatus "@baseboard_fab2_lib.baseboard_fab2(sch_1):page95_i113:source(0)" )
			)
			( pin "C7E4.1"
				( objectStatus "@baseboard_fab2_lib.baseboard_fab2(sch_1):page95_i115:a" )
			)
			( pin "C7E4.2"
				( objectStatus "@baseboard_fab2_lib.baseboard_fab2(sch_1):page95_i115:b" )
			)
			( pin "U7E2.1"
				( objectStatus "@baseboard_fab2_lib.baseboard_fab2(sch_1):page95_i117:a(0)" )
			)
			( pin "U7E2.2"
				( objectStatus "@baseboard_fab2_lib.baseboard_fab2(sch_1):page95_i117:b(0)" )
			)
			( pin "U7E2.4"
				( objectStatus "@baseboard_fab2_lib.baseboard_fab2(sch_1):page95_i117:y(0)" )
			)
			( pin "U7E3.1"
				( objectStatus "@baseboard_fab2_lib.baseboard_fab2(sch_1):page95_i118:a(0)" )
			)
			( pin "U7E3.2"
				( objectStatus "@baseboard_fab2_lib.baseboard_fab2(sch_1):page95_i118:b(0)" )
			)
			( pin "U7E3.4"
				( objectStatus "@baseboard_fab2_lib.baseboard_fab2(sch_1):page95_i118:y(0)" )
			)
			( pin "Q7E8.3"
				( objectStatus "@baseboard_fab2_lib.baseboard_fab2(sch_1):page95_i119:drn" )
			)
			( pin "Q7E8.1"
				( objectStatus "@baseboard_fab2_lib.baseboard_fab2(sch_1):page95_i119:gate" )
			)
			( pin "Q7E8.2"
				( objectStatus "@baseboard_fab2_lib.baseboard_fab2(sch_1):page95_i119:src" )
			)
			( pin "R6D12.1"
				( objectStatus "@baseboard_fab2_lib.baseboard_fab2(sch_1):page96_i2:a" )
			)
			( pin "R6D12.2"
				( objectStatus "@baseboard_fab2_lib.baseboard_fab2(sch_1):page96_i2:b" )
			)
			( pin "R6D8.1"
				( objectStatus "@baseboard_fab2_lib.baseboard_fab2(sch_1):page96_i3:a" )
			)
			( pin "R6D8.2"
				( objectStatus "@baseboard_fab2_lib.baseboard_fab2(sch_1):page96_i3:b" )
			)
			( pin "R3P29.1"
				( objectStatus "@baseboard_fab2_lib.baseboard_fab2(sch_1):page96_i5:a" )
			)
			( pin "R3P29.2"
				( objectStatus "@baseboard_fab2_lib.baseboard_fab2(sch_1):page96_i5:b" )
			)
			( pin "R3P38.1"
				( objectStatus "@baseboard_fab2_lib.baseboard_fab2(sch_1):page96_i7:a" )
			)
			( pin "R3P38.2"
				( objectStatus "@baseboard_fab2_lib.baseboard_fab2(sch_1):page96_i7:b" )
			)
			( pin "R3D20.1"
				( objectStatus "@baseboard_fab2_lib.baseboard_fab2(sch_1):page96_i25:a" )
			)
			( pin "R3D20.2"
				( objectStatus "@baseboard_fab2_lib.baseboard_fab2(sch_1):page96_i25:b" )
			)
			( pin "R3D15.1"
				( objectStatus "@baseboard_fab2_lib.baseboard_fab2(sch_1):page96_i26:a" )
			)
			( pin "R3D15.2"
				( objectStatus "@baseboard_fab2_lib.baseboard_fab2(sch_1):page96_i26:b" )
			)
			( pin "R7M9.1"
				( objectStatus "@baseboard_fab2_lib.baseboard_fab2(sch_1):page96_i28:a" )
			)
			( pin "R7M9.2"
				( objectStatus "@baseboard_fab2_lib.baseboard_fab2(sch_1):page96_i28:b" )
			)
			( pin "R3D21.1"
				( objectStatus "@baseboard_fab2_lib.baseboard_fab2(sch_1):page96_i30:a" )
			)
			( pin "R3D21.2"
				( objectStatus "@baseboard_fab2_lib.baseboard_fab2(sch_1):page96_i30:b" )
			)
			( pin "R3P36.1"
				( objectStatus "@baseboard_fab2_lib.baseboard_fab2(sch_1):page96_i36:a" )
			)
			( pin "R3P36.2"
				( objectStatus "@baseboard_fab2_lib.baseboard_fab2(sch_1):page96_i36:b" )
			)
			( pin "U3P1.13"
				( objectStatus "@baseboard_fab2_lib.baseboard_fab2(sch_1):page96_i42:a0" )
			)
			( pin "U3P1.12"
				( objectStatus "@baseboard_fab2_lib.baseboard_fab2(sch_1):page96_i42:a1" )
			)
			( pin "U3P1.10"
				( objectStatus "@baseboard_fab2_lib.baseboard_fab2(sch_1):page96_i42:a2" )
			)
			( pin "U3P1.9"
				( objectStatus "@baseboard_fab2_lib.baseboard_fab2(sch_1):page96_i42:a3" )
			)
			( pin "U3P1.2"
				( objectStatus "@baseboard_fab2_lib.baseboard_fab2(sch_1):page96_i42:b0" )
			)
			( pin "U3P1.3"
				( objectStatus "@baseboard_fab2_lib.baseboard_fab2(sch_1):page96_i42:b1" )
			)
			( pin "U3P1.5"
				( objectStatus "@baseboard_fab2_lib.baseboard_fab2(sch_1):page96_i42:b2" )
			)
			( pin "U3P1.6"
				( objectStatus "@baseboard_fab2_lib.baseboard_fab2(sch_1):page96_i42:b3" )
			)
			( pin "U3P1.1"
				( objectStatus "@baseboard_fab2_lib.baseboard_fab2(sch_1):page96_i42:dir" )
			)
			( pin "U3P1.7"
				( objectStatus "@baseboard_fab2_lib.baseboard_fab2(sch_1):page96_i42:gnd(0)" )
			)
			( pin "U3P1.8"
				( objectStatus "@baseboard_fab2_lib.baseboard_fab2(sch_1):page96_i42:gnd(1)" )
			)
			( pin "U3P1.11"
				( objectStatus "@baseboard_fab2_lib.baseboard_fab2(sch_1):page96_i42:gnd(2)" )
			)
			( pin "U3P1.14"
				( objectStatus "@baseboard_fab2_lib.baseboard_fab2(sch_1):page96_i42:vcc" )
			)
			( pin "U3P1.4"
				( objectStatus "@baseboard_fab2_lib.baseboard_fab2(sch_1):page96_i42:vref" )
			)
			( pin "U4C2.13"
				( objectStatus "@baseboard_fab2_lib.baseboard_fab2(sch_1):page96_i46:a0" )
			)
			( pin "U4C2.12"
				( objectStatus "@baseboard_fab2_lib.baseboard_fab2(sch_1):page96_i46:a1" )
			)
			( pin "U4C2.10"
				( objectStatus "@baseboard_fab2_lib.baseboard_fab2(sch_1):page96_i46:a2" )
			)
			( pin "U4C2.9"
				( objectStatus "@baseboard_fab2_lib.baseboard_fab2(sch_1):page96_i46:a3" )
			)
			( pin "U4C2.2"
				( objectStatus "@baseboard_fab2_lib.baseboard_fab2(sch_1):page96_i46:b0" )
			)
			( pin "U4C2.3"
				( objectStatus "@baseboard_fab2_lib.baseboard_fab2(sch_1):page96_i46:b1" )
			)
			( pin "U4C2.5"
				( objectStatus "@baseboard_fab2_lib.baseboard_fab2(sch_1):page96_i46:b2" )
			)
			( pin "U4C2.6"
				( objectStatus "@baseboard_fab2_lib.baseboard_fab2(sch_1):page96_i46:b3" )
			)
			( pin "U4C2.1"
				( objectStatus "@baseboard_fab2_lib.baseboard_fab2(sch_1):page96_i46:dir" )
			)
			( pin "U4C2.7"
				( objectStatus "@baseboard_fab2_lib.baseboard_fab2(sch_1):page96_i46:gnd(0)" )
			)
			( pin "U4C2.8"
				( objectStatus "@baseboard_fab2_lib.baseboard_fab2(sch_1):page96_i46:gnd(1)" )
			)
			( pin "U4C2.11"
				( objectStatus "@baseboard_fab2_lib.baseboard_fab2(sch_1):page96_i46:gnd(2)" )
			)
			( pin "U4C2.14"
				( objectStatus "@baseboard_fab2_lib.baseboard_fab2(sch_1):page96_i46:vcc" )
			)
			( pin "U4C2.4"
				( objectStatus "@baseboard_fab2_lib.baseboard_fab2(sch_1):page96_i46:vref" )
			)
			( pin "R4C8.1"
				( objectStatus "@baseboard_fab2_lib.baseboard_fab2(sch_1):page96_i55:a" )
			)
			( pin "R4C8.2"
				( objectStatus "@baseboard_fab2_lib.baseboard_fab2(sch_1):page96_i55:b" )
			)
			( pin "R4C9.1"
				( objectStatus "@baseboard_fab2_lib.baseboard_fab2(sch_1):page96_i69:a" )
			)
			( pin "R4C9.2"
				( objectStatus "@baseboard_fab2_lib.baseboard_fab2(sch_1):page96_i69:b" )
			)
			( pin "R3P32.1"
				( objectStatus "@baseboard_fab2_lib.baseboard_fab2(sch_1):page96_i71:a" )
			)
			( pin "R3P32.2"
				( objectStatus "@baseboard_fab2_lib.baseboard_fab2(sch_1):page96_i71:b" )
			)
			( pin "C3P42.1"
				( objectStatus "@baseboard_fab2_lib.baseboard_fab2(sch_1):page96_i73:a" )
			)
			( pin "C3P42.2"
				( objectStatus "@baseboard_fab2_lib.baseboard_fab2(sch_1):page96_i73:b" )
			)
			( pin "C4C3.1"
				( objectStatus "@baseboard_fab2_lib.baseboard_fab2(sch_1):page96_i75:a" )
			)
			( pin "C4C3.2"
				( objectStatus "@baseboard_fab2_lib.baseboard_fab2(sch_1):page96_i75:b" )
			)
			( pin "R3D18.1"
				( objectStatus "@baseboard_fab2_lib.baseboard_fab2(sch_1):page97_i33:a" )
			)
			( pin "R3D18.2"
				( objectStatus "@baseboard_fab2_lib.baseboard_fab2(sch_1):page97_i33:b" )
			)
			( pin "R4R4.1"
				( objectStatus "@baseboard_fab2_lib.baseboard_fab2(sch_1):page97_i42:a" )
			)
			( pin "R4R4.2"
				( objectStatus "@baseboard_fab2_lib.baseboard_fab2(sch_1):page97_i42:b" )
			)
			( pin "R7P20.1"
				( objectStatus "@baseboard_fab2_lib.baseboard_fab2(sch_1):page97_i44:a" )
			)
			( pin "R7P20.2"
				( objectStatus "@baseboard_fab2_lib.baseboard_fab2(sch_1):page97_i44:b" )
			)
			( pin "R4P21.1"
				( objectStatus "@baseboard_fab2_lib.baseboard_fab2(sch_1):page97_i72:a" )
			)
			( pin "R4P21.2"
				( objectStatus "@baseboard_fab2_lib.baseboard_fab2(sch_1):page97_i72:b" )
			)
			( pin "R4C10.1"
				( objectStatus "@baseboard_fab2_lib.baseboard_fab2(sch_1):page97_i76:a" )
			)
			( pin "R4C10.2"
				( objectStatus "@baseboard_fab2_lib.baseboard_fab2(sch_1):page97_i76:b" )
			)
			( pin "R4P5.1"
				( objectStatus "@baseboard_fab2_lib.baseboard_fab2(sch_1):page97_i80:a" )
			)
			( pin "R4P5.2"
				( objectStatus "@baseboard_fab2_lib.baseboard_fab2(sch_1):page97_i80:b" )
			)
			( pin "R7P13.1"
				( objectStatus "@baseboard_fab2_lib.baseboard_fab2(sch_1):page97_i81:a" )
			)
			( pin "R7P13.2"
				( objectStatus "@baseboard_fab2_lib.baseboard_fab2(sch_1):page97_i81:b" )
			)
			( pin "R4F5.1"
				( objectStatus "@baseboard_fab2_lib.baseboard_fab2(sch_1):page98_i4:a" )
			)
			( pin "R4F5.2"
				( objectStatus "@baseboard_fab2_lib.baseboard_fab2(sch_1):page98_i4:b" )
			)
			( pin "R4F3.1"
				( objectStatus "@baseboard_fab2_lib.baseboard_fab2(sch_1):page98_i5:a" )
			)
			( pin "R4F3.2"
				( objectStatus "@baseboard_fab2_lib.baseboard_fab2(sch_1):page98_i5:b" )
			)
			( pin "C4F9.1"
				( objectStatus "@baseboard_fab2_lib.baseboard_fab2(sch_1):page98_i7:a" )
			)
			( pin "C4F9.2"
				( objectStatus "@baseboard_fab2_lib.baseboard_fab2(sch_1):page98_i7:b" )
			)
			( pin "R6M1.1"
				( objectStatus "@baseboard_fab2_lib.baseboard_fab2(sch_1):page98_i9:a" )
			)
			( pin "R6M1.2"
				( objectStatus "@baseboard_fab2_lib.baseboard_fab2(sch_1):page98_i9:b" )
			)
			( pin "R6L16.1"
				( objectStatus "@baseboard_fab2_lib.baseboard_fab2(sch_1):page98_i12:a" )
			)
			( pin "R6L16.2"
				( objectStatus "@baseboard_fab2_lib.baseboard_fab2(sch_1):page98_i12:b" )
			)
			( pin "R6M2.1"
				( objectStatus "@baseboard_fab2_lib.baseboard_fab2(sch_1):page98_i14:a" )
			)
			( pin "R6M2.2"
				( objectStatus "@baseboard_fab2_lib.baseboard_fab2(sch_1):page98_i14:b" )
			)
			( pin "C6M2.1"
				( objectStatus "@baseboard_fab2_lib.baseboard_fab2(sch_1):page98_i33:a" )
			)
			( pin "C6M2.2"
				( objectStatus "@baseboard_fab2_lib.baseboard_fab2(sch_1):page98_i33:b" )
			)
			( pin "R4F4.1"
				( objectStatus "@baseboard_fab2_lib.baseboard_fab2(sch_1):page98_i36:a" )
			)
			( pin "R4F4.2"
				( objectStatus "@baseboard_fab2_lib.baseboard_fab2(sch_1):page98_i36:b" )
			)
			( pin "R4G2.1"
				( objectStatus "@baseboard_fab2_lib.baseboard_fab2(sch_1):page98_i38:a" )
			)
			( pin "R4G2.2"
				( objectStatus "@baseboard_fab2_lib.baseboard_fab2(sch_1):page98_i38:b" )
			)
			( pin "R4G3.1"
				( objectStatus "@baseboard_fab2_lib.baseboard_fab2(sch_1):page98_i40:a" )
			)
			( pin "R4G3.2"
				( objectStatus "@baseboard_fab2_lib.baseboard_fab2(sch_1):page98_i40:b" )
			)
			( pin "R4G1.1"
				( objectStatus "@baseboard_fab2_lib.baseboard_fab2(sch_1):page98_i42:a" )
			)
			( pin "R4G1.2"
				( objectStatus "@baseboard_fab2_lib.baseboard_fab2(sch_1):page98_i42:b" )
			)
			( pin "C4G1.1"
				( objectStatus "@baseboard_fab2_lib.baseboard_fab2(sch_1):page98_i43:a" )
			)
			( pin "C4G1.2"
				( objectStatus "@baseboard_fab2_lib.baseboard_fab2(sch_1):page98_i43:b" )
			)
			( pin "R4G21.1"
				( objectStatus "@baseboard_fab2_lib.baseboard_fab2(sch_1):page98_i46:a" )
			)
			( pin "R4G21.2"
				( objectStatus "@baseboard_fab2_lib.baseboard_fab2(sch_1):page98_i46:b" )
			)
			( pin "R4G22.1"
				( objectStatus "@baseboard_fab2_lib.baseboard_fab2(sch_1):page98_i48:a" )
			)
			( pin "R4G22.2"
				( objectStatus "@baseboard_fab2_lib.baseboard_fab2(sch_1):page98_i48:b" )
			)
			( pin "R4G20.1"
				( objectStatus "@baseboard_fab2_lib.baseboard_fab2(sch_1):page98_i50:a" )
			)
			( pin "R4G20.2"
				( objectStatus "@baseboard_fab2_lib.baseboard_fab2(sch_1):page98_i50:b" )
			)
			( pin "C4G17.1"
				( objectStatus "@baseboard_fab2_lib.baseboard_fab2(sch_1):page98_i51:a" )
			)
			( pin "C4G17.2"
				( objectStatus "@baseboard_fab2_lib.baseboard_fab2(sch_1):page98_i51:b" )
			)
			( pin "R6L13.1"
				( objectStatus "@baseboard_fab2_lib.baseboard_fab2(sch_1):page98_i54:a" )
			)
			( pin "R6L13.2"
				( objectStatus "@baseboard_fab2_lib.baseboard_fab2(sch_1):page98_i54:b" )
			)
			( pin "R6L12.1"
				( objectStatus "@baseboard_fab2_lib.baseboard_fab2(sch_1):page98_i56:a" )
			)
			( pin "R6L12.2"
				( objectStatus "@baseboard_fab2_lib.baseboard_fab2(sch_1):page98_i56:b" )
			)
			( pin "R6L14.1"
				( objectStatus "@baseboard_fab2_lib.baseboard_fab2(sch_1):page98_i58:a" )
			)
			( pin "R6L14.2"
				( objectStatus "@baseboard_fab2_lib.baseboard_fab2(sch_1):page98_i58:b" )
			)
			( pin "C6L7.1"
				( objectStatus "@baseboard_fab2_lib.baseboard_fab2(sch_1):page98_i59:a" )
			)
			( pin "C6L7.2"
				( objectStatus "@baseboard_fab2_lib.baseboard_fab2(sch_1):page98_i59:b" )
			)
			( pin "R6L2.1"
				( objectStatus "@baseboard_fab2_lib.baseboard_fab2(sch_1):page98_i62:a" )
			)
			( pin "R6L2.2"
				( objectStatus "@baseboard_fab2_lib.baseboard_fab2(sch_1):page98_i62:b" )
			)
			( pin "R6L1.1"
				( objectStatus "@baseboard_fab2_lib.baseboard_fab2(sch_1):page98_i64:a" )
			)
			( pin "R6L1.2"
				( objectStatus "@baseboard_fab2_lib.baseboard_fab2(sch_1):page98_i64:b" )
			)
			( pin "R6L3.1"
				( objectStatus "@baseboard_fab2_lib.baseboard_fab2(sch_1):page98_i66:a" )
			)
			( pin "R6L3.2"
				( objectStatus "@baseboard_fab2_lib.baseboard_fab2(sch_1):page98_i66:b" )
			)
			( pin "C6L2.1"
				( objectStatus "@baseboard_fab2_lib.baseboard_fab2(sch_1):page98_i67:a" )
			)
			( pin "C6L2.2"
				( objectStatus "@baseboard_fab2_lib.baseboard_fab2(sch_1):page98_i67:b" )
			)
			( pin "C6F2.1"
				( objectStatus "@baseboard_fab2_lib.baseboard_fab2(sch_1):page99_i2:a" )
			)
			( pin "C6F2.2"
				( objectStatus "@baseboard_fab2_lib.baseboard_fab2(sch_1):page99_i2:b" )
			)
			( pin "C6F3.1"
				( objectStatus "@baseboard_fab2_lib.baseboard_fab2(sch_1):page99_i7:a" )
			)
			( pin "C6F3.2"
				( objectStatus "@baseboard_fab2_lib.baseboard_fab2(sch_1):page99_i7:b" )
			)
			( pin "R4T9.1"
				( objectStatus "@baseboard_fab2_lib.baseboard_fab2(sch_1):page99_i9:a" )
			)
			( pin "R4T9.2"
				( objectStatus "@baseboard_fab2_lib.baseboard_fab2(sch_1):page99_i9:b" )
			)
			( pin "R4T10.1"
				( objectStatus "@baseboard_fab2_lib.baseboard_fab2(sch_1):page99_i10:a" )
			)
			( pin "R4T10.2"
				( objectStatus "@baseboard_fab2_lib.baseboard_fab2(sch_1):page99_i10:b" )
			)
			( pin "R4T8.1"
				( objectStatus "@baseboard_fab2_lib.baseboard_fab2(sch_1):page99_i11:a" )
			)
			( pin "R4T8.2"
				( objectStatus "@baseboard_fab2_lib.baseboard_fab2(sch_1):page99_i11:b" )
			)
			( pin "R4T7.1"
				( objectStatus "@baseboard_fab2_lib.baseboard_fab2(sch_1):page99_i13:a" )
			)
			( pin "R4T7.2"
				( objectStatus "@baseboard_fab2_lib.baseboard_fab2(sch_1):page99_i13:b" )
			)
			( pin "U6F1.5"
				( objectStatus "@baseboard_fab2_lib.baseboard_fab2(sch_1):page99_i15:en" )
			)
			( pin "U6F1.2"
				( objectStatus "@baseboard_fab2_lib.baseboard_fab2(sch_1):page99_i15:scla" )
			)
			( pin "U6F1.7"
				( objectStatus "@baseboard_fab2_lib.baseboard_fab2(sch_1):page99_i15:sclb" )
			)
			( pin "U6F1.3"
				( objectStatus "@baseboard_fab2_lib.baseboard_fab2(sch_1):page99_i15:sdaa" )
			)
			( pin "U6F1.6"
				( objectStatus "@baseboard_fab2_lib.baseboard_fab2(sch_1):page99_i15:sdab" )
			)
			( pin "U6F1.1"
				( objectStatus "@baseboard_fab2_lib.baseboard_fab2(sch_1):page99_i15:vcca" )
			)
			( pin "U6F1.8"
				( objectStatus "@baseboard_fab2_lib.baseboard_fab2(sch_1):page99_i15:vccb" )
			)
			( pin "R4T6.1"
				( objectStatus "@baseboard_fab2_lib.baseboard_fab2(sch_1):page99_i17:a" )
			)
			( pin "R4T6.2"
				( objectStatus "@baseboard_fab2_lib.baseboard_fab2(sch_1):page99_i17:b" )
			)
			( pin "R4T5.1"
				( objectStatus "@baseboard_fab2_lib.baseboard_fab2(sch_1):page99_i19:a" )
			)
			( pin "R4T5.2"
				( objectStatus "@baseboard_fab2_lib.baseboard_fab2(sch_1):page99_i19:b" )
			)
			( pin "R4T4.1"
				( objectStatus "@baseboard_fab2_lib.baseboard_fab2(sch_1):page99_i20:a" )
			)
			( pin "R4T4.2"
				( objectStatus "@baseboard_fab2_lib.baseboard_fab2(sch_1):page99_i20:b" )
			)
			( pin "C7E1.1"
				( objectStatus "@baseboard_fab2_lib.baseboard_fab2(sch_1):page99_i23:a" )
			)
			( pin "C7E1.2"
				( objectStatus "@baseboard_fab2_lib.baseboard_fab2(sch_1):page99_i23:b" )
			)
			( pin "C4G22.1"
				( objectStatus "@baseboard_fab2_lib.baseboard_fab2(sch_1):page99_i27:a" )
			)
			( pin "C4G22.2"
				( objectStatus "@baseboard_fab2_lib.baseboard_fab2(sch_1):page99_i27:b" )
			)
			( pin "C7E2.1"
				( objectStatus "@baseboard_fab2_lib.baseboard_fab2(sch_1):page99_i32:a" )
			)
			( pin "C7E2.2"
				( objectStatus "@baseboard_fab2_lib.baseboard_fab2(sch_1):page99_i32:b" )
			)
			( pin "R3R9.1"
				( objectStatus "@baseboard_fab2_lib.baseboard_fab2(sch_1):page99_i34:a" )
			)
			( pin "R3R9.2"
				( objectStatus "@baseboard_fab2_lib.baseboard_fab2(sch_1):page99_i34:b" )
			)
			( pin "R3R8.1"
				( objectStatus "@baseboard_fab2_lib.baseboard_fab2(sch_1):page99_i35:a" )
			)
			( pin "R3R8.2"
				( objectStatus "@baseboard_fab2_lib.baseboard_fab2(sch_1):page99_i35:b" )
			)
			( pin "C4G25.1"
				( objectStatus "@baseboard_fab2_lib.baseboard_fab2(sch_1):page99_i41:a" )
			)
			( pin "C4G25.2"
				( objectStatus "@baseboard_fab2_lib.baseboard_fab2(sch_1):page99_i41:b" )
			)
			( pin "R6U13.1"
				( objectStatus "@baseboard_fab2_lib.baseboard_fab2(sch_1):page99_i42:a" )
			)
			( pin "R6U13.2"
				( objectStatus "@baseboard_fab2_lib.baseboard_fab2(sch_1):page99_i42:b" )
			)
			( pin "R6U14.1"
				( objectStatus "@baseboard_fab2_lib.baseboard_fab2(sch_1):page99_i43:a" )
			)
			( pin "R6U14.2"
				( objectStatus "@baseboard_fab2_lib.baseboard_fab2(sch_1):page99_i43:b" )
			)
			( pin "C3B4.1"
				( objectStatus "@baseboard_fab2_lib.baseboard_fab2(sch_1):page99_i47:a" )
			)
			( pin "C3B4.2"
				( objectStatus "@baseboard_fab2_lib.baseboard_fab2(sch_1):page99_i47:b" )
			)
			( pin "C3B5.1"
				( objectStatus "@baseboard_fab2_lib.baseboard_fab2(sch_1):page99_i53:a" )
			)
			( pin "C3B5.2"
				( objectStatus "@baseboard_fab2_lib.baseboard_fab2(sch_1):page99_i53:b" )
			)
			( pin "R7M5.1"
				( objectStatus "@baseboard_fab2_lib.baseboard_fab2(sch_1):page99_i55:a" )
			)
			( pin "R7M5.2"
				( objectStatus "@baseboard_fab2_lib.baseboard_fab2(sch_1):page99_i55:b" )
			)
			( pin "R7M4.1"
				( objectStatus "@baseboard_fab2_lib.baseboard_fab2(sch_1):page99_i56:a" )
			)
			( pin "R7M4.2"
				( objectStatus "@baseboard_fab2_lib.baseboard_fab2(sch_1):page99_i56:b" )
			)
			( pin "U7E1.5"
				( objectStatus "@baseboard_fab2_lib.baseboard_fab2(sch_1):page99_i61:en" )
			)
			( pin "U7E1.2"
				( objectStatus "@baseboard_fab2_lib.baseboard_fab2(sch_1):page99_i61:scla" )
			)
			( pin "U7E1.7"
				( objectStatus "@baseboard_fab2_lib.baseboard_fab2(sch_1):page99_i61:sclb" )
			)
			( pin "U7E1.3"
				( objectStatus "@baseboard_fab2_lib.baseboard_fab2(sch_1):page99_i61:sdaa" )
			)
			( pin "U7E1.6"
				( objectStatus "@baseboard_fab2_lib.baseboard_fab2(sch_1):page99_i61:sdab" )
			)
			( pin "U7E1.1"
				( objectStatus "@baseboard_fab2_lib.baseboard_fab2(sch_1):page99_i61:vcca" )
			)
			( pin "U7E1.8"
				( objectStatus "@baseboard_fab2_lib.baseboard_fab2(sch_1):page99_i61:vccb" )
			)
			( pin "U4G1.5"
				( objectStatus "@baseboard_fab2_lib.baseboard_fab2(sch_1):page99_i63:en" )
			)
			( pin "U4G1.2"
				( objectStatus "@baseboard_fab2_lib.baseboard_fab2(sch_1):page99_i63:scla" )
			)
			( pin "U4G1.7"
				( objectStatus "@baseboard_fab2_lib.baseboard_fab2(sch_1):page99_i63:sclb" )
			)
			( pin "U4G1.3"
				( objectStatus "@baseboard_fab2_lib.baseboard_fab2(sch_1):page99_i63:sdaa" )
			)
			( pin "U4G1.6"
				( objectStatus "@baseboard_fab2_lib.baseboard_fab2(sch_1):page99_i63:sdab" )
			)
			( pin "U4G1.1"
				( objectStatus "@baseboard_fab2_lib.baseboard_fab2(sch_1):page99_i63:vcca" )
			)
			( pin "U4G1.8"
				( objectStatus "@baseboard_fab2_lib.baseboard_fab2(sch_1):page99_i63:vccb" )
			)
			( pin "R3R13.1"
				( objectStatus "@baseboard_fab2_lib.baseboard_fab2(sch_1):page99_i65:a" )
			)
			( pin "R3R13.2"
				( objectStatus "@baseboard_fab2_lib.baseboard_fab2(sch_1):page99_i65:b" )
			)
			( pin "R3P60.1"
				( objectStatus "@baseboard_fab2_lib.baseboard_fab2(sch_1):page99_i67:a" )
			)
			( pin "R3P60.2"
				( objectStatus "@baseboard_fab2_lib.baseboard_fab2(sch_1):page99_i67:b" )
			)
			( pin "R6T1.1"
				( objectStatus "@baseboard_fab2_lib.baseboard_fab2(sch_1):page99_i70:a" )
			)
			( pin "R6T1.2"
				( objectStatus "@baseboard_fab2_lib.baseboard_fab2(sch_1):page99_i70:b" )
			)
			( pin "R6T2.1"
				( objectStatus "@baseboard_fab2_lib.baseboard_fab2(sch_1):page99_i72:a" )
			)
			( pin "R6T2.2"
				( objectStatus "@baseboard_fab2_lib.baseboard_fab2(sch_1):page99_i72:b" )
			)
			( pin "U3B1.5"
				( objectStatus "@baseboard_fab2_lib.baseboard_fab2(sch_1):page99_i75:en" )
			)
			( pin "U3B1.2"
				( objectStatus "@baseboard_fab2_lib.baseboard_fab2(sch_1):page99_i75:scla" )
			)
			( pin "U3B1.7"
				( objectStatus "@baseboard_fab2_lib.baseboard_fab2(sch_1):page99_i75:sclb" )
			)
			( pin "U3B1.3"
				( objectStatus "@baseboard_fab2_lib.baseboard_fab2(sch_1):page99_i75:sdaa" )
			)
			( pin "U3B1.6"
				( objectStatus "@baseboard_fab2_lib.baseboard_fab2(sch_1):page99_i75:sdab" )
			)
			( pin "U3B1.1"
				( objectStatus "@baseboard_fab2_lib.baseboard_fab2(sch_1):page99_i75:vcca" )
			)
			( pin "U3B1.8"
				( objectStatus "@baseboard_fab2_lib.baseboard_fab2(sch_1):page99_i75:vccb" )
			)
			( pin "R7M7.1"
				( objectStatus "@baseboard_fab2_lib.baseboard_fab2(sch_1):page99_i77:a" )
			)
			( pin "R7M7.2"
				( objectStatus "@baseboard_fab2_lib.baseboard_fab2(sch_1):page99_i77:b" )
			)
			( pin "R7M2.1"
				( objectStatus "@baseboard_fab2_lib.baseboard_fab2(sch_1):page99_i79:a" )
			)
			( pin "R7M2.2"
				( objectStatus "@baseboard_fab2_lib.baseboard_fab2(sch_1):page99_i79:b" )
			)
			( pin "R4T3.1"
				( objectStatus "@baseboard_fab2_lib.baseboard_fab2(sch_1):page99_i83:a" )
			)
			( pin "R4T3.2"
				( objectStatus "@baseboard_fab2_lib.baseboard_fab2(sch_1):page99_i83:b" )
			)
			( pin "R3R7.1"
				( objectStatus "@baseboard_fab2_lib.baseboard_fab2(sch_1):page99_i88:a" )
			)
			( pin "R3R7.2"
				( objectStatus "@baseboard_fab2_lib.baseboard_fab2(sch_1):page99_i88:b" )
			)
			( pin "R6T3.1"
				( objectStatus "@baseboard_fab2_lib.baseboard_fab2(sch_1):page99_i92:a" )
			)
			( pin "R6T3.2"
				( objectStatus "@baseboard_fab2_lib.baseboard_fab2(sch_1):page99_i92:b" )
			)
			( pin "R7M3.1"
				( objectStatus "@baseboard_fab2_lib.baseboard_fab2(sch_1):page99_i98:a" )
			)
			( pin "R7M3.2"
				( objectStatus "@baseboard_fab2_lib.baseboard_fab2(sch_1):page99_i98:b" )
			)
			( pin "R3R12.1"
				( objectStatus "@baseboard_fab2_lib.baseboard_fab2(sch_1):page99_i101:a" )
			)
			( pin "R3R12.2"
				( objectStatus "@baseboard_fab2_lib.baseboard_fab2(sch_1):page99_i101:b" )
			)
			( pin "R3R5.1"
				( objectStatus "@baseboard_fab2_lib.baseboard_fab2(sch_1):page99_i103:a" )
			)
			( pin "R3R5.2"
				( objectStatus "@baseboard_fab2_lib.baseboard_fab2(sch_1):page99_i103:b" )
			)
			( pin "R6U18.1"
				( objectStatus "@baseboard_fab2_lib.baseboard_fab2(sch_1):page99_i104:a" )
			)
			( pin "R6U18.2"
				( objectStatus "@baseboard_fab2_lib.baseboard_fab2(sch_1):page99_i104:b" )
			)
			( pin "R6U17.1"
				( objectStatus "@baseboard_fab2_lib.baseboard_fab2(sch_1):page99_i106:a" )
			)
			( pin "R6U17.2"
				( objectStatus "@baseboard_fab2_lib.baseboard_fab2(sch_1):page99_i106:b" )
			)
			( pin "R7M6.1"
				( objectStatus "@baseboard_fab2_lib.baseboard_fab2(sch_1):page99_i107:a" )
			)
			( pin "R7M6.2"
				( objectStatus "@baseboard_fab2_lib.baseboard_fab2(sch_1):page99_i107:b" )
			)
			( pin "R7M1.1"
				( objectStatus "@baseboard_fab2_lib.baseboard_fab2(sch_1):page99_i109:a" )
			)
			( pin "R7M1.2"
				( objectStatus "@baseboard_fab2_lib.baseboard_fab2(sch_1):page99_i109:b" )
			)
			( pin "R3R14.1"
				( objectStatus "@baseboard_fab2_lib.baseboard_fab2(sch_1):page99_i110:a" )
			)
			( pin "R3R14.2"
				( objectStatus "@baseboard_fab2_lib.baseboard_fab2(sch_1):page99_i110:b" )
			)
			( pin "R6T4.1"
				( objectStatus "@baseboard_fab2_lib.baseboard_fab2(sch_1):page99_i111:a" )
			)
			( pin "R6T4.2"
				( objectStatus "@baseboard_fab2_lib.baseboard_fab2(sch_1):page99_i111:b" )
			)
			( pin "R7M8.1"
				( objectStatus "@baseboard_fab2_lib.baseboard_fab2(sch_1):page99_i112:a" )
			)
			( pin "R7M8.2"
				( objectStatus "@baseboard_fab2_lib.baseboard_fab2(sch_1):page99_i112:b" )
			)
			( pin "R1F6.1"
				( objectStatus "@baseboard_fab2_lib.baseboard_fab2(sch_1):page100_i2:a" )
			)
			( pin "R1F6.2"
				( objectStatus "@baseboard_fab2_lib.baseboard_fab2(sch_1):page100_i2:b" )
			)
			( pin "R9L11.1"
				( objectStatus "@baseboard_fab2_lib.baseboard_fab2(sch_1):page100_i4:a" )
			)
			( pin "R9L11.2"
				( objectStatus "@baseboard_fab2_lib.baseboard_fab2(sch_1):page100_i4:b" )
			)
			( pin "R1F5.1"
				( objectStatus "@baseboard_fab2_lib.baseboard_fab2(sch_1):page100_i6:a" )
			)
			( pin "R1F5.2"
				( objectStatus "@baseboard_fab2_lib.baseboard_fab2(sch_1):page100_i6:b" )
			)
			( pin "R1F4.1"
				( objectStatus "@baseboard_fab2_lib.baseboard_fab2(sch_1):page100_i7:a" )
			)
			( pin "R1F4.2"
				( objectStatus "@baseboard_fab2_lib.baseboard_fab2(sch_1):page100_i7:b" )
			)
			( pin "C1F19.1"
				( objectStatus "@baseboard_fab2_lib.baseboard_fab2(sch_1):page100_i8:a" )
			)
			( pin "C1F19.2"
				( objectStatus "@baseboard_fab2_lib.baseboard_fab2(sch_1):page100_i8:b" )
			)
			( pin "R9M1.1"
				( objectStatus "@baseboard_fab2_lib.baseboard_fab2(sch_1):page100_i11:a" )
			)
			( pin "R9M1.2"
				( objectStatus "@baseboard_fab2_lib.baseboard_fab2(sch_1):page100_i11:b" )
			)
			( pin "R9M2.1"
				( objectStatus "@baseboard_fab2_lib.baseboard_fab2(sch_1):page100_i13:a" )
			)
			( pin "R9M2.2"
				( objectStatus "@baseboard_fab2_lib.baseboard_fab2(sch_1):page100_i13:b" )
			)
			( pin "C9M2.1"
				( objectStatus "@baseboard_fab2_lib.baseboard_fab2(sch_1):page100_i15:a" )
			)
			( pin "C9M2.2"
				( objectStatus "@baseboard_fab2_lib.baseboard_fab2(sch_1):page100_i15:b" )
			)
			( pin "R1G2.1"
				( objectStatus "@baseboard_fab2_lib.baseboard_fab2(sch_1):page100_i19:a" )
			)
			( pin "R1G2.2"
				( objectStatus "@baseboard_fab2_lib.baseboard_fab2(sch_1):page100_i19:b" )
			)
			( pin "R1G3.1"
				( objectStatus "@baseboard_fab2_lib.baseboard_fab2(sch_1):page100_i20:a" )
			)
			( pin "R1G3.2"
				( objectStatus "@baseboard_fab2_lib.baseboard_fab2(sch_1):page100_i20:b" )
			)
			( pin "R9L7.1"
				( objectStatus "@baseboard_fab2_lib.baseboard_fab2(sch_1):page100_i22:a" )
			)
			( pin "R9L7.2"
				( objectStatus "@baseboard_fab2_lib.baseboard_fab2(sch_1):page100_i22:b" )
			)
			( pin "R9L6.1"
				( objectStatus "@baseboard_fab2_lib.baseboard_fab2(sch_1):page100_i24:a" )
			)
			( pin "R9L6.2"
				( objectStatus "@baseboard_fab2_lib.baseboard_fab2(sch_1):page100_i24:b" )
			)
			( pin "R1G1.1"
				( objectStatus "@baseboard_fab2_lib.baseboard_fab2(sch_1):page100_i25:a" )
			)
			( pin "R1G1.2"
				( objectStatus "@baseboard_fab2_lib.baseboard_fab2(sch_1):page100_i25:b" )
			)
			( pin "C1G8.1"
				( objectStatus "@baseboard_fab2_lib.baseboard_fab2(sch_1):page100_i26:a" )
			)
			( pin "C1G8.2"
				( objectStatus "@baseboard_fab2_lib.baseboard_fab2(sch_1):page100_i26:b" )
			)
			( pin "R9L8.1"
				( objectStatus "@baseboard_fab2_lib.baseboard_fab2(sch_1):page100_i29:a" )
			)
			( pin "R9L8.2"
				( objectStatus "@baseboard_fab2_lib.baseboard_fab2(sch_1):page100_i29:b" )
			)
			( pin "C9L8.1"
				( objectStatus "@baseboard_fab2_lib.baseboard_fab2(sch_1):page100_i30:a" )
			)
			( pin "C9L8.2"
				( objectStatus "@baseboard_fab2_lib.baseboard_fab2(sch_1):page100_i30:b" )
			)
			( pin "R1G15.1"
				( objectStatus "@baseboard_fab2_lib.baseboard_fab2(sch_1):page100_i35:a" )
			)
			( pin "R1G15.2"
				( objectStatus "@baseboard_fab2_lib.baseboard_fab2(sch_1):page100_i35:b" )
			)
			( pin "R1G17.1"
				( objectStatus "@baseboard_fab2_lib.baseboard_fab2(sch_1):page100_i36:a" )
			)
			( pin "R1G17.2"
				( objectStatus "@baseboard_fab2_lib.baseboard_fab2(sch_1):page100_i36:b" )
			)
			( pin "R9L2.1"
				( objectStatus "@baseboard_fab2_lib.baseboard_fab2(sch_1):page100_i38:a" )
			)
			( pin "R9L2.2"
				( objectStatus "@baseboard_fab2_lib.baseboard_fab2(sch_1):page100_i38:b" )
			)
			( pin "R9L1.1"
				( objectStatus "@baseboard_fab2_lib.baseboard_fab2(sch_1):page100_i40:a" )
			)
			( pin "R9L1.2"
				( objectStatus "@baseboard_fab2_lib.baseboard_fab2(sch_1):page100_i40:b" )
			)
			( pin "R1G14.1"
				( objectStatus "@baseboard_fab2_lib.baseboard_fab2(sch_1):page100_i41:a" )
			)
			( pin "R1G14.2"
				( objectStatus "@baseboard_fab2_lib.baseboard_fab2(sch_1):page100_i41:b" )
			)
			( pin "C1G18.1"
				( objectStatus "@baseboard_fab2_lib.baseboard_fab2(sch_1):page100_i42:a" )
			)
			( pin "C1G18.2"
				( objectStatus "@baseboard_fab2_lib.baseboard_fab2(sch_1):page100_i42:b" )
			)
			( pin "R9L3.1"
				( objectStatus "@baseboard_fab2_lib.baseboard_fab2(sch_1):page100_i45:a" )
			)
			( pin "R9L3.2"
				( objectStatus "@baseboard_fab2_lib.baseboard_fab2(sch_1):page100_i45:b" )
			)
			( pin "C9L3.1"
				( objectStatus "@baseboard_fab2_lib.baseboard_fab2(sch_1):page100_i46:a" )
			)
			( pin "C9L3.2"
				( objectStatus "@baseboard_fab2_lib.baseboard_fab2(sch_1):page100_i46:b" )
			)
			( pin "R8F29.1"
				( objectStatus "@baseboard_fab2_lib.baseboard_fab2(sch_1):page101_i20:a" )
			)
			( pin "R8F29.2"
				( objectStatus "@baseboard_fab2_lib.baseboard_fab2(sch_1):page101_i20:b" )
			)
			( pin "R8F25.1"
				( objectStatus "@baseboard_fab2_lib.baseboard_fab2(sch_1):page101_i28:a" )
			)
			( pin "R8F25.2"
				( objectStatus "@baseboard_fab2_lib.baseboard_fab2(sch_1):page101_i28:b" )
			)
			( pin "EU8F2.16"
				( objectStatus "@baseboard_fab2_lib.baseboard_fab2(sch_1):page101_i34:\25mhz_0\" )
			)
			( pin "EU8F2.17"
				( objectStatus "@baseboard_fab2_lib.baseboard_fab2(sch_1):page101_i34:\25mhz_1\" )
			)
			( pin "EU8F2.13"
				( objectStatus "@baseboard_fab2_lib.baseboard_fab2(sch_1):page101_i34:\32khz\" )
			)
			( pin "EU8F2.22"
				( objectStatus "@baseboard_fab2_lib.baseboard_fab2(sch_1):page101_i34:\33mhz_smbadr\" )
			)
			( pin "EU8F2.8"
				( objectStatus "@baseboard_fab2_lib.baseboard_fab2(sch_1):page101_i34:cpuclkc0" )
			)
			( pin "EU8F2.7"
				( objectStatus "@baseboard_fab2_lib.baseboard_fab2(sch_1):page101_i34:cpuclkt0" )
			)
			( pin "EU8F2.4"
				( objectStatus "@baseboard_fab2_lib.baseboard_fab2(sch_1):page101_i34:dot96ssc" )
			)
			( pin "EU8F2.3"
				( objectStatus "@baseboard_fab2_lib.baseboard_fab2(sch_1):page101_i34:dot96sst" )
			)
			( pin "EU8F2.1"
				( objectStatus "@baseboard_fab2_lib.baseboard_fab2(sch_1):page101_i34:gnd(0)" )
			)
			( pin "EU8F2.41"
				( objectStatus "@baseboard_fab2_lib.baseboard_fab2(sch_1):page101_i34:gnd(1)" )
			)
			( pin "EU8F2.14"
				( objectStatus "@baseboard_fab2_lib.baseboard_fab2(sch_1):page101_i34:gnd32k" )
			)
			( pin "EU8F2.21"
				( objectStatus "@baseboard_fab2_lib.baseboard_fab2(sch_1):page101_i34:gnd33" )
			)
			( pin "EU8F2.35"
				( objectStatus "@baseboard_fab2_lib.baseboard_fab2(sch_1):page101_i34:gnd_rgmii" )
			)
			( pin "EU8F2.10"
				( objectStatus "@baseboard_fab2_lib.baseboard_fab2(sch_1):page101_i34:gndcpu" )
			)
			( pin "EU8F2.18"
				( objectStatus "@baseboard_fab2_lib.baseboard_fab2(sch_1):page101_i34:gndref" )
			)
			( pin "EU8F2.27"
				( objectStatus "@baseboard_fab2_lib.baseboard_fab2(sch_1):page101_i34:gndrmii(0)" )
			)
			( pin "EU8F2.30"
				( objectStatus "@baseboard_fab2_lib.baseboard_fab2(sch_1):page101_i34:gndrmii(1)" )
			)
			( pin "EU8F2.11"
				( objectStatus "@baseboard_fab2_lib.baseboard_fab2(sch_1):page101_i34:iref" )
			)
			( pin "EU8F2.5"
				( objectStatus "@baseboard_fab2_lib.baseboard_fab2(sch_1):page101_i34:oe_96" )
			)
			( pin "EU8F2.6"
				( objectStatus "@baseboard_fab2_lib.baseboard_fab2(sch_1):page101_i34:oe_cpu" )
			)
			( pin "EU8F2.37"
				( objectStatus "@baseboard_fab2_lib.baseboard_fab2(sch_1):page101_i34:rgmii(0)" )
			)
			( pin "EU8F2.36"
				( objectStatus "@baseboard_fab2_lib.baseboard_fab2(sch_1):page101_i34:rgmii(1)" )
			)
			( pin "EU8F2.33"
				( objectStatus "@baseboard_fab2_lib.baseboard_fab2(sch_1):page101_i34:rmii(0)" )
			)
			( pin "EU8F2.32"
				( objectStatus "@baseboard_fab2_lib.baseboard_fab2(sch_1):page101_i34:rmii(1)" )
			)
			( pin "EU8F2.29"
				( objectStatus "@baseboard_fab2_lib.baseboard_fab2(sch_1):page101_i34:rmii(2)" )
			)
			( pin "EU8F2.28"
				( objectStatus "@baseboard_fab2_lib.baseboard_fab2(sch_1):page101_i34:rmii(3)" )
			)
			( pin "EU8F2.25"
				( objectStatus "@baseboard_fab2_lib.baseboard_fab2(sch_1):page101_i34:rmii(4)" )
			)
			( pin "EU8F2.24"
				( objectStatus "@baseboard_fab2_lib.baseboard_fab2(sch_1):page101_i34:rmii(5)" )
			)
			( pin "EU8F2.38"
				( objectStatus "@baseboard_fab2_lib.baseboard_fab2(sch_1):page101_i34:smbclk" )
			)
			( pin "EU8F2.39"
				( objectStatus "@baseboard_fab2_lib.baseboard_fab2(sch_1):page101_i34:smbdat" )
			)
			( pin "EU8F2.12"
				( objectStatus "@baseboard_fab2_lib.baseboard_fab2(sch_1):page101_i34:vdd32k" )
			)
			( pin "EU8F2.23"
				( objectStatus "@baseboard_fab2_lib.baseboard_fab2(sch_1):page101_i34:vdd33" )
			)
			( pin "EU8F2.2"
				( objectStatus "@baseboard_fab2_lib.baseboard_fab2(sch_1):page101_i34:vdd96" )
			)
			( pin "EU8F2.34"
				( objectStatus "@baseboard_fab2_lib.baseboard_fab2(sch_1):page101_i34:vdd_rgmii" )
			)
			( pin "EU8F2.9"
				( objectStatus "@baseboard_fab2_lib.baseboard_fab2(sch_1):page101_i34:vddcpu" )
			)
			( pin "EU8F2.15"
				( objectStatus "@baseboard_fab2_lib.baseboard_fab2(sch_1):page101_i34:vddref" )
			)
			( pin "EU8F2.26"
				( objectStatus "@baseboard_fab2_lib.baseboard_fab2(sch_1):page101_i34:vddrmii(0)" )
			)
			( pin "EU8F2.31"
				( objectStatus "@baseboard_fab2_lib.baseboard_fab2(sch_1):page101_i34:vddrmii(1)" )
			)
			( pin "EU8F2.40"
				( objectStatus "@baseboard_fab2_lib.baseboard_fab2(sch_1):page101_i34:vttpwr_gd_pd_n" )
			)
			( pin "EU8F2.19"
				( objectStatus "@baseboard_fab2_lib.baseboard_fab2(sch_1):page101_i34:x1_25" )
			)
			( pin "EU8F2.20"
				( objectStatus "@baseboard_fab2_lib.baseboard_fab2(sch_1):page101_i34:x2_25" )
			)
			( pin "R2T25.1"
				( objectStatus "@baseboard_fab2_lib.baseboard_fab2(sch_1):page101_i48:a" )
			)
			( pin "R2T25.2"
				( objectStatus "@baseboard_fab2_lib.baseboard_fab2(sch_1):page101_i48:b" )
			)
			( pin "C8F18.1"
				( objectStatus "@baseboard_fab2_lib.baseboard_fab2(sch_1):page101_i49:a" )
			)
			( pin "C8F18.2"
				( objectStatus "@baseboard_fab2_lib.baseboard_fab2(sch_1):page101_i49:b" )
			)
			( pin "Y8F1.1"
				( objectStatus "@baseboard_fab2_lib.baseboard_fab2(sch_1):page101_i52:a" )
			)
			( pin "Y8F1.3"
				( objectStatus "@baseboard_fab2_lib.baseboard_fab2(sch_1):page101_i52:b" )
			)
			( pin "C8F19.1"
				( objectStatus "@baseboard_fab2_lib.baseboard_fab2(sch_1):page101_i53:a" )
			)
			( pin "C8F19.2"
				( objectStatus "@baseboard_fab2_lib.baseboard_fab2(sch_1):page101_i53:b" )
			)
			( pin "C2T31.1"
				( objectStatus "@baseboard_fab2_lib.baseboard_fab2(sch_1):page101_i89:a" )
			)
			( pin "C2T31.2"
				( objectStatus "@baseboard_fab2_lib.baseboard_fab2(sch_1):page101_i89:b" )
			)
			( pin "C2T27.1"
				( objectStatus "@baseboard_fab2_lib.baseboard_fab2(sch_1):page101_i90:a" )
			)
			( pin "C2T27.2"
				( objectStatus "@baseboard_fab2_lib.baseboard_fab2(sch_1):page101_i90:b" )
			)
			( pin "R2T23.1"
				( objectStatus "@baseboard_fab2_lib.baseboard_fab2(sch_1):page101_i94:a" )
			)
			( pin "R2T23.2"
				( objectStatus "@baseboard_fab2_lib.baseboard_fab2(sch_1):page101_i94:b" )
			)
			( pin "R2T52.1"
				( objectStatus "@baseboard_fab2_lib.baseboard_fab2(sch_1):page101_i95:a" )
			)
			( pin "R2T52.2"
				( objectStatus "@baseboard_fab2_lib.baseboard_fab2(sch_1):page101_i95:b" )
			)
			( pin "C2T38.1"
				( objectStatus "@baseboard_fab2_lib.baseboard_fab2(sch_1):page101_i97:a" )
			)
			( pin "C2T38.2"
				( objectStatus "@baseboard_fab2_lib.baseboard_fab2(sch_1):page101_i97:b" )
			)
			( pin "C2T37.1"
				( objectStatus "@baseboard_fab2_lib.baseboard_fab2(sch_1):page101_i99:a" )
			)
			( pin "C2T37.2"
				( objectStatus "@baseboard_fab2_lib.baseboard_fab2(sch_1):page101_i99:b" )
			)
			( pin "C2T18.1"
				( objectStatus "@baseboard_fab2_lib.baseboard_fab2(sch_1):page101_i104:a" )
			)
			( pin "C2T18.2"
				( objectStatus "@baseboard_fab2_lib.baseboard_fab2(sch_1):page101_i104:b" )
			)
			( pin "R2T21.1"
				( objectStatus "@baseboard_fab2_lib.baseboard_fab2(sch_1):page101_i105:a" )
			)
			( pin "R2T21.2"
				( objectStatus "@baseboard_fab2_lib.baseboard_fab2(sch_1):page101_i105:b" )
			)
			( pin "C2T19.1"
				( objectStatus "@baseboard_fab2_lib.baseboard_fab2(sch_1):page101_i106:a" )
			)
			( pin "C2T19.2"
				( objectStatus "@baseboard_fab2_lib.baseboard_fab2(sch_1):page101_i106:b" )
			)
			( pin "C2T34.1"
				( objectStatus "@baseboard_fab2_lib.baseboard_fab2(sch_1):page101_i109:a" )
			)
			( pin "C2T34.2"
				( objectStatus "@baseboard_fab2_lib.baseboard_fab2(sch_1):page101_i109:b" )
			)
			( pin "C2T30.1"
				( objectStatus "@baseboard_fab2_lib.baseboard_fab2(sch_1):page101_i110:a" )
			)
			( pin "C2T30.2"
				( objectStatus "@baseboard_fab2_lib.baseboard_fab2(sch_1):page101_i110:b" )
			)
			( pin "C2T25.1"
				( objectStatus "@baseboard_fab2_lib.baseboard_fab2(sch_1):page101_i111:a" )
			)
			( pin "C2T25.2"
				( objectStatus "@baseboard_fab2_lib.baseboard_fab2(sch_1):page101_i111:b" )
			)
			( pin "C2T17.1"
				( objectStatus "@baseboard_fab2_lib.baseboard_fab2(sch_1):page101_i112:a" )
			)
			( pin "C2T17.2"
				( objectStatus "@baseboard_fab2_lib.baseboard_fab2(sch_1):page101_i112:b" )
			)
			( pin "C2T22.1"
				( objectStatus "@baseboard_fab2_lib.baseboard_fab2(sch_1):page101_i113:a" )
			)
			( pin "C2T22.2"
				( objectStatus "@baseboard_fab2_lib.baseboard_fab2(sch_1):page101_i113:b" )
			)
			( pin "FB2T2.1"
				( objectStatus "@baseboard_fab2_lib.baseboard_fab2(sch_1):page101_i114:a" )
			)
			( pin "FB2T2.2"
				( objectStatus "@baseboard_fab2_lib.baseboard_fab2(sch_1):page101_i114:b" )
			)
			( pin "C2T28.1"
				( objectStatus "@baseboard_fab2_lib.baseboard_fab2(sch_1):page101_i116:a" )
			)
			( pin "C2T28.2"
				( objectStatus "@baseboard_fab2_lib.baseboard_fab2(sch_1):page101_i116:b" )
			)
			( pin "R2T42.1"
				( objectStatus "@baseboard_fab2_lib.baseboard_fab2(sch_1):page101_i124:a" )
			)
			( pin "R2T42.2"
				( objectStatus "@baseboard_fab2_lib.baseboard_fab2(sch_1):page101_i124:b" )
			)
			( pin "R2T46.1"
				( objectStatus "@baseboard_fab2_lib.baseboard_fab2(sch_1):page101_i125:a" )
			)
			( pin "R2T46.2"
				( objectStatus "@baseboard_fab2_lib.baseboard_fab2(sch_1):page101_i125:b" )
			)
			( pin "R8F27.1"
				( objectStatus "@baseboard_fab2_lib.baseboard_fab2(sch_1):page101_i129:a" )
			)
			( pin "R8F27.2"
				( objectStatus "@baseboard_fab2_lib.baseboard_fab2(sch_1):page101_i129:b" )
			)
			( pin "R2T47.1"
				( objectStatus "@baseboard_fab2_lib.baseboard_fab2(sch_1):page101_i130:a" )
			)
			( pin "R2T47.2"
				( objectStatus "@baseboard_fab2_lib.baseboard_fab2(sch_1):page101_i130:b" )
			)
			( pin "R8G25.1"
				( objectStatus "@baseboard_fab2_lib.baseboard_fab2(sch_1):page101_i131:a" )
			)
			( pin "R8G25.2"
				( objectStatus "@baseboard_fab2_lib.baseboard_fab2(sch_1):page101_i131:b" )
			)
			( pin "R8G24.1"
				( objectStatus "@baseboard_fab2_lib.baseboard_fab2(sch_1):page101_i132:a" )
			)
			( pin "R8G24.2"
				( objectStatus "@baseboard_fab2_lib.baseboard_fab2(sch_1):page101_i132:b" )
			)
			( pin "R8G1.1"
				( objectStatus "@baseboard_fab2_lib.baseboard_fab2(sch_1):page101_i133:a" )
			)
			( pin "R8G1.2"
				( objectStatus "@baseboard_fab2_lib.baseboard_fab2(sch_1):page101_i133:b" )
			)
			( pin "EU4D2.4"
				( objectStatus "@baseboard_fab2_lib.baseboard_fab2(sch_1):page102_i1:\100m_133m_n\" )
			)
			( pin "EU4D2.10"
				( objectStatus "@baseboard_fab2_lib.baseboard_fab2(sch_1):page102_i1:clk_inn" )
			)
			( pin "EU4D2.9"
				( objectStatus "@baseboard_fab2_lib.baseboard_fab2(sch_1):page102_i1:clk_inp" )
			)
			( pin "EU4D2.18"
				( objectStatus "@baseboard_fab2_lib.baseboard_fab2(sch_1):page102_i1:dif_0n" )
			)
			( pin "EU4D2.17"
				( objectStatus "@baseboard_fab2_lib.baseboard_fab2(sch_1):page102_i1:dif_0p" )
			)
			( pin "EU4D2.22"
				( objectStatus "@baseboard_fab2_lib.baseboard_fab2(sch_1):page102_i1:dif_1n" )
			)
			( pin "EU4D2.21"
				( objectStatus "@baseboard_fab2_lib.baseboard_fab2(sch_1):page102_i1:dif_1p" )
			)
			( pin "EU4D2.27"
				( objectStatus "@baseboard_fab2_lib.baseboard_fab2(sch_1):page102_i1:dif_2n" )
			)
			( pin "EU4D2.26"
				( objectStatus "@baseboard_fab2_lib.baseboard_fab2(sch_1):page102_i1:dif_2p" )
			)
			( pin "EU4D2.31"
				( objectStatus "@baseboard_fab2_lib.baseboard_fab2(sch_1):page102_i1:dif_3n" )
			)
			( pin "EU4D2.30"
				( objectStatus "@baseboard_fab2_lib.baseboard_fab2(sch_1):page102_i1:dif_3p" )
			)
			( pin "EU4D2.35"
				( objectStatus "@baseboard_fab2_lib.baseboard_fab2(sch_1):page102_i1:dif_4n" )
			)
			( pin "EU4D2.34"
				( objectStatus "@baseboard_fab2_lib.baseboard_fab2(sch_1):page102_i1:dif_4p" )
			)
			( pin "EU4D2.39"
				( objectStatus "@baseboard_fab2_lib.baseboard_fab2(sch_1):page102_i1:dif_5n" )
			)
			( pin "EU4D2.38"
				( objectStatus "@baseboard_fab2_lib.baseboard_fab2(sch_1):page102_i1:dif_5p" )
			)
			( pin "EU4D2.43"
				( objectStatus "@baseboard_fab2_lib.baseboard_fab2(sch_1):page102_i1:dif_6n" )
			)
			( pin "EU4D2.42"
				( objectStatus "@baseboard_fab2_lib.baseboard_fab2(sch_1):page102_i1:dif_6p" )
			)
			( pin "EU4D2.47"
				( objectStatus "@baseboard_fab2_lib.baseboard_fab2(sch_1):page102_i1:dif_7n" )
			)
			( pin "EU4D2.46"
				( objectStatus "@baseboard_fab2_lib.baseboard_fab2(sch_1):page102_i1:dif_7p" )
			)
			( pin "EU4D2.51"
				( objectStatus "@baseboard_fab2_lib.baseboard_fab2(sch_1):page102_i1:dif_8n" )
			)
			( pin "EU4D2.50"
				( objectStatus "@baseboard_fab2_lib.baseboard_fab2(sch_1):page102_i1:dif_8p" )
			)
			( pin "EU4D2.55"
				( objectStatus "@baseboard_fab2_lib.baseboard_fab2(sch_1):page102_i1:dif_9n" )
			)
			( pin "EU4D2.54"
				( objectStatus "@baseboard_fab2_lib.baseboard_fab2(sch_1):page102_i1:dif_9p" )
			)
			( pin "EU4D2.60"
				( objectStatus "@baseboard_fab2_lib.baseboard_fab2(sch_1):page102_i1:dif_10n" )
			)
			( pin "EU4D2.59"
				( objectStatus "@baseboard_fab2_lib.baseboard_fab2(sch_1):page102_i1:dif_10p" )
			)
			( pin "EU4D2.64"
				( objectStatus "@baseboard_fab2_lib.baseboard_fab2(sch_1):page102_i1:dif_11n" )
			)
			( pin "EU4D2.63"
				( objectStatus "@baseboard_fab2_lib.baseboard_fab2(sch_1):page102_i1:dif_11p" )
			)
			( pin "EU4D2.7"
				( objectStatus "@baseboard_fab2_lib.baseboard_fab2(sch_1):page102_i1:gnd(0)" )
			)
			( pin "EU4D2.23"
				( objectStatus "@baseboard_fab2_lib.baseboard_fab2(sch_1):page102_i1:gnd(1)" )
			)
			( pin "EU4D2.33"
				( objectStatus "@baseboard_fab2_lib.baseboard_fab2(sch_1):page102_i1:gnd(2)" )
			)
			( pin "EU4D2.41"
				( objectStatus "@baseboard_fab2_lib.baseboard_fab2(sch_1):page102_i1:gnd(3)" )
			)
			( pin "EU4D2.48"
				( objectStatus "@baseboard_fab2_lib.baseboard_fab2(sch_1):page102_i1:gnd(4)" )
			)
			( pin "EU4D2.58"
				( objectStatus "@baseboard_fab2_lib.baseboard_fab2(sch_1):page102_i1:gnd(5)" )
			)
			( pin "EU4D2.2"
				( objectStatus "@baseboard_fab2_lib.baseboard_fab2(sch_1):page102_i1:gnda" )
			)
			( pin "EU4D2.5"
				( objectStatus "@baseboard_fab2_lib.baseboard_fab2(sch_1):page102_i1:hbw_bypass_lobw_n" )
			)
			( pin "EU4D2.3"
				( objectStatus "@baseboard_fab2_lib.baseboard_fab2(sch_1):page102_i1:nc(0)" )
			)
			( pin "EU4D2.16"
				( objectStatus "@baseboard_fab2_lib.baseboard_fab2(sch_1):page102_i1:nc(1)" )
			)
			( pin "EU4D2.15"
				( objectStatus "@baseboard_fab2_lib.baseboard_fab2(sch_1):page102_i1:nc(2)" )
			)
			( pin "EU4D2.19"
				( objectStatus "@baseboard_fab2_lib.baseboard_fab2(sch_1):page102_i1:oe_0_n" )
			)
			( pin "EU4D2.20"
				( objectStatus "@baseboard_fab2_lib.baseboard_fab2(sch_1):page102_i1:oe_1_n" )
			)
			( pin "EU4D2.28"
				( objectStatus "@baseboard_fab2_lib.baseboard_fab2(sch_1):page102_i1:oe_2_n" )
			)
			( pin "EU4D2.29"
				( objectStatus "@baseboard_fab2_lib.baseboard_fab2(sch_1):page102_i1:oe_3_n" )
			)
			( pin "EU4D2.36"
				( objectStatus "@baseboard_fab2_lib.baseboard_fab2(sch_1):page102_i1:oe_4_n" )
			)
			( pin "EU4D2.37"
				( objectStatus "@baseboard_fab2_lib.baseboard_fab2(sch_1):page102_i1:oe_5_n" )
			)
			( pin "EU4D2.44"
				( objectStatus "@baseboard_fab2_lib.baseboard_fab2(sch_1):page102_i1:oe_6_n" )
			)
			( pin "EU4D2.45"
				( objectStatus "@baseboard_fab2_lib.baseboard_fab2(sch_1):page102_i1:oe_7_n" )
			)
			( pin "EU4D2.52"
				( objectStatus "@baseboard_fab2_lib.baseboard_fab2(sch_1):page102_i1:oe_8_n" )
			)
			( pin "EU4D2.53"
				( objectStatus "@baseboard_fab2_lib.baseboard_fab2(sch_1):page102_i1:oe_9_n" )
			)
			( pin "EU4D2.61"
				( objectStatus "@baseboard_fab2_lib.baseboard_fab2(sch_1):page102_i1:oe_10_n" )
			)
			( pin "EU4D2.62"
				( objectStatus "@baseboard_fab2_lib.baseboard_fab2(sch_1):page102_i1:oe_11_n" )
			)
			( pin "EU4D2.6"
				( objectStatus "@baseboard_fab2_lib.baseboard_fab2(sch_1):page102_i1:pwrgd_pwrdn_n" )
			)
			( pin "EU4D2.11"
				( objectStatus "@baseboard_fab2_lib.baseboard_fab2(sch_1):page102_i1:sa_0" )
			)
			( pin "EU4D2.14"
				( objectStatus "@baseboard_fab2_lib.baseboard_fab2(sch_1):page102_i1:sa_1" )
			)
			( pin "EU4D2.13"
				( objectStatus "@baseboard_fab2_lib.baseboard_fab2(sch_1):page102_i1:scl" )
			)
			( pin "EU4D2.12"
				( objectStatus "@baseboard_fab2_lib.baseboard_fab2(sch_1):page102_i1:sda" )
			)
			( pin "EU4D2.65"
				( objectStatus "@baseboard_fab2_lib.baseboard_fab2(sch_1):page102_i1:thpad" )
			)
			( pin "EU4D2.24"
				( objectStatus "@baseboard_fab2_lib.baseboard_fab2(sch_1):page102_i1:vdd(0)" )
			)
			( pin "EU4D2.40"
				( objectStatus "@baseboard_fab2_lib.baseboard_fab2(sch_1):page102_i1:vdd(1)" )
			)
			( pin "EU4D2.57"
				( objectStatus "@baseboard_fab2_lib.baseboard_fab2(sch_1):page102_i1:vdd(2)" )
			)
			( pin "EU4D2.1"
				( objectStatus "@baseboard_fab2_lib.baseboard_fab2(sch_1):page102_i1:vdda" )
			)
			( pin "EU4D2.25"
				( objectStatus "@baseboard_fab2_lib.baseboard_fab2(sch_1):page102_i1:vddio(0)" )
			)
			( pin "EU4D2.32"
				( objectStatus "@baseboard_fab2_lib.baseboard_fab2(sch_1):page102_i1:vddio(1)" )
			)
			( pin "EU4D2.49"
				( objectStatus "@baseboard_fab2_lib.baseboard_fab2(sch_1):page102_i1:vddio(2)" )
			)
			( pin "EU4D2.56"
				( objectStatus "@baseboard_fab2_lib.baseboard_fab2(sch_1):page102_i1:vddio(3)" )
			)
			( pin "EU4D2.8"
				( objectStatus "@baseboard_fab2_lib.baseboard_fab2(sch_1):page102_i1:vddr" )
			)
			( pin "FB6P1.1"
				( objectStatus "@baseboard_fab2_lib.baseboard_fab2(sch_1):page102_i8:a" )
			)
			( pin "FB6P1.2"
				( objectStatus "@baseboard_fab2_lib.baseboard_fab2(sch_1):page102_i8:b" )
			)
			( pin "C3D22.1"
				( objectStatus "@baseboard_fab2_lib.baseboard_fab2(sch_1):page102_i10:a" )
			)
			( pin "C3D22.2"
				( objectStatus "@baseboard_fab2_lib.baseboard_fab2(sch_1):page102_i10:b" )
			)
			( pin "C6P4.1"
				( objectStatus "@baseboard_fab2_lib.baseboard_fab2(sch_1):page102_i11:a" )
			)
			( pin "C6P4.2"
				( objectStatus "@baseboard_fab2_lib.baseboard_fab2(sch_1):page102_i11:b" )
			)
			( pin "C6P6.1"
				( objectStatus "@baseboard_fab2_lib.baseboard_fab2(sch_1):page102_i12:a" )
			)
			( pin "C6P6.2"
				( objectStatus "@baseboard_fab2_lib.baseboard_fab2(sch_1):page102_i12:b" )
			)
			( pin "C6P10.1"
				( objectStatus "@baseboard_fab2_lib.baseboard_fab2(sch_1):page102_i13:a" )
			)
			( pin "C6P10.2"
				( objectStatus "@baseboard_fab2_lib.baseboard_fab2(sch_1):page102_i13:b" )
			)
			( pin "C6P5.1"
				( objectStatus "@baseboard_fab2_lib.baseboard_fab2(sch_1):page102_i14:a" )
			)
			( pin "C6P5.2"
				( objectStatus "@baseboard_fab2_lib.baseboard_fab2(sch_1):page102_i14:b" )
			)
			( pin "C6P12.1"
				( objectStatus "@baseboard_fab2_lib.baseboard_fab2(sch_1):page102_i15:a" )
			)
			( pin "C6P12.2"
				( objectStatus "@baseboard_fab2_lib.baseboard_fab2(sch_1):page102_i15:b" )
			)
			( pin "C6P11.1"
				( objectStatus "@baseboard_fab2_lib.baseboard_fab2(sch_1):page102_i16:a" )
			)
			( pin "C6P11.2"
				( objectStatus "@baseboard_fab2_lib.baseboard_fab2(sch_1):page102_i16:b" )
			)
			( pin "C4D24.1"
				( objectStatus "@baseboard_fab2_lib.baseboard_fab2(sch_1):page102_i18:a" )
			)
			( pin "C4D24.2"
				( objectStatus "@baseboard_fab2_lib.baseboard_fab2(sch_1):page102_i18:b" )
			)
			( pin "C4D23.1"
				( objectStatus "@baseboard_fab2_lib.baseboard_fab2(sch_1):page102_i19:a" )
			)
			( pin "C4D23.2"
				( objectStatus "@baseboard_fab2_lib.baseboard_fab2(sch_1):page102_i19:b" )
			)
			( pin "R3D14.1"
				( objectStatus "@baseboard_fab2_lib.baseboard_fab2(sch_1):page102_i21:a" )
			)
			( pin "R3D14.2"
				( objectStatus "@baseboard_fab2_lib.baseboard_fab2(sch_1):page102_i21:b" )
			)
			( pin "R6P25.1"
				( objectStatus "@baseboard_fab2_lib.baseboard_fab2(sch_1):page102_i26:a" )
			)
			( pin "R6P25.2"
				( objectStatus "@baseboard_fab2_lib.baseboard_fab2(sch_1):page102_i26:b" )
			)
			( pin "C4D22.1"
				( objectStatus "@baseboard_fab2_lib.baseboard_fab2(sch_1):page102_i28:a" )
			)
			( pin "C4D22.2"
				( objectStatus "@baseboard_fab2_lib.baseboard_fab2(sch_1):page102_i28:b" )
			)
			( pin "C4D27.1"
				( objectStatus "@baseboard_fab2_lib.baseboard_fab2(sch_1):page102_i30:a" )
			)
			( pin "C4D27.2"
				( objectStatus "@baseboard_fab2_lib.baseboard_fab2(sch_1):page102_i30:b" )
			)
			( pin "R4D38.1"
				( objectStatus "@baseboard_fab2_lib.baseboard_fab2(sch_1):page102_i37:a" )
			)
			( pin "R4D38.2"
				( objectStatus "@baseboard_fab2_lib.baseboard_fab2(sch_1):page102_i37:b" )
			)
			( pin "R4D35.1"
				( objectStatus "@baseboard_fab2_lib.baseboard_fab2(sch_1):page102_i38:a" )
			)
			( pin "R4D35.2"
				( objectStatus "@baseboard_fab2_lib.baseboard_fab2(sch_1):page102_i38:b" )
			)
			( pin "R4D40.1"
				( objectStatus "@baseboard_fab2_lib.baseboard_fab2(sch_1):page102_i45:a" )
			)
			( pin "R4D40.2"
				( objectStatus "@baseboard_fab2_lib.baseboard_fab2(sch_1):page102_i45:b" )
			)
			( pin "R6P23.1"
				( objectStatus "@baseboard_fab2_lib.baseboard_fab2(sch_1):page102_i46:a" )
			)
			( pin "R6P23.2"
				( objectStatus "@baseboard_fab2_lib.baseboard_fab2(sch_1):page102_i46:b" )
			)
			( pin "R6P22.1"
				( objectStatus "@baseboard_fab2_lib.baseboard_fab2(sch_1):page102_i47:a" )
			)
			( pin "R6P22.2"
				( objectStatus "@baseboard_fab2_lib.baseboard_fab2(sch_1):page102_i47:b" )
			)
			( pin "R4D41.1"
				( objectStatus "@baseboard_fab2_lib.baseboard_fab2(sch_1):page102_i53:a" )
			)
			( pin "R4D41.2"
				( objectStatus "@baseboard_fab2_lib.baseboard_fab2(sch_1):page102_i53:b" )
			)
			( pin "C6P9.1"
				( objectStatus "@baseboard_fab2_lib.baseboard_fab2(sch_1):page102_i79:a" )
			)
			( pin "C6P9.2"
				( objectStatus "@baseboard_fab2_lib.baseboard_fab2(sch_1):page102_i79:b" )
			)
			( pin "R6P21.1"
				( objectStatus "@baseboard_fab2_lib.baseboard_fab2(sch_1):page102_i80:a" )
			)
			( pin "R6P21.2"
				( objectStatus "@baseboard_fab2_lib.baseboard_fab2(sch_1):page102_i80:b" )
			)
			( pin "R6P20.1"
				( objectStatus "@baseboard_fab2_lib.baseboard_fab2(sch_1):page102_i81:a" )
			)
			( pin "R6P20.2"
				( objectStatus "@baseboard_fab2_lib.baseboard_fab2(sch_1):page102_i81:b" )
			)
			( pin "R4D36.1"
				( objectStatus "@baseboard_fab2_lib.baseboard_fab2(sch_1):page102_i82:a" )
			)
			( pin "R4D36.2"
				( objectStatus "@baseboard_fab2_lib.baseboard_fab2(sch_1):page102_i82:b" )
			)
			( pin "R4D37.1"
				( objectStatus "@baseboard_fab2_lib.baseboard_fab2(sch_1):page102_i87:a" )
			)
			( pin "R4D37.2"
				( objectStatus "@baseboard_fab2_lib.baseboard_fab2(sch_1):page102_i87:b" )
			)
			( pin "R6P48.1"
				( objectStatus "@baseboard_fab2_lib.baseboard_fab2(sch_1):page102_i91:a" )
			)
			( pin "R6P48.2"
				( objectStatus "@baseboard_fab2_lib.baseboard_fab2(sch_1):page102_i91:b" )
			)
			( pin "R4D69.1"
				( objectStatus "@baseboard_fab2_lib.baseboard_fab2(sch_1):page102_i93:a" )
			)
			( pin "R4D69.2"
				( objectStatus "@baseboard_fab2_lib.baseboard_fab2(sch_1):page102_i93:b" )
			)
			( pin "R4D70.1"
				( objectStatus "@baseboard_fab2_lib.baseboard_fab2(sch_1):page102_i94:a" )
			)
			( pin "R4D70.2"
				( objectStatus "@baseboard_fab2_lib.baseboard_fab2(sch_1):page102_i94:b" )
			)
			( pin "R4D25.1"
				( objectStatus "@baseboard_fab2_lib.baseboard_fab2(sch_1):page103_i1:a" )
			)
			( pin "R4D25.2"
				( objectStatus "@baseboard_fab2_lib.baseboard_fab2(sch_1):page103_i1:b" )
			)
			( pin "R4D23.1"
				( objectStatus "@baseboard_fab2_lib.baseboard_fab2(sch_1):page103_i9:a" )
			)
			( pin "R4D23.2"
				( objectStatus "@baseboard_fab2_lib.baseboard_fab2(sch_1):page103_i9:b" )
			)
			( pin "R4D28.1"
				( objectStatus "@baseboard_fab2_lib.baseboard_fab2(sch_1):page103_i14:a" )
			)
			( pin "R4D28.2"
				( objectStatus "@baseboard_fab2_lib.baseboard_fab2(sch_1):page103_i14:b" )
			)
			( pin "R4D19.1"
				( objectStatus "@baseboard_fab2_lib.baseboard_fab2(sch_1):page103_i19:a" )
			)
			( pin "R4D19.2"
				( objectStatus "@baseboard_fab2_lib.baseboard_fab2(sch_1):page103_i19:b" )
			)
			( pin "R4D21.1"
				( objectStatus "@baseboard_fab2_lib.baseboard_fab2(sch_1):page103_i24:a" )
			)
			( pin "R4D21.2"
				( objectStatus "@baseboard_fab2_lib.baseboard_fab2(sch_1):page103_i24:b" )
			)
			( pin "R4D13.1"
				( objectStatus "@baseboard_fab2_lib.baseboard_fab2(sch_1):page103_i29:a" )
			)
			( pin "R4D13.2"
				( objectStatus "@baseboard_fab2_lib.baseboard_fab2(sch_1):page103_i29:b" )
			)
			( pin "R4D16.1"
				( objectStatus "@baseboard_fab2_lib.baseboard_fab2(sch_1):page103_i34:a" )
			)
			( pin "R4D16.2"
				( objectStatus "@baseboard_fab2_lib.baseboard_fab2(sch_1):page103_i34:b" )
			)
			( pin "R4D9.1"
				( objectStatus "@baseboard_fab2_lib.baseboard_fab2(sch_1):page103_i39:a" )
			)
			( pin "R4D9.2"
				( objectStatus "@baseboard_fab2_lib.baseboard_fab2(sch_1):page103_i39:b" )
			)
			( pin "R4D11.1"
				( objectStatus "@baseboard_fab2_lib.baseboard_fab2(sch_1):page103_i44:a" )
			)
			( pin "R4D11.2"
				( objectStatus "@baseboard_fab2_lib.baseboard_fab2(sch_1):page103_i44:b" )
			)
			( pin "R4D2.1"
				( objectStatus "@baseboard_fab2_lib.baseboard_fab2(sch_1):page103_i49:a" )
			)
			( pin "R4D2.2"
				( objectStatus "@baseboard_fab2_lib.baseboard_fab2(sch_1):page103_i49:b" )
			)
			( pin "R4D1.1"
				( objectStatus "@baseboard_fab2_lib.baseboard_fab2(sch_1):page103_i54:a" )
			)
			( pin "R4D1.2"
				( objectStatus "@baseboard_fab2_lib.baseboard_fab2(sch_1):page103_i54:b" )
			)
			( pin "R4D4.1"
				( objectStatus "@baseboard_fab2_lib.baseboard_fab2(sch_1):page103_i59:a" )
			)
			( pin "R4D4.2"
				( objectStatus "@baseboard_fab2_lib.baseboard_fab2(sch_1):page103_i59:b" )
			)
			( pin "R4D3.1"
				( objectStatus "@baseboard_fab2_lib.baseboard_fab2(sch_1):page103_i64:a" )
			)
			( pin "R4D3.2"
				( objectStatus "@baseboard_fab2_lib.baseboard_fab2(sch_1):page103_i64:b" )
			)
			( pin "R4D29.1"
				( objectStatus "@baseboard_fab2_lib.baseboard_fab2(sch_1):page103_i69:a" )
			)
			( pin "R4D29.2"
				( objectStatus "@baseboard_fab2_lib.baseboard_fab2(sch_1):page103_i69:b" )
			)
			( pin "R4D6.1"
				( objectStatus "@baseboard_fab2_lib.baseboard_fab2(sch_1):page103_i74:a" )
			)
			( pin "R4D6.2"
				( objectStatus "@baseboard_fab2_lib.baseboard_fab2(sch_1):page103_i74:b" )
			)
			( pin "R4D5.1"
				( objectStatus "@baseboard_fab2_lib.baseboard_fab2(sch_1):page103_i79:a" )
			)
			( pin "R4D5.2"
				( objectStatus "@baseboard_fab2_lib.baseboard_fab2(sch_1):page103_i79:b" )
			)
			( pin "R4D8.1"
				( objectStatus "@baseboard_fab2_lib.baseboard_fab2(sch_1):page103_i84:a" )
			)
			( pin "R4D8.2"
				( objectStatus "@baseboard_fab2_lib.baseboard_fab2(sch_1):page103_i84:b" )
			)
			( pin "R4D7.1"
				( objectStatus "@baseboard_fab2_lib.baseboard_fab2(sch_1):page103_i89:a" )
			)
			( pin "R4D7.2"
				( objectStatus "@baseboard_fab2_lib.baseboard_fab2(sch_1):page103_i89:b" )
			)
			( pin "R4D12.1"
				( objectStatus "@baseboard_fab2_lib.baseboard_fab2(sch_1):page103_i94:a" )
			)
			( pin "R4D12.2"
				( objectStatus "@baseboard_fab2_lib.baseboard_fab2(sch_1):page103_i94:b" )
			)
			( pin "R4D10.1"
				( objectStatus "@baseboard_fab2_lib.baseboard_fab2(sch_1):page103_i99:a" )
			)
			( pin "R4D10.2"
				( objectStatus "@baseboard_fab2_lib.baseboard_fab2(sch_1):page103_i99:b" )
			)
			( pin "R4D17.1"
				( objectStatus "@baseboard_fab2_lib.baseboard_fab2(sch_1):page103_i104:a" )
			)
			( pin "R4D17.2"
				( objectStatus "@baseboard_fab2_lib.baseboard_fab2(sch_1):page103_i104:b" )
			)
			( pin "R4D14.1"
				( objectStatus "@baseboard_fab2_lib.baseboard_fab2(sch_1):page103_i109:a" )
			)
			( pin "R4D14.2"
				( objectStatus "@baseboard_fab2_lib.baseboard_fab2(sch_1):page103_i109:b" )
			)
			( pin "R4D22.1"
				( objectStatus "@baseboard_fab2_lib.baseboard_fab2(sch_1):page103_i114:a" )
			)
			( pin "R4D22.2"
				( objectStatus "@baseboard_fab2_lib.baseboard_fab2(sch_1):page103_i114:b" )
			)
			( pin "R4D20.1"
				( objectStatus "@baseboard_fab2_lib.baseboard_fab2(sch_1):page103_i119:a" )
			)
			( pin "R4D20.2"
				( objectStatus "@baseboard_fab2_lib.baseboard_fab2(sch_1):page103_i119:b" )
			)
			( pin "R7P9.1"
				( objectStatus "@baseboard_fab2_lib.baseboard_fab2(sch_1):page103_i121:a" )
			)
			( pin "R7P9.2"
				( objectStatus "@baseboard_fab2_lib.baseboard_fab2(sch_1):page103_i121:b" )
			)
			( pin "R7P12.1"
				( objectStatus "@baseboard_fab2_lib.baseboard_fab2(sch_1):page103_i123:a" )
			)
			( pin "R7P12.2"
				( objectStatus "@baseboard_fab2_lib.baseboard_fab2(sch_1):page103_i123:b" )
			)
			( pin "R7P6.1"
				( objectStatus "@baseboard_fab2_lib.baseboard_fab2(sch_1):page103_i125:a" )
			)
			( pin "R7P6.2"
				( objectStatus "@baseboard_fab2_lib.baseboard_fab2(sch_1):page103_i125:b" )
			)
			( pin "R7P7.1"
				( objectStatus "@baseboard_fab2_lib.baseboard_fab2(sch_1):page103_i127:a" )
			)
			( pin "R7P7.2"
				( objectStatus "@baseboard_fab2_lib.baseboard_fab2(sch_1):page103_i127:b" )
			)
			( pin "R7P3.1"
				( objectStatus "@baseboard_fab2_lib.baseboard_fab2(sch_1):page103_i129:a" )
			)
			( pin "R7P3.2"
				( objectStatus "@baseboard_fab2_lib.baseboard_fab2(sch_1):page103_i129:b" )
			)
			( pin "R7P4.1"
				( objectStatus "@baseboard_fab2_lib.baseboard_fab2(sch_1):page103_i131:a" )
			)
			( pin "R7P4.2"
				( objectStatus "@baseboard_fab2_lib.baseboard_fab2(sch_1):page103_i131:b" )
			)
			( pin "R7P1.1"
				( objectStatus "@baseboard_fab2_lib.baseboard_fab2(sch_1):page103_i133:a" )
			)
			( pin "R7P1.2"
				( objectStatus "@baseboard_fab2_lib.baseboard_fab2(sch_1):page103_i133:b" )
			)
			( pin "R7P2.1"
				( objectStatus "@baseboard_fab2_lib.baseboard_fab2(sch_1):page103_i135:a" )
			)
			( pin "R7P2.2"
				( objectStatus "@baseboard_fab2_lib.baseboard_fab2(sch_1):page103_i135:b" )
			)
			( pin "R6P7.1"
				( objectStatus "@baseboard_fab2_lib.baseboard_fab2(sch_1):page103_i137:a" )
			)
			( pin "R6P7.2"
				( objectStatus "@baseboard_fab2_lib.baseboard_fab2(sch_1):page103_i137:b" )
			)
			( pin "R6P8.1"
				( objectStatus "@baseboard_fab2_lib.baseboard_fab2(sch_1):page103_i139:a" )
			)
			( pin "R6P8.2"
				( objectStatus "@baseboard_fab2_lib.baseboard_fab2(sch_1):page103_i139:b" )
			)
			( pin "R6P5.1"
				( objectStatus "@baseboard_fab2_lib.baseboard_fab2(sch_1):page103_i141:a" )
			)
			( pin "R6P5.2"
				( objectStatus "@baseboard_fab2_lib.baseboard_fab2(sch_1):page103_i141:b" )
			)
			( pin "R6P6.1"
				( objectStatus "@baseboard_fab2_lib.baseboard_fab2(sch_1):page103_i143:a" )
			)
			( pin "R6P6.2"
				( objectStatus "@baseboard_fab2_lib.baseboard_fab2(sch_1):page103_i143:b" )
			)
			( pin "R6P3.1"
				( objectStatus "@baseboard_fab2_lib.baseboard_fab2(sch_1):page103_i145:a" )
			)
			( pin "R6P3.2"
				( objectStatus "@baseboard_fab2_lib.baseboard_fab2(sch_1):page103_i145:b" )
			)
			( pin "R6P4.1"
				( objectStatus "@baseboard_fab2_lib.baseboard_fab2(sch_1):page103_i147:a" )
			)
			( pin "R6P4.2"
				( objectStatus "@baseboard_fab2_lib.baseboard_fab2(sch_1):page103_i147:b" )
			)
			( pin "R6P1.1"
				( objectStatus "@baseboard_fab2_lib.baseboard_fab2(sch_1):page103_i149:a" )
			)
			( pin "R6P1.2"
				( objectStatus "@baseboard_fab2_lib.baseboard_fab2(sch_1):page103_i149:b" )
			)
			( pin "R6P2.1"
				( objectStatus "@baseboard_fab2_lib.baseboard_fab2(sch_1):page103_i151:a" )
			)
			( pin "R6P2.2"
				( objectStatus "@baseboard_fab2_lib.baseboard_fab2(sch_1):page103_i151:b" )
			)
			( pin "R6P11.1"
				( objectStatus "@baseboard_fab2_lib.baseboard_fab2(sch_1):page103_i153:a" )
			)
			( pin "R6P11.2"
				( objectStatus "@baseboard_fab2_lib.baseboard_fab2(sch_1):page103_i153:b" )
			)
			( pin "R6P9.1"
				( objectStatus "@baseboard_fab2_lib.baseboard_fab2(sch_1):page103_i155:a" )
			)
			( pin "R6P9.2"
				( objectStatus "@baseboard_fab2_lib.baseboard_fab2(sch_1):page103_i155:b" )
			)
			( pin "R6P13.1"
				( objectStatus "@baseboard_fab2_lib.baseboard_fab2(sch_1):page103_i157:a" )
			)
			( pin "R6P13.2"
				( objectStatus "@baseboard_fab2_lib.baseboard_fab2(sch_1):page103_i157:b" )
			)
			( pin "R6P12.1"
				( objectStatus "@baseboard_fab2_lib.baseboard_fab2(sch_1):page103_i159:a" )
			)
			( pin "R6P12.2"
				( objectStatus "@baseboard_fab2_lib.baseboard_fab2(sch_1):page103_i159:b" )
			)
			( pin "R4D24.1"
				( objectStatus "@baseboard_fab2_lib.baseboard_fab2(sch_1):page103_i161:a" )
			)
			( pin "R4D24.2"
				( objectStatus "@baseboard_fab2_lib.baseboard_fab2(sch_1):page103_i161:b" )
			)
			( pin "R4D18.1"
				( objectStatus "@baseboard_fab2_lib.baseboard_fab2(sch_1):page103_i163:a" )
			)
			( pin "R4D18.2"
				( objectStatus "@baseboard_fab2_lib.baseboard_fab2(sch_1):page103_i163:b" )
			)
			( pin "R6P17.1"
				( objectStatus "@baseboard_fab2_lib.baseboard_fab2(sch_1):page103_i165:a" )
			)
			( pin "R6P17.2"
				( objectStatus "@baseboard_fab2_lib.baseboard_fab2(sch_1):page103_i165:b" )
			)
			( pin "R6P15.1"
				( objectStatus "@baseboard_fab2_lib.baseboard_fab2(sch_1):page103_i167:a" )
			)
			( pin "R6P15.2"
				( objectStatus "@baseboard_fab2_lib.baseboard_fab2(sch_1):page103_i167:b" )
			)
			( pin "C6F1.1"
				( objectStatus "@baseboard_fab2_lib.baseboard_fab2(sch_1):page104_i25:a" )
			)
			( pin "C6F1.2"
				( objectStatus "@baseboard_fab2_lib.baseboard_fab2(sch_1):page104_i25:b" )
			)
			( pin "C3F2.1"
				( objectStatus "@baseboard_fab2_lib.baseboard_fab2(sch_1):page104_i34:a" )
			)
			( pin "C3F2.2"
				( objectStatus "@baseboard_fab2_lib.baseboard_fab2(sch_1):page104_i34:b" )
			)
			( pin "R6F8.1"
				( objectStatus "@baseboard_fab2_lib.baseboard_fab2(sch_1):page104_i37:a" )
			)
			( pin "R6F8.2"
				( objectStatus "@baseboard_fab2_lib.baseboard_fab2(sch_1):page104_i37:b" )
			)
			( pin "R6F6.1"
				( objectStatus "@baseboard_fab2_lib.baseboard_fab2(sch_1):page104_i41:a" )
			)
			( pin "R6F6.2"
				( objectStatus "@baseboard_fab2_lib.baseboard_fab2(sch_1):page104_i41:b" )
			)
			( pin "R3F1.1"
				( objectStatus "@baseboard_fab2_lib.baseboard_fab2(sch_1):page104_i51:a" )
			)
			( pin "R3F1.2"
				( objectStatus "@baseboard_fab2_lib.baseboard_fab2(sch_1):page104_i51:b" )
			)
			( pin "R3F3.1"
				( objectStatus "@baseboard_fab2_lib.baseboard_fab2(sch_1):page104_i53:a" )
			)
			( pin "R3F3.2"
				( objectStatus "@baseboard_fab2_lib.baseboard_fab2(sch_1):page104_i53:b" )
			)
			( pin "R6F7.1"
				( objectStatus "@baseboard_fab2_lib.baseboard_fab2(sch_1):page104_i67:a" )
			)
			( pin "R6F7.2"
				( objectStatus "@baseboard_fab2_lib.baseboard_fab2(sch_1):page104_i67:b" )
			)
			( pin "R6F9.1"
				( objectStatus "@baseboard_fab2_lib.baseboard_fab2(sch_1):page104_i68:a" )
			)
			( pin "R6F9.2"
				( objectStatus "@baseboard_fab2_lib.baseboard_fab2(sch_1):page104_i68:b" )
			)
			( pin "R3F2.1"
				( objectStatus "@baseboard_fab2_lib.baseboard_fab2(sch_1):page104_i69:a" )
			)
			( pin "R3F2.2"
				( objectStatus "@baseboard_fab2_lib.baseboard_fab2(sch_1):page104_i69:b" )
			)
			( pin "R3F4.1"
				( objectStatus "@baseboard_fab2_lib.baseboard_fab2(sch_1):page104_i70:a" )
			)
			( pin "R3F4.2"
				( objectStatus "@baseboard_fab2_lib.baseboard_fab2(sch_1):page104_i70:b" )
			)
			( pin "Y6F1.1"
				( objectStatus "@baseboard_fab2_lib.baseboard_fab2(sch_1):page104_i71:enable_disable" )
			)
			( pin "Y6F1.3"
				( objectStatus "@baseboard_fab2_lib.baseboard_fab2(sch_1):page104_i71:gnd" )
			)
			( pin "Y6F1.2"
				( objectStatus "@baseboard_fab2_lib.baseboard_fab2(sch_1):page104_i71:nc_gnd" )
			)
			( pin "Y6F1.4"
				( objectStatus "@baseboard_fab2_lib.baseboard_fab2(sch_1):page104_i71:\out\" )
			)
			( pin "Y6F1.5"
				( objectStatus "@baseboard_fab2_lib.baseboard_fab2(sch_1):page104_i71:out_n" )
			)
			( pin "Y6F1.6"
				( objectStatus "@baseboard_fab2_lib.baseboard_fab2(sch_1):page104_i71:vcc" )
			)
			( pin "Y3F1.1"
				( objectStatus "@baseboard_fab2_lib.baseboard_fab2(sch_1):page104_i72:enable_disable" )
			)
			( pin "Y3F1.3"
				( objectStatus "@baseboard_fab2_lib.baseboard_fab2(sch_1):page104_i72:gnd" )
			)
			( pin "Y3F1.2"
				( objectStatus "@baseboard_fab2_lib.baseboard_fab2(sch_1):page104_i72:nc_gnd" )
			)
			( pin "Y3F1.4"
				( objectStatus "@baseboard_fab2_lib.baseboard_fab2(sch_1):page104_i72:\out\" )
			)
			( pin "Y3F1.5"
				( objectStatus "@baseboard_fab2_lib.baseboard_fab2(sch_1):page104_i72:out_n" )
			)
			( pin "Y3F1.6"
				( objectStatus "@baseboard_fab2_lib.baseboard_fab2(sch_1):page104_i72:vcc" )
			)
			( pin "R6F10.1"
				( objectStatus "@baseboard_fab2_lib.baseboard_fab2(sch_1):page104_i78:a" )
			)
			( pin "R6F10.2"
				( objectStatus "@baseboard_fab2_lib.baseboard_fab2(sch_1):page104_i78:b" )
			)
			( pin "R6F11.1"
				( objectStatus "@baseboard_fab2_lib.baseboard_fab2(sch_1):page104_i79:a" )
			)
			( pin "R6F11.2"
				( objectStatus "@baseboard_fab2_lib.baseboard_fab2(sch_1):page104_i79:b" )
			)
			( pin "R3F5.1"
				( objectStatus "@baseboard_fab2_lib.baseboard_fab2(sch_1):page104_i84:a" )
			)
			( pin "R3F5.2"
				( objectStatus "@baseboard_fab2_lib.baseboard_fab2(sch_1):page104_i84:b" )
			)
			( pin "R3F6.1"
				( objectStatus "@baseboard_fab2_lib.baseboard_fab2(sch_1):page104_i88:a" )
			)
			( pin "R3F6.2"
				( objectStatus "@baseboard_fab2_lib.baseboard_fab2(sch_1):page104_i88:b" )
			)
			( pin "R8D43.1"
				( objectStatus "@baseboard_fab2_lib.baseboard_fab2(sch_1):page104_i93:a" )
			)
			( pin "R8D43.2"
				( objectStatus "@baseboard_fab2_lib.baseboard_fab2(sch_1):page104_i93:b" )
			)
			( pin "R7D40.1"
				( objectStatus "@baseboard_fab2_lib.baseboard_fab2(sch_1):page104_i94:a" )
			)
			( pin "R7D40.2"
				( objectStatus "@baseboard_fab2_lib.baseboard_fab2(sch_1):page104_i94:b" )
			)
			( pin "R7D39.1"
				( objectStatus "@baseboard_fab2_lib.baseboard_fab2(sch_1):page104_i95:a" )
			)
			( pin "R7D39.2"
				( objectStatus "@baseboard_fab2_lib.baseboard_fab2(sch_1):page104_i95:b" )
			)
			( pin "R7D36.1"
				( objectStatus "@baseboard_fab2_lib.baseboard_fab2(sch_1):page104_i96:a" )
			)
			( pin "R7D36.2"
				( objectStatus "@baseboard_fab2_lib.baseboard_fab2(sch_1):page104_i96:b" )
			)
			( pin "R7D38.1"
				( objectStatus "@baseboard_fab2_lib.baseboard_fab2(sch_1):page104_i97:a" )
			)
			( pin "R7D38.2"
				( objectStatus "@baseboard_fab2_lib.baseboard_fab2(sch_1):page104_i97:b" )
			)
			( pin "R7D37.1"
				( objectStatus "@baseboard_fab2_lib.baseboard_fab2(sch_1):page104_i98:a" )
			)
			( pin "R7D37.2"
				( objectStatus "@baseboard_fab2_lib.baseboard_fab2(sch_1):page104_i98:b" )
			)
			( pin "C7G24.1"
				( objectStatus "@baseboard_fab2_lib.baseboard_fab2(sch_1):page105_i1:a" )
			)
			( pin "C7G24.2"
				( objectStatus "@baseboard_fab2_lib.baseboard_fab2(sch_1):page105_i1:b" )
			)
			( pin "C7G6.1"
				( objectStatus "@baseboard_fab2_lib.baseboard_fab2(sch_1):page105_i6:a" )
			)
			( pin "C7G6.2"
				( objectStatus "@baseboard_fab2_lib.baseboard_fab2(sch_1):page105_i6:b" )
			)
			( pin "C7G7.1"
				( objectStatus "@baseboard_fab2_lib.baseboard_fab2(sch_1):page105_i7:a" )
			)
			( pin "C7G7.2"
				( objectStatus "@baseboard_fab2_lib.baseboard_fab2(sch_1):page105_i7:b" )
			)
			( pin "C7G10.1"
				( objectStatus "@baseboard_fab2_lib.baseboard_fab2(sch_1):page105_i8:a" )
			)
			( pin "C7G10.2"
				( objectStatus "@baseboard_fab2_lib.baseboard_fab2(sch_1):page105_i8:b" )
			)
			( pin "C7G12.1"
				( objectStatus "@baseboard_fab2_lib.baseboard_fab2(sch_1):page105_i12:a" )
			)
			( pin "C7G12.2"
				( objectStatus "@baseboard_fab2_lib.baseboard_fab2(sch_1):page105_i12:b" )
			)
			( pin "C7G13.1"
				( objectStatus "@baseboard_fab2_lib.baseboard_fab2(sch_1):page105_i13:a" )
			)
			( pin "C7G13.2"
				( objectStatus "@baseboard_fab2_lib.baseboard_fab2(sch_1):page105_i13:b" )
			)
			( pin "C7G5.1"
				( objectStatus "@baseboard_fab2_lib.baseboard_fab2(sch_1):page105_i20:a" )
			)
			( pin "C7G5.2"
				( objectStatus "@baseboard_fab2_lib.baseboard_fab2(sch_1):page105_i20:b" )
			)
			( pin "C7G9.1"
				( objectStatus "@baseboard_fab2_lib.baseboard_fab2(sch_1):page105_i21:a" )
			)
			( pin "C7G9.2"
				( objectStatus "@baseboard_fab2_lib.baseboard_fab2(sch_1):page105_i21:b" )
			)
			( pin "C7G8.1"
				( objectStatus "@baseboard_fab2_lib.baseboard_fab2(sch_1):page105_i22:a" )
			)
			( pin "C7G8.2"
				( objectStatus "@baseboard_fab2_lib.baseboard_fab2(sch_1):page105_i22:b" )
			)
			( pin "C7G11.1"
				( objectStatus "@baseboard_fab2_lib.baseboard_fab2(sch_1):page105_i27:a" )
			)
			( pin "C7G11.2"
				( objectStatus "@baseboard_fab2_lib.baseboard_fab2(sch_1):page105_i27:b" )
			)
			( pin "C7G14.1"
				( objectStatus "@baseboard_fab2_lib.baseboard_fab2(sch_1):page105_i28:a" )
			)
			( pin "C7G14.2"
				( objectStatus "@baseboard_fab2_lib.baseboard_fab2(sch_1):page105_i28:b" )
			)
			( pin "C7G16.1"
				( objectStatus "@baseboard_fab2_lib.baseboard_fab2(sch_1):page105_i31:a" )
			)
			( pin "C7G16.2"
				( objectStatus "@baseboard_fab2_lib.baseboard_fab2(sch_1):page105_i31:b" )
			)
			( pin "C7G18.1"
				( objectStatus "@baseboard_fab2_lib.baseboard_fab2(sch_1):page105_i32:a" )
			)
			( pin "C7G18.2"
				( objectStatus "@baseboard_fab2_lib.baseboard_fab2(sch_1):page105_i32:b" )
			)
			( pin "C7G20.1"
				( objectStatus "@baseboard_fab2_lib.baseboard_fab2(sch_1):page105_i34:a" )
			)
			( pin "C7G20.2"
				( objectStatus "@baseboard_fab2_lib.baseboard_fab2(sch_1):page105_i34:b" )
			)
			( pin "C7G22.1"
				( objectStatus "@baseboard_fab2_lib.baseboard_fab2(sch_1):page105_i37:a" )
			)
			( pin "C7G22.2"
				( objectStatus "@baseboard_fab2_lib.baseboard_fab2(sch_1):page105_i37:b" )
			)
			( pin "C7G17.1"
				( objectStatus "@baseboard_fab2_lib.baseboard_fab2(sch_1):page105_i44:a" )
			)
			( pin "C7G17.2"
				( objectStatus "@baseboard_fab2_lib.baseboard_fab2(sch_1):page105_i44:b" )
			)
			( pin "C7G15.1"
				( objectStatus "@baseboard_fab2_lib.baseboard_fab2(sch_1):page105_i45:a" )
			)
			( pin "C7G15.2"
				( objectStatus "@baseboard_fab2_lib.baseboard_fab2(sch_1):page105_i45:b" )
			)
			( pin "C7G19.1"
				( objectStatus "@baseboard_fab2_lib.baseboard_fab2(sch_1):page105_i46:a" )
			)
			( pin "C7G19.2"
				( objectStatus "@baseboard_fab2_lib.baseboard_fab2(sch_1):page105_i46:b" )
			)
			( pin "C7G21.1"
				( objectStatus "@baseboard_fab2_lib.baseboard_fab2(sch_1):page105_i51:a" )
			)
			( pin "C7G21.2"
				( objectStatus "@baseboard_fab2_lib.baseboard_fab2(sch_1):page105_i51:b" )
			)
			( pin "C7G23.1"
				( objectStatus "@baseboard_fab2_lib.baseboard_fab2(sch_1):page105_i52:a" )
			)
			( pin "C7G23.2"
				( objectStatus "@baseboard_fab2_lib.baseboard_fab2(sch_1):page105_i52:b" )
			)
			( pin "C7G26.1"
				( objectStatus "@baseboard_fab2_lib.baseboard_fab2(sch_1):page105_i55:a" )
			)
			( pin "C7G26.2"
				( objectStatus "@baseboard_fab2_lib.baseboard_fab2(sch_1):page105_i55:b" )
			)
			( pin "C8G4.1"
				( objectStatus "@baseboard_fab2_lib.baseboard_fab2(sch_1):page105_i56:a" )
			)
			( pin "C8G4.2"
				( objectStatus "@baseboard_fab2_lib.baseboard_fab2(sch_1):page105_i56:b" )
			)
			( pin "C8G2.1"
				( objectStatus "@baseboard_fab2_lib.baseboard_fab2(sch_1):page105_i58:a" )
			)
			( pin "C8G2.2"
				( objectStatus "@baseboard_fab2_lib.baseboard_fab2(sch_1):page105_i58:b" )
			)
			( pin "C8G6.1"
				( objectStatus "@baseboard_fab2_lib.baseboard_fab2(sch_1):page105_i61:a" )
			)
			( pin "C8G6.2"
				( objectStatus "@baseboard_fab2_lib.baseboard_fab2(sch_1):page105_i61:b" )
			)
			( pin "C8G7.1"
				( objectStatus "@baseboard_fab2_lib.baseboard_fab2(sch_1):page105_i62:a" )
			)
			( pin "C8G7.2"
				( objectStatus "@baseboard_fab2_lib.baseboard_fab2(sch_1):page105_i62:b" )
			)
			( pin "C7G25.1"
				( objectStatus "@baseboard_fab2_lib.baseboard_fab2(sch_1):page105_i69:a" )
			)
			( pin "C7G25.2"
				( objectStatus "@baseboard_fab2_lib.baseboard_fab2(sch_1):page105_i69:b" )
			)
			( pin "C8G1.1"
				( objectStatus "@baseboard_fab2_lib.baseboard_fab2(sch_1):page105_i70:a" )
			)
			( pin "C8G1.2"
				( objectStatus "@baseboard_fab2_lib.baseboard_fab2(sch_1):page105_i70:b" )
			)
			( pin "C8G3.1"
				( objectStatus "@baseboard_fab2_lib.baseboard_fab2(sch_1):page105_i71:a" )
			)
			( pin "C8G3.2"
				( objectStatus "@baseboard_fab2_lib.baseboard_fab2(sch_1):page105_i71:b" )
			)
			( pin "C8G5.1"
				( objectStatus "@baseboard_fab2_lib.baseboard_fab2(sch_1):page105_i75:a" )
			)
			( pin "C8G5.2"
				( objectStatus "@baseboard_fab2_lib.baseboard_fab2(sch_1):page105_i75:b" )
			)
			( pin "C8G8.1"
				( objectStatus "@baseboard_fab2_lib.baseboard_fab2(sch_1):page105_i76:a" )
			)
			( pin "C8G8.2"
				( objectStatus "@baseboard_fab2_lib.baseboard_fab2(sch_1):page105_i76:b" )
			)
			( pin "C8G9.1"
				( objectStatus "@baseboard_fab2_lib.baseboard_fab2(sch_1):page105_i93:a" )
			)
			( pin "C8G9.2"
				( objectStatus "@baseboard_fab2_lib.baseboard_fab2(sch_1):page105_i93:b" )
			)
			( pin "C8G10.1"
				( objectStatus "@baseboard_fab2_lib.baseboard_fab2(sch_1):page105_i96:a" )
			)
			( pin "C8G10.2"
				( objectStatus "@baseboard_fab2_lib.baseboard_fab2(sch_1):page105_i96:b" )
			)
			( pin "C6B18.1"
				( objectStatus "@baseboard_fab2_lib.baseboard_fab2(sch_1):page105_i153:a" )
			)
			( pin "C6B18.2"
				( objectStatus "@baseboard_fab2_lib.baseboard_fab2(sch_1):page105_i153:b" )
			)
			( pin "C6B19.1"
				( objectStatus "@baseboard_fab2_lib.baseboard_fab2(sch_1):page105_i160:a" )
			)
			( pin "C6B19.2"
				( objectStatus "@baseboard_fab2_lib.baseboard_fab2(sch_1):page105_i160:b" )
			)
			( pin "C6B15.1"
				( objectStatus "@baseboard_fab2_lib.baseboard_fab2(sch_1):page105_i163:a" )
			)
			( pin "C6B15.2"
				( objectStatus "@baseboard_fab2_lib.baseboard_fab2(sch_1):page105_i163:b" )
			)
			( pin "C6B11.1"
				( objectStatus "@baseboard_fab2_lib.baseboard_fab2(sch_1):page105_i166:a" )
			)
			( pin "C6B11.2"
				( objectStatus "@baseboard_fab2_lib.baseboard_fab2(sch_1):page105_i166:b" )
			)
			( pin "C6B6.1"
				( objectStatus "@baseboard_fab2_lib.baseboard_fab2(sch_1):page105_i169:a" )
			)
			( pin "C6B6.2"
				( objectStatus "@baseboard_fab2_lib.baseboard_fab2(sch_1):page105_i169:b" )
			)
			( pin "C6B20.1"
				( objectStatus "@baseboard_fab2_lib.baseboard_fab2(sch_1):page105_i173:a" )
			)
			( pin "C6B20.2"
				( objectStatus "@baseboard_fab2_lib.baseboard_fab2(sch_1):page105_i173:b" )
			)
			( pin "C6B17.1"
				( objectStatus "@baseboard_fab2_lib.baseboard_fab2(sch_1):page105_i175:a" )
			)
			( pin "C6B17.2"
				( objectStatus "@baseboard_fab2_lib.baseboard_fab2(sch_1):page105_i175:b" )
			)
			( pin "C6B16.1"
				( objectStatus "@baseboard_fab2_lib.baseboard_fab2(sch_1):page105_i180:a" )
			)
			( pin "C6B16.2"
				( objectStatus "@baseboard_fab2_lib.baseboard_fab2(sch_1):page105_i180:b" )
			)
			( pin "C6B14.1"
				( objectStatus "@baseboard_fab2_lib.baseboard_fab2(sch_1):page105_i181:a" )
			)
			( pin "C6B14.2"
				( objectStatus "@baseboard_fab2_lib.baseboard_fab2(sch_1):page105_i181:b" )
			)
			( pin "C6B9.1"
				( objectStatus "@baseboard_fab2_lib.baseboard_fab2(sch_1):page105_i185:a" )
			)
			( pin "C6B9.2"
				( objectStatus "@baseboard_fab2_lib.baseboard_fab2(sch_1):page105_i185:b" )
			)
			( pin "C6B12.1"
				( objectStatus "@baseboard_fab2_lib.baseboard_fab2(sch_1):page105_i187:a" )
			)
			( pin "C6B12.2"
				( objectStatus "@baseboard_fab2_lib.baseboard_fab2(sch_1):page105_i187:b" )
			)
			( pin "C6B13.1"
				( objectStatus "@baseboard_fab2_lib.baseboard_fab2(sch_1):page105_i189:a" )
			)
			( pin "C6B13.2"
				( objectStatus "@baseboard_fab2_lib.baseboard_fab2(sch_1):page105_i189:b" )
			)
			( pin "C6B10.1"
				( objectStatus "@baseboard_fab2_lib.baseboard_fab2(sch_1):page105_i193:a" )
			)
			( pin "C6B10.2"
				( objectStatus "@baseboard_fab2_lib.baseboard_fab2(sch_1):page105_i193:b" )
			)
			( pin "C6B4.1"
				( objectStatus "@baseboard_fab2_lib.baseboard_fab2(sch_1):page105_i196:a" )
			)
			( pin "C6B4.2"
				( objectStatus "@baseboard_fab2_lib.baseboard_fab2(sch_1):page105_i196:b" )
			)
			( pin "C6B8.1"
				( objectStatus "@baseboard_fab2_lib.baseboard_fab2(sch_1):page105_i198:a" )
			)
			( pin "C6B8.2"
				( objectStatus "@baseboard_fab2_lib.baseboard_fab2(sch_1):page105_i198:b" )
			)
			( pin "C6B5.1"
				( objectStatus "@baseboard_fab2_lib.baseboard_fab2(sch_1):page105_i201:a" )
			)
			( pin "C6B5.2"
				( objectStatus "@baseboard_fab2_lib.baseboard_fab2(sch_1):page105_i201:b" )
			)
			( pin "C3M25.1"
				( objectStatus "@baseboard_fab2_lib.baseboard_fab2(sch_1):page105_i205:a" )
			)
			( pin "C3M25.2"
				( objectStatus "@baseboard_fab2_lib.baseboard_fab2(sch_1):page105_i205:b" )
			)
			( pin "C3M34.1"
				( objectStatus "@baseboard_fab2_lib.baseboard_fab2(sch_1):page105_i206:a" )
			)
			( pin "C3M34.2"
				( objectStatus "@baseboard_fab2_lib.baseboard_fab2(sch_1):page105_i206:b" )
			)
			( pin "C3M28.1"
				( objectStatus "@baseboard_fab2_lib.baseboard_fab2(sch_1):page105_i212:a" )
			)
			( pin "C3M28.2"
				( objectStatus "@baseboard_fab2_lib.baseboard_fab2(sch_1):page105_i212:b" )
			)
			( pin "C3M33.1"
				( objectStatus "@baseboard_fab2_lib.baseboard_fab2(sch_1):page105_i217:a" )
			)
			( pin "C3M33.2"
				( objectStatus "@baseboard_fab2_lib.baseboard_fab2(sch_1):page105_i217:b" )
			)
			( pin "C3M36.1"
				( objectStatus "@baseboard_fab2_lib.baseboard_fab2(sch_1):page105_i218:a" )
			)
			( pin "C3M36.2"
				( objectStatus "@baseboard_fab2_lib.baseboard_fab2(sch_1):page105_i218:b" )
			)
			( pin "C3M32.1"
				( objectStatus "@baseboard_fab2_lib.baseboard_fab2(sch_1):page105_i223:a" )
			)
			( pin "C3M32.2"
				( objectStatus "@baseboard_fab2_lib.baseboard_fab2(sch_1):page105_i223:b" )
			)
			( pin "C3M35.1"
				( objectStatus "@baseboard_fab2_lib.baseboard_fab2(sch_1):page105_i225:a" )
			)
			( pin "C3M35.2"
				( objectStatus "@baseboard_fab2_lib.baseboard_fab2(sch_1):page105_i225:b" )
			)
			( pin "C3M26.1"
				( objectStatus "@baseboard_fab2_lib.baseboard_fab2(sch_1):page105_i229:a" )
			)
			( pin "C3M26.2"
				( objectStatus "@baseboard_fab2_lib.baseboard_fab2(sch_1):page105_i229:b" )
			)
			( pin "C3M3.1"
				( objectStatus "@baseboard_fab2_lib.baseboard_fab2(sch_1):page105_i232:a" )
			)
			( pin "C3M3.2"
				( objectStatus "@baseboard_fab2_lib.baseboard_fab2(sch_1):page105_i232:b" )
			)
			( pin "C3M11.1"
				( objectStatus "@baseboard_fab2_lib.baseboard_fab2(sch_1):page105_i234:a" )
			)
			( pin "C3M11.2"
				( objectStatus "@baseboard_fab2_lib.baseboard_fab2(sch_1):page105_i234:b" )
			)
			( pin "C3M13.1"
				( objectStatus "@baseboard_fab2_lib.baseboard_fab2(sch_1):page105_i239:a" )
			)
			( pin "C3M13.2"
				( objectStatus "@baseboard_fab2_lib.baseboard_fab2(sch_1):page105_i239:b" )
			)
			( pin "C3M4.1"
				( objectStatus "@baseboard_fab2_lib.baseboard_fab2(sch_1):page105_i244:a" )
			)
			( pin "C3M4.2"
				( objectStatus "@baseboard_fab2_lib.baseboard_fab2(sch_1):page105_i244:b" )
			)
			( pin "C3M12.1"
				( objectStatus "@baseboard_fab2_lib.baseboard_fab2(sch_1):page105_i246:a" )
			)
			( pin "C3M12.2"
				( objectStatus "@baseboard_fab2_lib.baseboard_fab2(sch_1):page105_i246:b" )
			)
			( pin "C3M2.1"
				( objectStatus "@baseboard_fab2_lib.baseboard_fab2(sch_1):page105_i247:a" )
			)
			( pin "C3M2.2"
				( objectStatus "@baseboard_fab2_lib.baseboard_fab2(sch_1):page105_i247:b" )
			)
			( pin "C3M14.1"
				( objectStatus "@baseboard_fab2_lib.baseboard_fab2(sch_1):page105_i253:a" )
			)
			( pin "C3M14.2"
				( objectStatus "@baseboard_fab2_lib.baseboard_fab2(sch_1):page105_i253:b" )
			)
			( pin "C3M1.1"
				( objectStatus "@baseboard_fab2_lib.baseboard_fab2(sch_1):page105_i255:a" )
			)
			( pin "C3M1.2"
				( objectStatus "@baseboard_fab2_lib.baseboard_fab2(sch_1):page105_i255:b" )
			)
			( pin "C1R2.1"
				( objectStatus "@baseboard_fab2_lib.baseboard_fab2(sch_1):page106_i10:a" )
			)
			( pin "C1R2.2"
				( objectStatus "@baseboard_fab2_lib.baseboard_fab2(sch_1):page106_i10:b" )
			)
			( pin "C1R4.1"
				( objectStatus "@baseboard_fab2_lib.baseboard_fab2(sch_1):page106_i26:a" )
			)
			( pin "C1R4.2"
				( objectStatus "@baseboard_fab2_lib.baseboard_fab2(sch_1):page106_i26:b" )
			)
			( pin "C1R1.1"
				( objectStatus "@baseboard_fab2_lib.baseboard_fab2(sch_1):page106_i29:a" )
			)
			( pin "C1R1.2"
				( objectStatus "@baseboard_fab2_lib.baseboard_fab2(sch_1):page106_i29:b" )
			)
			( pin "C1R3.1"
				( objectStatus "@baseboard_fab2_lib.baseboard_fab2(sch_1):page106_i37:a" )
			)
			( pin "C1R3.2"
				( objectStatus "@baseboard_fab2_lib.baseboard_fab2(sch_1):page106_i37:b" )
			)
			( pin "C1R6.1"
				( objectStatus "@baseboard_fab2_lib.baseboard_fab2(sch_1):page106_i40:a" )
			)
			( pin "C1R6.2"
				( objectStatus "@baseboard_fab2_lib.baseboard_fab2(sch_1):page106_i40:b" )
			)
			( pin "C1R8.1"
				( objectStatus "@baseboard_fab2_lib.baseboard_fab2(sch_1):page106_i55:a" )
			)
			( pin "C1R8.2"
				( objectStatus "@baseboard_fab2_lib.baseboard_fab2(sch_1):page106_i55:b" )
			)
			( pin "C1R5.1"
				( objectStatus "@baseboard_fab2_lib.baseboard_fab2(sch_1):page106_i59:a" )
			)
			( pin "C1R5.2"
				( objectStatus "@baseboard_fab2_lib.baseboard_fab2(sch_1):page106_i59:b" )
			)
			( pin "C1R7.1"
				( objectStatus "@baseboard_fab2_lib.baseboard_fab2(sch_1):page106_i70:a" )
			)
			( pin "C1R7.2"
				( objectStatus "@baseboard_fab2_lib.baseboard_fab2(sch_1):page106_i70:b" )
			)
			( pin "C2M14.1"
				( objectStatus "@baseboard_fab2_lib.baseboard_fab2(sch_1):page106_i76:a" )
			)
			( pin "C2M14.2"
				( objectStatus "@baseboard_fab2_lib.baseboard_fab2(sch_1):page106_i76:b" )
			)
			( pin "C1M18.1"
				( objectStatus "@baseboard_fab2_lib.baseboard_fab2(sch_1):page106_i78:a" )
			)
			( pin "C1M18.2"
				( objectStatus "@baseboard_fab2_lib.baseboard_fab2(sch_1):page106_i78:b" )
			)
			( pin "C1M16.1"
				( objectStatus "@baseboard_fab2_lib.baseboard_fab2(sch_1):page106_i82:a" )
			)
			( pin "C1M16.2"
				( objectStatus "@baseboard_fab2_lib.baseboard_fab2(sch_1):page106_i82:b" )
			)
			( pin "C1M14.1"
				( objectStatus "@baseboard_fab2_lib.baseboard_fab2(sch_1):page106_i85:a" )
			)
			( pin "C1M14.2"
				( objectStatus "@baseboard_fab2_lib.baseboard_fab2(sch_1):page106_i85:b" )
			)
			( pin "C2M15.1"
				( objectStatus "@baseboard_fab2_lib.baseboard_fab2(sch_1):page106_i86:a" )
			)
			( pin "C2M15.2"
				( objectStatus "@baseboard_fab2_lib.baseboard_fab2(sch_1):page106_i86:b" )
			)
			( pin "C1M19.1"
				( objectStatus "@baseboard_fab2_lib.baseboard_fab2(sch_1):page106_i90:a" )
			)
			( pin "C1M19.2"
				( objectStatus "@baseboard_fab2_lib.baseboard_fab2(sch_1):page106_i90:b" )
			)
			( pin "C1M17.1"
				( objectStatus "@baseboard_fab2_lib.baseboard_fab2(sch_1):page106_i92:a" )
			)
			( pin "C1M17.2"
				( objectStatus "@baseboard_fab2_lib.baseboard_fab2(sch_1):page106_i92:b" )
			)
			( pin "C1M15.1"
				( objectStatus "@baseboard_fab2_lib.baseboard_fab2(sch_1):page106_i95:a" )
			)
			( pin "C1M15.2"
				( objectStatus "@baseboard_fab2_lib.baseboard_fab2(sch_1):page106_i95:b" )
			)
			( pin "C1M12.1"
				( objectStatus "@baseboard_fab2_lib.baseboard_fab2(sch_1):page106_i100:a" )
			)
			( pin "C1M12.2"
				( objectStatus "@baseboard_fab2_lib.baseboard_fab2(sch_1):page106_i100:b" )
			)
			( pin "C1M10.1"
				( objectStatus "@baseboard_fab2_lib.baseboard_fab2(sch_1):page106_i102:a" )
			)
			( pin "C1M10.2"
				( objectStatus "@baseboard_fab2_lib.baseboard_fab2(sch_1):page106_i102:b" )
			)
			( pin "C1M8.1"
				( objectStatus "@baseboard_fab2_lib.baseboard_fab2(sch_1):page106_i105:a" )
			)
			( pin "C1M8.2"
				( objectStatus "@baseboard_fab2_lib.baseboard_fab2(sch_1):page106_i105:b" )
			)
			( pin "C1M6.1"
				( objectStatus "@baseboard_fab2_lib.baseboard_fab2(sch_1):page106_i109:a" )
			)
			( pin "C1M6.2"
				( objectStatus "@baseboard_fab2_lib.baseboard_fab2(sch_1):page106_i109:b" )
			)
			( pin "C1M13.1"
				( objectStatus "@baseboard_fab2_lib.baseboard_fab2(sch_1):page106_i111:a" )
			)
			( pin "C1M13.2"
				( objectStatus "@baseboard_fab2_lib.baseboard_fab2(sch_1):page106_i111:b" )
			)
			( pin "C1M9.1"
				( objectStatus "@baseboard_fab2_lib.baseboard_fab2(sch_1):page106_i114:a" )
			)
			( pin "C1M9.2"
				( objectStatus "@baseboard_fab2_lib.baseboard_fab2(sch_1):page106_i114:b" )
			)
			( pin "C1M11.1"
				( objectStatus "@baseboard_fab2_lib.baseboard_fab2(sch_1):page106_i117:a" )
			)
			( pin "C1M11.2"
				( objectStatus "@baseboard_fab2_lib.baseboard_fab2(sch_1):page106_i117:b" )
			)
			( pin "C1M7.1"
				( objectStatus "@baseboard_fab2_lib.baseboard_fab2(sch_1):page106_i122:a" )
			)
			( pin "C1M7.2"
				( objectStatus "@baseboard_fab2_lib.baseboard_fab2(sch_1):page106_i122:b" )
			)
			( pin "C2R7.1"
				( objectStatus "@baseboard_fab2_lib.baseboard_fab2(sch_1):page106_i123:a" )
			)
			( pin "C2R7.2"
				( objectStatus "@baseboard_fab2_lib.baseboard_fab2(sch_1):page106_i123:b" )
			)
			( pin "C1R10.1"
				( objectStatus "@baseboard_fab2_lib.baseboard_fab2(sch_1):page106_i128:a" )
			)
			( pin "C1R10.2"
				( objectStatus "@baseboard_fab2_lib.baseboard_fab2(sch_1):page106_i128:b" )
			)
			( pin "C2R14.1"
				( objectStatus "@baseboard_fab2_lib.baseboard_fab2(sch_1):page106_i130:a" )
			)
			( pin "C2R14.2"
				( objectStatus "@baseboard_fab2_lib.baseboard_fab2(sch_1):page106_i130:b" )
			)
			( pin "C1R9.1"
				( objectStatus "@baseboard_fab2_lib.baseboard_fab2(sch_1):page106_i134:a" )
			)
			( pin "C1R9.2"
				( objectStatus "@baseboard_fab2_lib.baseboard_fab2(sch_1):page106_i134:b" )
			)
			( pin "C2R13.1"
				( objectStatus "@baseboard_fab2_lib.baseboard_fab2(sch_1):page106_i137:a" )
			)
			( pin "C2R13.2"
				( objectStatus "@baseboard_fab2_lib.baseboard_fab2(sch_1):page106_i137:b" )
			)
			( pin "C2R8.1"
				( objectStatus "@baseboard_fab2_lib.baseboard_fab2(sch_1):page106_i141:a" )
			)
			( pin "C2R8.2"
				( objectStatus "@baseboard_fab2_lib.baseboard_fab2(sch_1):page106_i141:b" )
			)
			( pin "C2R10.1"
				( objectStatus "@baseboard_fab2_lib.baseboard_fab2(sch_1):page106_i142:a" )
			)
			( pin "C2R10.2"
				( objectStatus "@baseboard_fab2_lib.baseboard_fab2(sch_1):page106_i142:b" )
			)
			( pin "C2R9.1"
				( objectStatus "@baseboard_fab2_lib.baseboard_fab2(sch_1):page106_i147:a" )
			)
			( pin "C2R9.2"
				( objectStatus "@baseboard_fab2_lib.baseboard_fab2(sch_1):page106_i147:b" )
			)
			( pin "C3P13.1"
				( objectStatus "@baseboard_fab2_lib.baseboard_fab2(sch_1):page107_i207:a" )
			)
			( pin "C3P13.2"
				( objectStatus "@baseboard_fab2_lib.baseboard_fab2(sch_1):page107_i207:b" )
			)
			( pin "C3P17.1"
				( objectStatus "@baseboard_fab2_lib.baseboard_fab2(sch_1):page107_i208:a" )
			)
			( pin "C3P17.2"
				( objectStatus "@baseboard_fab2_lib.baseboard_fab2(sch_1):page107_i208:b" )
			)
			( pin "C3P11.1"
				( objectStatus "@baseboard_fab2_lib.baseboard_fab2(sch_1):page107_i212:a" )
			)
			( pin "C3P11.2"
				( objectStatus "@baseboard_fab2_lib.baseboard_fab2(sch_1):page107_i212:b" )
			)
			( pin "C3P20.1"
				( objectStatus "@baseboard_fab2_lib.baseboard_fab2(sch_1):page107_i215:a" )
			)
			( pin "C3P20.2"
				( objectStatus "@baseboard_fab2_lib.baseboard_fab2(sch_1):page107_i215:b" )
			)
			( pin "C3P25.1"
				( objectStatus "@baseboard_fab2_lib.baseboard_fab2(sch_1):page107_i216:a" )
			)
			( pin "C3P25.2"
				( objectStatus "@baseboard_fab2_lib.baseboard_fab2(sch_1):page107_i216:b" )
			)
			( pin "C3P18.1"
				( objectStatus "@baseboard_fab2_lib.baseboard_fab2(sch_1):page107_i219:a" )
			)
			( pin "C3P18.2"
				( objectStatus "@baseboard_fab2_lib.baseboard_fab2(sch_1):page107_i219:b" )
			)
			( pin "C3P27.1"
				( objectStatus "@baseboard_fab2_lib.baseboard_fab2(sch_1):page107_i223:a" )
			)
			( pin "C3P27.2"
				( objectStatus "@baseboard_fab2_lib.baseboard_fab2(sch_1):page107_i223:b" )
			)
			( pin "C3P15.1"
				( objectStatus "@baseboard_fab2_lib.baseboard_fab2(sch_1):page107_i226:a" )
			)
			( pin "C3P15.2"
				( objectStatus "@baseboard_fab2_lib.baseboard_fab2(sch_1):page107_i226:b" )
			)
			( pin "C3P23.1"
				( objectStatus "@baseboard_fab2_lib.baseboard_fab2(sch_1):page107_i229:a" )
			)
			( pin "C3P23.2"
				( objectStatus "@baseboard_fab2_lib.baseboard_fab2(sch_1):page107_i229:b" )
			)
			( pin "C3P28.1"
				( objectStatus "@baseboard_fab2_lib.baseboard_fab2(sch_1):page107_i232:a" )
			)
			( pin "C3P28.2"
				( objectStatus "@baseboard_fab2_lib.baseboard_fab2(sch_1):page107_i232:b" )
			)
			( pin "C3P32.1"
				( objectStatus "@baseboard_fab2_lib.baseboard_fab2(sch_1):page107_i234:a" )
			)
			( pin "C3P32.2"
				( objectStatus "@baseboard_fab2_lib.baseboard_fab2(sch_1):page107_i234:b" )
			)
			( pin "C3P37.1"
				( objectStatus "@baseboard_fab2_lib.baseboard_fab2(sch_1):page107_i235:a" )
			)
			( pin "C3P37.2"
				( objectStatus "@baseboard_fab2_lib.baseboard_fab2(sch_1):page107_i235:b" )
			)
			( pin "C3P35.1"
				( objectStatus "@baseboard_fab2_lib.baseboard_fab2(sch_1):page107_i240:a" )
			)
			( pin "C3P35.2"
				( objectStatus "@baseboard_fab2_lib.baseboard_fab2(sch_1):page107_i240:b" )
			)
			( pin "C3P40.1"
				( objectStatus "@baseboard_fab2_lib.baseboard_fab2(sch_1):page107_i241:a" )
			)
			( pin "C3P40.2"
				( objectStatus "@baseboard_fab2_lib.baseboard_fab2(sch_1):page107_i241:b" )
			)
			( pin "C3P30.1"
				( objectStatus "@baseboard_fab2_lib.baseboard_fab2(sch_1):page107_i245:a" )
			)
			( pin "C3P30.2"
				( objectStatus "@baseboard_fab2_lib.baseboard_fab2(sch_1):page107_i245:b" )
			)
			( pin "C3P39.1"
				( objectStatus "@baseboard_fab2_lib.baseboard_fab2(sch_1):page107_i248:a" )
			)
			( pin "C3P39.2"
				( objectStatus "@baseboard_fab2_lib.baseboard_fab2(sch_1):page107_i248:b" )
			)
			( pin "C2U4.1"
				( objectStatus "@baseboard_fab2_lib.baseboard_fab2(sch_1):page107_i257:a" )
			)
			( pin "C2U4.2"
				( objectStatus "@baseboard_fab2_lib.baseboard_fab2(sch_1):page107_i257:b" )
			)
			( pin "C2U6.1"
				( objectStatus "@baseboard_fab2_lib.baseboard_fab2(sch_1):page107_i260:a" )
			)
			( pin "C2U6.2"
				( objectStatus "@baseboard_fab2_lib.baseboard_fab2(sch_1):page107_i260:b" )
			)
			( pin "C2U8.1"
				( objectStatus "@baseboard_fab2_lib.baseboard_fab2(sch_1):page107_i264:a" )
			)
			( pin "C2U8.2"
				( objectStatus "@baseboard_fab2_lib.baseboard_fab2(sch_1):page107_i264:b" )
			)
			( pin "C2U12.1"
				( objectStatus "@baseboard_fab2_lib.baseboard_fab2(sch_1):page107_i265:a" )
			)
			( pin "C2U12.2"
				( objectStatus "@baseboard_fab2_lib.baseboard_fab2(sch_1):page107_i265:b" )
			)
			( pin "C2U10.1"
				( objectStatus "@baseboard_fab2_lib.baseboard_fab2(sch_1):page107_i267:a" )
			)
			( pin "C2U10.2"
				( objectStatus "@baseboard_fab2_lib.baseboard_fab2(sch_1):page107_i267:b" )
			)
			( pin "C2U3.1"
				( objectStatus "@baseboard_fab2_lib.baseboard_fab2(sch_1):page107_i272:a" )
			)
			( pin "C2U3.2"
				( objectStatus "@baseboard_fab2_lib.baseboard_fab2(sch_1):page107_i272:b" )
			)
			( pin "C2U5.1"
				( objectStatus "@baseboard_fab2_lib.baseboard_fab2(sch_1):page107_i274:a" )
			)
			( pin "C2U5.2"
				( objectStatus "@baseboard_fab2_lib.baseboard_fab2(sch_1):page107_i274:b" )
			)
			( pin "C2U7.1"
				( objectStatus "@baseboard_fab2_lib.baseboard_fab2(sch_1):page107_i277:a" )
			)
			( pin "C2U7.2"
				( objectStatus "@baseboard_fab2_lib.baseboard_fab2(sch_1):page107_i277:b" )
			)
			( pin "C2U11.1"
				( objectStatus "@baseboard_fab2_lib.baseboard_fab2(sch_1):page107_i278:a" )
			)
			( pin "C2U11.2"
				( objectStatus "@baseboard_fab2_lib.baseboard_fab2(sch_1):page107_i278:b" )
			)
			( pin "C2U9.1"
				( objectStatus "@baseboard_fab2_lib.baseboard_fab2(sch_1):page107_i279:a" )
			)
			( pin "C2U9.2"
				( objectStatus "@baseboard_fab2_lib.baseboard_fab2(sch_1):page107_i279:b" )
			)
			( pin "C2U16.1"
				( objectStatus "@baseboard_fab2_lib.baseboard_fab2(sch_1):page107_i286:a" )
			)
			( pin "C2U16.2"
				( objectStatus "@baseboard_fab2_lib.baseboard_fab2(sch_1):page107_i286:b" )
			)
			( pin "C2U14.1"
				( objectStatus "@baseboard_fab2_lib.baseboard_fab2(sch_1):page107_i287:a" )
			)
			( pin "C2U14.2"
				( objectStatus "@baseboard_fab2_lib.baseboard_fab2(sch_1):page107_i287:b" )
			)
			( pin "C2U18.1"
				( objectStatus "@baseboard_fab2_lib.baseboard_fab2(sch_1):page107_i294:a" )
			)
			( pin "C2U18.2"
				( objectStatus "@baseboard_fab2_lib.baseboard_fab2(sch_1):page107_i294:b" )
			)
			( pin "C2U15.1"
				( objectStatus "@baseboard_fab2_lib.baseboard_fab2(sch_1):page107_i296:a" )
			)
			( pin "C2U15.2"
				( objectStatus "@baseboard_fab2_lib.baseboard_fab2(sch_1):page107_i296:b" )
			)
			( pin "C2U13.1"
				( objectStatus "@baseboard_fab2_lib.baseboard_fab2(sch_1):page107_i297:a" )
			)
			( pin "C2U13.2"
				( objectStatus "@baseboard_fab2_lib.baseboard_fab2(sch_1):page107_i297:b" )
			)
			( pin "C2U17.1"
				( objectStatus "@baseboard_fab2_lib.baseboard_fab2(sch_1):page107_i300:a" )
			)
			( pin "C2U17.2"
				( objectStatus "@baseboard_fab2_lib.baseboard_fab2(sch_1):page107_i300:b" )
			)
			( pin "C3P12.1"
				( objectStatus "@baseboard_fab2_lib.baseboard_fab2(sch_1):page107_i415:a" )
			)
			( pin "C3P12.2"
				( objectStatus "@baseboard_fab2_lib.baseboard_fab2(sch_1):page107_i415:b" )
			)
			( pin "C3P10.1"
				( objectStatus "@baseboard_fab2_lib.baseboard_fab2(sch_1):page107_i417:a" )
			)
			( pin "C3P10.2"
				( objectStatus "@baseboard_fab2_lib.baseboard_fab2(sch_1):page107_i417:b" )
			)
			( pin "C3P16.1"
				( objectStatus "@baseboard_fab2_lib.baseboard_fab2(sch_1):page107_i422:a" )
			)
			( pin "C3P16.2"
				( objectStatus "@baseboard_fab2_lib.baseboard_fab2(sch_1):page107_i422:b" )
			)
			( pin "C3P21.1"
				( objectStatus "@baseboard_fab2_lib.baseboard_fab2(sch_1):page107_i423:a" )
			)
			( pin "C3P21.2"
				( objectStatus "@baseboard_fab2_lib.baseboard_fab2(sch_1):page107_i423:b" )
			)
			( pin "C3P24.1"
				( objectStatus "@baseboard_fab2_lib.baseboard_fab2(sch_1):page107_i424:a" )
			)
			( pin "C3P24.2"
				( objectStatus "@baseboard_fab2_lib.baseboard_fab2(sch_1):page107_i424:b" )
			)
			( pin "C3P19.1"
				( objectStatus "@baseboard_fab2_lib.baseboard_fab2(sch_1):page107_i427:a" )
			)
			( pin "C3P19.2"
				( objectStatus "@baseboard_fab2_lib.baseboard_fab2(sch_1):page107_i427:b" )
			)
			( pin "C3P14.1"
				( objectStatus "@baseboard_fab2_lib.baseboard_fab2(sch_1):page107_i431:a" )
			)
			( pin "C3P14.2"
				( objectStatus "@baseboard_fab2_lib.baseboard_fab2(sch_1):page107_i431:b" )
			)
			( pin "C3P22.1"
				( objectStatus "@baseboard_fab2_lib.baseboard_fab2(sch_1):page107_i435:a" )
			)
			( pin "C3P22.2"
				( objectStatus "@baseboard_fab2_lib.baseboard_fab2(sch_1):page107_i435:b" )
			)
			( pin "C3P29.1"
				( objectStatus "@baseboard_fab2_lib.baseboard_fab2(sch_1):page107_i437:a" )
			)
			( pin "C3P29.2"
				( objectStatus "@baseboard_fab2_lib.baseboard_fab2(sch_1):page107_i437:b" )
			)
			( pin "C3P36.1"
				( objectStatus "@baseboard_fab2_lib.baseboard_fab2(sch_1):page107_i438:a" )
			)
			( pin "C3P36.2"
				( objectStatus "@baseboard_fab2_lib.baseboard_fab2(sch_1):page107_i438:b" )
			)
			( pin "C3P33.1"
				( objectStatus "@baseboard_fab2_lib.baseboard_fab2(sch_1):page107_i439:a" )
			)
			( pin "C3P33.2"
				( objectStatus "@baseboard_fab2_lib.baseboard_fab2(sch_1):page107_i439:b" )
			)
			( pin "C3P26.1"
				( objectStatus "@baseboard_fab2_lib.baseboard_fab2(sch_1):page107_i444:a" )
			)
			( pin "C3P26.2"
				( objectStatus "@baseboard_fab2_lib.baseboard_fab2(sch_1):page107_i444:b" )
			)
			( pin "C3P34.1"
				( objectStatus "@baseboard_fab2_lib.baseboard_fab2(sch_1):page107_i447:a" )
			)
			( pin "C3P34.2"
				( objectStatus "@baseboard_fab2_lib.baseboard_fab2(sch_1):page107_i447:b" )
			)
			( pin "C3P41.1"
				( objectStatus "@baseboard_fab2_lib.baseboard_fab2(sch_1):page107_i448:a" )
			)
			( pin "C3P41.2"
				( objectStatus "@baseboard_fab2_lib.baseboard_fab2(sch_1):page107_i448:b" )
			)
			( pin "C3P31.1"
				( objectStatus "@baseboard_fab2_lib.baseboard_fab2(sch_1):page107_i452:a" )
			)
			( pin "C3P31.2"
				( objectStatus "@baseboard_fab2_lib.baseboard_fab2(sch_1):page107_i452:b" )
			)
			( pin "C3P38.1"
				( objectStatus "@baseboard_fab2_lib.baseboard_fab2(sch_1):page107_i455:a" )
			)
			( pin "C3P38.2"
				( objectStatus "@baseboard_fab2_lib.baseboard_fab2(sch_1):page107_i455:b" )
			)
			( pin "R2U29.1"
				( objectStatus "@baseboard_fab2_lib.baseboard_fab2(sch_1):page107_i458:a" )
			)
			( pin "R2U29.2"
				( objectStatus "@baseboard_fab2_lib.baseboard_fab2(sch_1):page107_i458:b" )
			)
			( pin "R2U27.1"
				( objectStatus "@baseboard_fab2_lib.baseboard_fab2(sch_1):page107_i459:a" )
			)
			( pin "R2U27.2"
				( objectStatus "@baseboard_fab2_lib.baseboard_fab2(sch_1):page107_i459:b" )
			)
			( pin "R2U25.1"
				( objectStatus "@baseboard_fab2_lib.baseboard_fab2(sch_1):page107_i460:a" )
			)
			( pin "R2U25.2"
				( objectStatus "@baseboard_fab2_lib.baseboard_fab2(sch_1):page107_i460:b" )
			)
			( pin "R2U23.1"
				( objectStatus "@baseboard_fab2_lib.baseboard_fab2(sch_1):page107_i461:a" )
			)
			( pin "R2U23.2"
				( objectStatus "@baseboard_fab2_lib.baseboard_fab2(sch_1):page107_i461:b" )
			)
			( pin "R2U21.1"
				( objectStatus "@baseboard_fab2_lib.baseboard_fab2(sch_1):page107_i462:a" )
			)
			( pin "R2U21.2"
				( objectStatus "@baseboard_fab2_lib.baseboard_fab2(sch_1):page107_i462:b" )
			)
			( pin "R2U19.1"
				( objectStatus "@baseboard_fab2_lib.baseboard_fab2(sch_1):page107_i463:a" )
			)
			( pin "R2U19.2"
				( objectStatus "@baseboard_fab2_lib.baseboard_fab2(sch_1):page107_i463:b" )
			)
			( pin "R2U17.1"
				( objectStatus "@baseboard_fab2_lib.baseboard_fab2(sch_1):page107_i464:a" )
			)
			( pin "R2U17.2"
				( objectStatus "@baseboard_fab2_lib.baseboard_fab2(sch_1):page107_i464:b" )
			)
			( pin "R2U15.1"
				( objectStatus "@baseboard_fab2_lib.baseboard_fab2(sch_1):page107_i465:a" )
			)
			( pin "R2U15.2"
				( objectStatus "@baseboard_fab2_lib.baseboard_fab2(sch_1):page107_i465:b" )
			)
			( pin "R2U14.1"
				( objectStatus "@baseboard_fab2_lib.baseboard_fab2(sch_1):page107_i466:a" )
			)
			( pin "R2U14.2"
				( objectStatus "@baseboard_fab2_lib.baseboard_fab2(sch_1):page107_i466:b" )
			)
			( pin "R2U16.1"
				( objectStatus "@baseboard_fab2_lib.baseboard_fab2(sch_1):page107_i467:a" )
			)
			( pin "R2U16.2"
				( objectStatus "@baseboard_fab2_lib.baseboard_fab2(sch_1):page107_i467:b" )
			)
			( pin "R2U18.1"
				( objectStatus "@baseboard_fab2_lib.baseboard_fab2(sch_1):page107_i468:a" )
			)
			( pin "R2U18.2"
				( objectStatus "@baseboard_fab2_lib.baseboard_fab2(sch_1):page107_i468:b" )
			)
			( pin "R2U20.1"
				( objectStatus "@baseboard_fab2_lib.baseboard_fab2(sch_1):page107_i469:a" )
			)
			( pin "R2U20.2"
				( objectStatus "@baseboard_fab2_lib.baseboard_fab2(sch_1):page107_i469:b" )
			)
			( pin "R2U22.1"
				( objectStatus "@baseboard_fab2_lib.baseboard_fab2(sch_1):page107_i470:a" )
			)
			( pin "R2U22.2"
				( objectStatus "@baseboard_fab2_lib.baseboard_fab2(sch_1):page107_i470:b" )
			)
			( pin "R2U24.1"
				( objectStatus "@baseboard_fab2_lib.baseboard_fab2(sch_1):page107_i471:a" )
			)
			( pin "R2U24.2"
				( objectStatus "@baseboard_fab2_lib.baseboard_fab2(sch_1):page107_i471:b" )
			)
			( pin "R2U26.1"
				( objectStatus "@baseboard_fab2_lib.baseboard_fab2(sch_1):page107_i472:a" )
			)
			( pin "R2U26.2"
				( objectStatus "@baseboard_fab2_lib.baseboard_fab2(sch_1):page107_i472:b" )
			)
			( pin "R2U28.1"
				( objectStatus "@baseboard_fab2_lib.baseboard_fab2(sch_1):page107_i473:a" )
			)
			( pin "R2U28.2"
				( objectStatus "@baseboard_fab2_lib.baseboard_fab2(sch_1):page107_i473:b" )
			)
			( pin "C2U20.1"
				( objectStatus "@baseboard_fab2_lib.baseboard_fab2(sch_1):page108_i1:a" )
			)
			( pin "C2U20.2"
				( objectStatus "@baseboard_fab2_lib.baseboard_fab2(sch_1):page108_i1:b" )
			)
			( pin "C2U24.1"
				( objectStatus "@baseboard_fab2_lib.baseboard_fab2(sch_1):page108_i2:a" )
			)
			( pin "C2U24.2"
				( objectStatus "@baseboard_fab2_lib.baseboard_fab2(sch_1):page108_i2:b" )
			)
			( pin "C2U21.1"
				( objectStatus "@baseboard_fab2_lib.baseboard_fab2(sch_1):page108_i5:a" )
			)
			( pin "C2U21.2"
				( objectStatus "@baseboard_fab2_lib.baseboard_fab2(sch_1):page108_i5:b" )
			)
			( pin "C2U25.1"
				( objectStatus "@baseboard_fab2_lib.baseboard_fab2(sch_1):page108_i7:a" )
			)
			( pin "C2U25.2"
				( objectStatus "@baseboard_fab2_lib.baseboard_fab2(sch_1):page108_i7:b" )
			)
			( pin "R2U37.1"
				( objectStatus "@baseboard_fab2_lib.baseboard_fab2(sch_1):page108_i173:a" )
			)
			( pin "R2U37.2"
				( objectStatus "@baseboard_fab2_lib.baseboard_fab2(sch_1):page108_i173:b" )
			)
			( pin "J8G1.1"
				( objectStatus "@baseboard_fab2_lib.baseboard_fab2(sch_1):page108_i258:io1" )
			)
			( pin "J8G1.2"
				( objectStatus "@baseboard_fab2_lib.baseboard_fab2(sch_1):page108_i258:io2" )
			)
			( pin "J8G1.3"
				( objectStatus "@baseboard_fab2_lib.baseboard_fab2(sch_1):page108_i258:io3" )
			)
			( pin "J8G1.4"
				( objectStatus "@baseboard_fab2_lib.baseboard_fab2(sch_1):page108_i258:io4" )
			)
			( pin "J8G1.5"
				( objectStatus "@baseboard_fab2_lib.baseboard_fab2(sch_1):page108_i258:io5" )
			)
			( pin "J8G1.6"
				( objectStatus "@baseboard_fab2_lib.baseboard_fab2(sch_1):page108_i258:io6" )
			)
			( pin "J8G1.7"
				( objectStatus "@baseboard_fab2_lib.baseboard_fab2(sch_1):page108_i258:io7" )
			)
			( pin "J8G1.8"
				( objectStatus "@baseboard_fab2_lib.baseboard_fab2(sch_1):page108_i258:io8" )
			)
			( pin "J8G1.9"
				( objectStatus "@baseboard_fab2_lib.baseboard_fab2(sch_1):page108_i258:io9" )
			)
			( pin "J8G1.10"
				( objectStatus "@baseboard_fab2_lib.baseboard_fab2(sch_1):page108_i258:io10" )
			)
			( pin "J8G1.11"
				( objectStatus "@baseboard_fab2_lib.baseboard_fab2(sch_1):page108_i258:io11" )
			)
			( pin "J8G1.12"
				( objectStatus "@baseboard_fab2_lib.baseboard_fab2(sch_1):page108_i258:io12" )
			)
			( pin "J8G1.13"
				( objectStatus "@baseboard_fab2_lib.baseboard_fab2(sch_1):page108_i258:io13" )
			)
			( pin "J8G1.14"
				( objectStatus "@baseboard_fab2_lib.baseboard_fab2(sch_1):page108_i258:io14" )
			)
			( pin "J8G1.15"
				( objectStatus "@baseboard_fab2_lib.baseboard_fab2(sch_1):page108_i258:io15" )
			)
			( pin "J8G1.16"
				( objectStatus "@baseboard_fab2_lib.baseboard_fab2(sch_1):page108_i258:io16" )
			)
			( pin "J8G1.17"
				( objectStatus "@baseboard_fab2_lib.baseboard_fab2(sch_1):page108_i258:io17" )
			)
			( pin "J8G1.18"
				( objectStatus "@baseboard_fab2_lib.baseboard_fab2(sch_1):page108_i258:io18" )
			)
			( pin "J8G1.19"
				( objectStatus "@baseboard_fab2_lib.baseboard_fab2(sch_1):page108_i258:io19" )
			)
			( pin "J8G1.20"
				( objectStatus "@baseboard_fab2_lib.baseboard_fab2(sch_1):page108_i258:io20" )
			)
			( pin "J8G1.21"
				( objectStatus "@baseboard_fab2_lib.baseboard_fab2(sch_1):page108_i258:io21" )
			)
			( pin "J8G1.22"
				( objectStatus "@baseboard_fab2_lib.baseboard_fab2(sch_1):page108_i258:io22" )
			)
			( pin "J8G1.23"
				( objectStatus "@baseboard_fab2_lib.baseboard_fab2(sch_1):page108_i258:io23" )
			)
			( pin "J8G1.24"
				( objectStatus "@baseboard_fab2_lib.baseboard_fab2(sch_1):page108_i258:io24" )
			)
			( pin "J8G1.25"
				( objectStatus "@baseboard_fab2_lib.baseboard_fab2(sch_1):page108_i258:io25" )
			)
			( pin "J8G1.26"
				( objectStatus "@baseboard_fab2_lib.baseboard_fab2(sch_1):page108_i258:io26" )
			)
			( pin "J8G1.27"
				( objectStatus "@baseboard_fab2_lib.baseboard_fab2(sch_1):page108_i258:io27" )
			)
			( pin "J8G1.28"
				( objectStatus "@baseboard_fab2_lib.baseboard_fab2(sch_1):page108_i258:io28" )
			)
			( pin "J8G1.29"
				( objectStatus "@baseboard_fab2_lib.baseboard_fab2(sch_1):page108_i258:io29" )
			)
			( pin "J8G1.30"
				( objectStatus "@baseboard_fab2_lib.baseboard_fab2(sch_1):page108_i258:io30" )
			)
			( pin "J8G1.31"
				( objectStatus "@baseboard_fab2_lib.baseboard_fab2(sch_1):page108_i258:io31" )
			)
			( pin "J8G1.32"
				( objectStatus "@baseboard_fab2_lib.baseboard_fab2(sch_1):page108_i258:io32" )
			)
			( pin "J8G1.33"
				( objectStatus "@baseboard_fab2_lib.baseboard_fab2(sch_1):page108_i258:io33" )
			)
			( pin "J8G1.34"
				( objectStatus "@baseboard_fab2_lib.baseboard_fab2(sch_1):page108_i258:io34" )
			)
			( pin "J8G1.35"
				( objectStatus "@baseboard_fab2_lib.baseboard_fab2(sch_1):page108_i258:io35" )
			)
			( pin "J8G1.36"
				( objectStatus "@baseboard_fab2_lib.baseboard_fab2(sch_1):page108_i258:io36" )
			)
			( pin "J8G1.37"
				( objectStatus "@baseboard_fab2_lib.baseboard_fab2(sch_1):page108_i258:io37" )
			)
			( pin "J8G1.38"
				( objectStatus "@baseboard_fab2_lib.baseboard_fab2(sch_1):page108_i258:io38" )
			)
			( pin "J8G1.39"
				( objectStatus "@baseboard_fab2_lib.baseboard_fab2(sch_1):page108_i258:io39" )
			)
			( pin "J8G1.40"
				( objectStatus "@baseboard_fab2_lib.baseboard_fab2(sch_1):page108_i258:io40" )
			)
			( pin "J8G1.41"
				( objectStatus "@baseboard_fab2_lib.baseboard_fab2(sch_1):page108_i258:io41" )
			)
			( pin "J8G1.42"
				( objectStatus "@baseboard_fab2_lib.baseboard_fab2(sch_1):page108_i258:io42" )
			)
			( pin "J8G1.43"
				( objectStatus "@baseboard_fab2_lib.baseboard_fab2(sch_1):page108_i258:io43" )
			)
			( pin "J8G1.44"
				( objectStatus "@baseboard_fab2_lib.baseboard_fab2(sch_1):page108_i258:io44" )
			)
			( pin "J8G1.45"
				( objectStatus "@baseboard_fab2_lib.baseboard_fab2(sch_1):page108_i258:io45" )
			)
			( pin "J8G1.46"
				( objectStatus "@baseboard_fab2_lib.baseboard_fab2(sch_1):page108_i258:io46" )
			)
			( pin "J8G1.47"
				( objectStatus "@baseboard_fab2_lib.baseboard_fab2(sch_1):page108_i258:io47" )
			)
			( pin "J8G1.48"
				( objectStatus "@baseboard_fab2_lib.baseboard_fab2(sch_1):page108_i258:io48" )
			)
			( pin "J8G1.49"
				( objectStatus "@baseboard_fab2_lib.baseboard_fab2(sch_1):page108_i258:io49" )
			)
			( pin "J8G1.50"
				( objectStatus "@baseboard_fab2_lib.baseboard_fab2(sch_1):page108_i258:io50" )
			)
			( pin "J8G1.51"
				( objectStatus "@baseboard_fab2_lib.baseboard_fab2(sch_1):page108_i258:io51" )
			)
			( pin "J8G1.52"
				( objectStatus "@baseboard_fab2_lib.baseboard_fab2(sch_1):page108_i258:io52" )
			)
			( pin "J8G1.53"
				( objectStatus "@baseboard_fab2_lib.baseboard_fab2(sch_1):page108_i258:io53" )
			)
			( pin "J8G1.54"
				( objectStatus "@baseboard_fab2_lib.baseboard_fab2(sch_1):page108_i258:io54" )
			)
			( pin "J8G1.55"
				( objectStatus "@baseboard_fab2_lib.baseboard_fab2(sch_1):page108_i258:io55" )
			)
			( pin "J8G1.56"
				( objectStatus "@baseboard_fab2_lib.baseboard_fab2(sch_1):page108_i258:io56" )
			)
			( pin "J8G1.57"
				( objectStatus "@baseboard_fab2_lib.baseboard_fab2(sch_1):page108_i258:io57" )
			)
			( pin "J8G1.58"
				( objectStatus "@baseboard_fab2_lib.baseboard_fab2(sch_1):page108_i258:io58" )
			)
			( pin "J8G1.59"
				( objectStatus "@baseboard_fab2_lib.baseboard_fab2(sch_1):page108_i258:io59" )
			)
			( pin "J8G1.60"
				( objectStatus "@baseboard_fab2_lib.baseboard_fab2(sch_1):page108_i258:io60" )
			)
			( pin "J8G1.61"
				( objectStatus "@baseboard_fab2_lib.baseboard_fab2(sch_1):page108_i258:io61" )
			)
			( pin "J8G1.62"
				( objectStatus "@baseboard_fab2_lib.baseboard_fab2(sch_1):page108_i258:io62" )
			)
			( pin "J8G1.63"
				( objectStatus "@baseboard_fab2_lib.baseboard_fab2(sch_1):page108_i258:io63" )
			)
			( pin "J8G1.64"
				( objectStatus "@baseboard_fab2_lib.baseboard_fab2(sch_1):page108_i258:io64" )
			)
			( pin "J8G1.65"
				( objectStatus "@baseboard_fab2_lib.baseboard_fab2(sch_1):page108_i258:io65" )
			)
			( pin "J8G1.66"
				( objectStatus "@baseboard_fab2_lib.baseboard_fab2(sch_1):page108_i258:io66" )
			)
			( pin "J8G1.67"
				( objectStatus "@baseboard_fab2_lib.baseboard_fab2(sch_1):page108_i258:io67" )
			)
			( pin "J8G1.68"
				( objectStatus "@baseboard_fab2_lib.baseboard_fab2(sch_1):page108_i258:io68" )
			)
			( pin "J8G1.69"
				( objectStatus "@baseboard_fab2_lib.baseboard_fab2(sch_1):page108_i258:io69" )
			)
			( pin "J8G1.70"
				( objectStatus "@baseboard_fab2_lib.baseboard_fab2(sch_1):page108_i258:io70" )
			)
			( pin "J8G1.71"
				( objectStatus "@baseboard_fab2_lib.baseboard_fab2(sch_1):page108_i258:io71" )
			)
			( pin "J8G1.72"
				( objectStatus "@baseboard_fab2_lib.baseboard_fab2(sch_1):page108_i258:io72" )
			)
			( pin "J8G1.73"
				( objectStatus "@baseboard_fab2_lib.baseboard_fab2(sch_1):page108_i258:io73" )
			)
			( pin "J8G1.74"
				( objectStatus "@baseboard_fab2_lib.baseboard_fab2(sch_1):page108_i258:io74" )
			)
			( pin "J8G1.75"
				( objectStatus "@baseboard_fab2_lib.baseboard_fab2(sch_1):page108_i258:io75" )
			)
			( pin "J8G1.76"
				( objectStatus "@baseboard_fab2_lib.baseboard_fab2(sch_1):page108_i258:io76" )
			)
			( pin "J8G1.77"
				( objectStatus "@baseboard_fab2_lib.baseboard_fab2(sch_1):page108_i258:io77" )
			)
			( pin "J8G1.78"
				( objectStatus "@baseboard_fab2_lib.baseboard_fab2(sch_1):page108_i258:io78" )
			)
			( pin "J8G1.79"
				( objectStatus "@baseboard_fab2_lib.baseboard_fab2(sch_1):page108_i258:io79" )
			)
			( pin "J8G1.80"
				( objectStatus "@baseboard_fab2_lib.baseboard_fab2(sch_1):page108_i258:io80" )
			)
			( pin "J8G1.81"
				( objectStatus "@baseboard_fab2_lib.baseboard_fab2(sch_1):page108_i258:io81" )
			)
			( pin "J8G1.82"
				( objectStatus "@baseboard_fab2_lib.baseboard_fab2(sch_1):page108_i258:io82" )
			)
			( pin "J8G1.83"
				( objectStatus "@baseboard_fab2_lib.baseboard_fab2(sch_1):page108_i258:io83" )
			)
			( pin "J8G1.84"
				( objectStatus "@baseboard_fab2_lib.baseboard_fab2(sch_1):page108_i258:io84" )
			)
			( pin "J8G1.85"
				( objectStatus "@baseboard_fab2_lib.baseboard_fab2(sch_1):page108_i258:io85" )
			)
			( pin "J8G1.86"
				( objectStatus "@baseboard_fab2_lib.baseboard_fab2(sch_1):page108_i258:io86" )
			)
			( pin "J8G1.87"
				( objectStatus "@baseboard_fab2_lib.baseboard_fab2(sch_1):page108_i258:io87" )
			)
			( pin "J8G1.88"
				( objectStatus "@baseboard_fab2_lib.baseboard_fab2(sch_1):page108_i258:io88" )
			)
			( pin "J8G1.89"
				( objectStatus "@baseboard_fab2_lib.baseboard_fab2(sch_1):page108_i258:io89" )
			)
			( pin "J8G1.90"
				( objectStatus "@baseboard_fab2_lib.baseboard_fab2(sch_1):page108_i258:io90" )
			)
			( pin "J8G1.91"
				( objectStatus "@baseboard_fab2_lib.baseboard_fab2(sch_1):page108_i258:io91" )
			)
			( pin "J8G1.92"
				( objectStatus "@baseboard_fab2_lib.baseboard_fab2(sch_1):page108_i258:io92" )
			)
			( pin "J8G1.93"
				( objectStatus "@baseboard_fab2_lib.baseboard_fab2(sch_1):page108_i258:io93" )
			)
			( pin "J8G1.94"
				( objectStatus "@baseboard_fab2_lib.baseboard_fab2(sch_1):page108_i258:io94" )
			)
			( pin "J8G1.95"
				( objectStatus "@baseboard_fab2_lib.baseboard_fab2(sch_1):page108_i258:io95" )
			)
			( pin "J8G1.96"
				( objectStatus "@baseboard_fab2_lib.baseboard_fab2(sch_1):page108_i258:io96" )
			)
			( pin "J8G1.97"
				( objectStatus "@baseboard_fab2_lib.baseboard_fab2(sch_1):page108_i258:io97" )
			)
			( pin "J8G1.98"
				( objectStatus "@baseboard_fab2_lib.baseboard_fab2(sch_1):page108_i258:io98" )
			)
			( pin "J8G1.99"
				( objectStatus "@baseboard_fab2_lib.baseboard_fab2(sch_1):page108_i258:io99" )
			)
			( pin "J8G1.100"
				( objectStatus "@baseboard_fab2_lib.baseboard_fab2(sch_1):page108_i258:io100" )
			)
			( pin "J8G1.MH1"
				( objectStatus "@baseboard_fab2_lib.baseboard_fab2(sch_1):page108_i258:mh1" )
			)
			( pin "J8G1.MH2"
				( objectStatus "@baseboard_fab2_lib.baseboard_fab2(sch_1):page108_i258:mh2" )
			)
			( pin "C2U23.1"
				( objectStatus "@baseboard_fab2_lib.baseboard_fab2(sch_1):page108_i315:a" )
			)
			( pin "C2U23.2"
				( objectStatus "@baseboard_fab2_lib.baseboard_fab2(sch_1):page108_i315:b" )
			)
			( pin "C2U22.1"
				( objectStatus "@baseboard_fab2_lib.baseboard_fab2(sch_1):page108_i318:a" )
			)
			( pin "C2U22.2"
				( objectStatus "@baseboard_fab2_lib.baseboard_fab2(sch_1):page108_i318:b" )
			)
			( pin "R2U35.1"
				( objectStatus "@baseboard_fab2_lib.baseboard_fab2(sch_1):page108_i320:a" )
			)
			( pin "R2U35.2"
				( objectStatus "@baseboard_fab2_lib.baseboard_fab2(sch_1):page108_i320:b" )
			)
			( pin "R2U31.1"
				( objectStatus "@baseboard_fab2_lib.baseboard_fab2(sch_1):page108_i330:a" )
			)
			( pin "R2U31.2"
				( objectStatus "@baseboard_fab2_lib.baseboard_fab2(sch_1):page108_i330:b" )
			)
			( pin "R2U32.1"
				( objectStatus "@baseboard_fab2_lib.baseboard_fab2(sch_1):page108_i339:a" )
			)
			( pin "R2U32.2"
				( objectStatus "@baseboard_fab2_lib.baseboard_fab2(sch_1):page108_i339:b" )
			)
			( pin "R2U36.1"
				( objectStatus "@baseboard_fab2_lib.baseboard_fab2(sch_1):page108_i340:a" )
			)
			( pin "R2U36.2"
				( objectStatus "@baseboard_fab2_lib.baseboard_fab2(sch_1):page108_i340:b" )
			)
			( pin "R7E22.1"
				( objectStatus "@baseboard_fab2_lib.baseboard_fab2(sch_1):page108_i341:a" )
			)
			( pin "R7E22.2"
				( objectStatus "@baseboard_fab2_lib.baseboard_fab2(sch_1):page108_i341:b" )
			)
			( pin "R7E21.1"
				( objectStatus "@baseboard_fab2_lib.baseboard_fab2(sch_1):page108_i343:a" )
			)
			( pin "R7E21.2"
				( objectStatus "@baseboard_fab2_lib.baseboard_fab2(sch_1):page108_i343:b" )
			)
			( pin "TC9F1.1"
				( objectStatus "@baseboard_fab2_lib.baseboard_fab2(sch_1):page110_i1:gnd" )
			)
			( pin "TC9F1.2"
				( objectStatus "@baseboard_fab2_lib.baseboard_fab2(sch_1):page110_i1:io1" )
			)
			( pin "TC9F1.3"
				( objectStatus "@baseboard_fab2_lib.baseboard_fab2(sch_1):page110_i1:io2" )
			)
			( pin "TC1G1.1"
				( objectStatus "@baseboard_fab2_lib.baseboard_fab2(sch_1):page110_i3:gnd" )
			)
			( pin "TC1G1.2"
				( objectStatus "@baseboard_fab2_lib.baseboard_fab2(sch_1):page110_i3:io1" )
			)
			( pin "TC1G1.3"
				( objectStatus "@baseboard_fab2_lib.baseboard_fab2(sch_1):page110_i3:io2" )
			)
			( pin "TC1A1.1"
				( objectStatus "@baseboard_fab2_lib.baseboard_fab2(sch_1):page110_i7:gnd" )
			)
			( pin "TC1A1.2"
				( objectStatus "@baseboard_fab2_lib.baseboard_fab2(sch_1):page110_i7:io1" )
			)
			( pin "TC1A1.3"
				( objectStatus "@baseboard_fab2_lib.baseboard_fab2(sch_1):page110_i7:io2" )
			)
			( pin "TC9A1.1"
				( objectStatus "@baseboard_fab2_lib.baseboard_fab2(sch_1):page110_i9:gnd" )
			)
			( pin "TC9A1.2"
				( objectStatus "@baseboard_fab2_lib.baseboard_fab2(sch_1):page110_i9:io1" )
			)
			( pin "TC9A1.3"
				( objectStatus "@baseboard_fab2_lib.baseboard_fab2(sch_1):page110_i9:io2" )
			)
			( pin "R1L13.1"
				( objectStatus "@baseboard_fab2_lib.baseboard_fab2(sch_1):page111_i6:a" )
			)
			( pin "R1L13.2"
				( objectStatus "@baseboard_fab2_lib.baseboard_fab2(sch_1):page111_i6:b" )
			)
			( pin "C9A2.1"
				( objectStatus "@baseboard_fab2_lib.baseboard_fab2(sch_1):page111_i10:a" )
			)
			( pin "C9A2.2"
				( objectStatus "@baseboard_fab2_lib.baseboard_fab2(sch_1):page111_i10:b" )
			)
			( pin "R9A14.1"
				( objectStatus "@baseboard_fab2_lib.baseboard_fab2(sch_1):page111_i11:a" )
			)
			( pin "R9A14.2"
				( objectStatus "@baseboard_fab2_lib.baseboard_fab2(sch_1):page111_i11:b" )
			)
			( pin "C9A5.1"
				( objectStatus "@baseboard_fab2_lib.baseboard_fab2(sch_1):page111_i12:a" )
			)
			( pin "C9A5.2"
				( objectStatus "@baseboard_fab2_lib.baseboard_fab2(sch_1):page111_i12:b" )
			)
			( pin "R1L23.1"
				( objectStatus "@baseboard_fab2_lib.baseboard_fab2(sch_1):page111_i13:a" )
			)
			( pin "R1L23.2"
				( objectStatus "@baseboard_fab2_lib.baseboard_fab2(sch_1):page111_i13:b" )
			)
			( pin "C1L8.1"
				( objectStatus "@baseboard_fab2_lib.baseboard_fab2(sch_1):page111_i14:a" )
			)
			( pin "C1L8.2"
				( objectStatus "@baseboard_fab2_lib.baseboard_fab2(sch_1):page111_i14:b" )
			)
			( pin "C9A6.1"
				( objectStatus "@baseboard_fab2_lib.baseboard_fab2(sch_1):page111_i25:a" )
			)
			( pin "C9A6.2"
				( objectStatus "@baseboard_fab2_lib.baseboard_fab2(sch_1):page111_i25:b" )
			)
			( pin "J9A3.1"
				( objectStatus "@baseboard_fab2_lib.baseboard_fab2(sch_1):page111_i26:io1" )
			)
			( pin "J9A3.2"
				( objectStatus "@baseboard_fab2_lib.baseboard_fab2(sch_1):page111_i26:io2" )
			)
			( pin "J9A3.3"
				( objectStatus "@baseboard_fab2_lib.baseboard_fab2(sch_1):page111_i26:io3" )
			)
			( pin "J9A3.4"
				( objectStatus "@baseboard_fab2_lib.baseboard_fab2(sch_1):page111_i26:io4" )
			)
			( pin "J9A3.5"
				( objectStatus "@baseboard_fab2_lib.baseboard_fab2(sch_1):page111_i26:io5" )
			)
			( pin "J9A3.6"
				( objectStatus "@baseboard_fab2_lib.baseboard_fab2(sch_1):page111_i26:io6" )
			)
			( pin "J9A3.7"
				( objectStatus "@baseboard_fab2_lib.baseboard_fab2(sch_1):page111_i26:io7" )
			)
			( pin "J9A3.8"
				( objectStatus "@baseboard_fab2_lib.baseboard_fab2(sch_1):page111_i26:io8" )
			)
			( pin "J9A3.9"
				( objectStatus "@baseboard_fab2_lib.baseboard_fab2(sch_1):page111_i26:io9" )
			)
			( pin "J9A3.10"
				( objectStatus "@baseboard_fab2_lib.baseboard_fab2(sch_1):page111_i26:io10" )
			)
			( pin "J9A3.11"
				( objectStatus "@baseboard_fab2_lib.baseboard_fab2(sch_1):page111_i26:io11" )
			)
			( pin "J9A3.12"
				( objectStatus "@baseboard_fab2_lib.baseboard_fab2(sch_1):page111_i26:io12" )
			)
			( pin "J9A3.13"
				( objectStatus "@baseboard_fab2_lib.baseboard_fab2(sch_1):page111_i26:io13" )
			)
			( pin "J9A3.14"
				( objectStatus "@baseboard_fab2_lib.baseboard_fab2(sch_1):page111_i26:io14" )
			)
			( pin "J9A3.15"
				( objectStatus "@baseboard_fab2_lib.baseboard_fab2(sch_1):page111_i26:io15" )
			)
			( pin "J9A3.16"
				( objectStatus "@baseboard_fab2_lib.baseboard_fab2(sch_1):page111_i26:io16" )
			)
			( pin "J9A3.17"
				( objectStatus "@baseboard_fab2_lib.baseboard_fab2(sch_1):page111_i26:io17" )
			)
			( pin "J9A3.18"
				( objectStatus "@baseboard_fab2_lib.baseboard_fab2(sch_1):page111_i26:io18" )
			)
			( pin "J9A3.19"
				( objectStatus "@baseboard_fab2_lib.baseboard_fab2(sch_1):page111_i26:io19" )
			)
			( pin "J9A3.20"
				( objectStatus "@baseboard_fab2_lib.baseboard_fab2(sch_1):page111_i26:io20" )
			)
			( pin "J9A3.21"
				( objectStatus "@baseboard_fab2_lib.baseboard_fab2(sch_1):page111_i26:io21" )
			)
			( pin "J9A3.22"
				( objectStatus "@baseboard_fab2_lib.baseboard_fab2(sch_1):page111_i26:io22" )
			)
			( pin "J9A3.23"
				( objectStatus "@baseboard_fab2_lib.baseboard_fab2(sch_1):page111_i26:io23" )
			)
			( pin "J9A3.24"
				( objectStatus "@baseboard_fab2_lib.baseboard_fab2(sch_1):page111_i26:io24" )
			)
			( pin "J9A3.25"
				( objectStatus "@baseboard_fab2_lib.baseboard_fab2(sch_1):page111_i26:io25" )
			)
			( pin "J9A3.26"
				( objectStatus "@baseboard_fab2_lib.baseboard_fab2(sch_1):page111_i26:io26" )
			)
			( pin "J9A3.27"
				( objectStatus "@baseboard_fab2_lib.baseboard_fab2(sch_1):page111_i26:io27" )
			)
			( pin "J9A3.28"
				( objectStatus "@baseboard_fab2_lib.baseboard_fab2(sch_1):page111_i26:io28" )
			)
			( pin "J9A3.29"
				( objectStatus "@baseboard_fab2_lib.baseboard_fab2(sch_1):page111_i26:io29" )
			)
			( pin "J9A3.30"
				( objectStatus "@baseboard_fab2_lib.baseboard_fab2(sch_1):page111_i26:io30" )
			)
			( pin "J9A3.31"
				( objectStatus "@baseboard_fab2_lib.baseboard_fab2(sch_1):page111_i26:io31" )
			)
			( pin "J9A3.32"
				( objectStatus "@baseboard_fab2_lib.baseboard_fab2(sch_1):page111_i26:io32" )
			)
			( pin "J9A3.33"
				( objectStatus "@baseboard_fab2_lib.baseboard_fab2(sch_1):page111_i26:io33" )
			)
			( pin "J9A3.34"
				( objectStatus "@baseboard_fab2_lib.baseboard_fab2(sch_1):page111_i26:io34" )
			)
			( pin "J9A3.35"
				( objectStatus "@baseboard_fab2_lib.baseboard_fab2(sch_1):page111_i26:io35" )
			)
			( pin "J9A3.36"
				( objectStatus "@baseboard_fab2_lib.baseboard_fab2(sch_1):page111_i26:io36" )
			)
			( pin "J9A3.37"
				( objectStatus "@baseboard_fab2_lib.baseboard_fab2(sch_1):page111_i26:io37" )
			)
			( pin "J9A3.38"
				( objectStatus "@baseboard_fab2_lib.baseboard_fab2(sch_1):page111_i26:io38" )
			)
			( pin "J9A3.39"
				( objectStatus "@baseboard_fab2_lib.baseboard_fab2(sch_1):page111_i26:io39" )
			)
			( pin "J9A3.40"
				( objectStatus "@baseboard_fab2_lib.baseboard_fab2(sch_1):page111_i26:io40" )
			)
			( pin "J9A3.41"
				( objectStatus "@baseboard_fab2_lib.baseboard_fab2(sch_1):page111_i26:io41" )
			)
			( pin "J9A3.42"
				( objectStatus "@baseboard_fab2_lib.baseboard_fab2(sch_1):page111_i26:io42" )
			)
			( pin "J9A3.43"
				( objectStatus "@baseboard_fab2_lib.baseboard_fab2(sch_1):page111_i26:io43" )
			)
			( pin "J9A3.44"
				( objectStatus "@baseboard_fab2_lib.baseboard_fab2(sch_1):page111_i26:io44" )
			)
			( pin "J9A3.45"
				( objectStatus "@baseboard_fab2_lib.baseboard_fab2(sch_1):page111_i26:io45" )
			)
			( pin "J9A3.46"
				( objectStatus "@baseboard_fab2_lib.baseboard_fab2(sch_1):page111_i26:io46" )
			)
			( pin "J9A3.47"
				( objectStatus "@baseboard_fab2_lib.baseboard_fab2(sch_1):page111_i26:io47" )
			)
			( pin "J9A3.48"
				( objectStatus "@baseboard_fab2_lib.baseboard_fab2(sch_1):page111_i26:io48" )
			)
			( pin "J9A3.49"
				( objectStatus "@baseboard_fab2_lib.baseboard_fab2(sch_1):page111_i26:io49" )
			)
			( pin "J9A3.50"
				( objectStatus "@baseboard_fab2_lib.baseboard_fab2(sch_1):page111_i26:io50" )
			)
			( pin "J9A3.51"
				( objectStatus "@baseboard_fab2_lib.baseboard_fab2(sch_1):page111_i26:io51" )
			)
			( pin "J9A3.52"
				( objectStatus "@baseboard_fab2_lib.baseboard_fab2(sch_1):page111_i26:io52" )
			)
			( pin "J9A3.53"
				( objectStatus "@baseboard_fab2_lib.baseboard_fab2(sch_1):page111_i26:io53" )
			)
			( pin "J9A3.54"
				( objectStatus "@baseboard_fab2_lib.baseboard_fab2(sch_1):page111_i26:io54" )
			)
			( pin "J9A3.55"
				( objectStatus "@baseboard_fab2_lib.baseboard_fab2(sch_1):page111_i26:io55" )
			)
			( pin "J9A3.56"
				( objectStatus "@baseboard_fab2_lib.baseboard_fab2(sch_1):page111_i26:io56" )
			)
			( pin "J9A3.57"
				( objectStatus "@baseboard_fab2_lib.baseboard_fab2(sch_1):page111_i26:io57" )
			)
			( pin "J9A3.58"
				( objectStatus "@baseboard_fab2_lib.baseboard_fab2(sch_1):page111_i26:io58" )
			)
			( pin "J9A3.59"
				( objectStatus "@baseboard_fab2_lib.baseboard_fab2(sch_1):page111_i26:io59" )
			)
			( pin "J9A3.60"
				( objectStatus "@baseboard_fab2_lib.baseboard_fab2(sch_1):page111_i26:io60" )
			)
			( pin "C1L5.1"
				( objectStatus "@baseboard_fab2_lib.baseboard_fab2(sch_1):page111_i30:a" )
			)
			( pin "C1L5.2"
				( objectStatus "@baseboard_fab2_lib.baseboard_fab2(sch_1):page111_i30:b" )
			)
			( pin "R2P2.1"
				( objectStatus "@baseboard_fab2_lib.baseboard_fab2(sch_1):page111_i37:a" )
			)
			( pin "R2P2.2"
				( objectStatus "@baseboard_fab2_lib.baseboard_fab2(sch_1):page111_i37:b" )
			)
			( pin "R9A4.1"
				( objectStatus "@baseboard_fab2_lib.baseboard_fab2(sch_1):page111_i55:a" )
			)
			( pin "R9A4.2"
				( objectStatus "@baseboard_fab2_lib.baseboard_fab2(sch_1):page111_i55:b" )
			)
			( pin "R1L17.1"
				( objectStatus "@baseboard_fab2_lib.baseboard_fab2(sch_1):page111_i56:a" )
			)
			( pin "R1L17.2"
				( objectStatus "@baseboard_fab2_lib.baseboard_fab2(sch_1):page111_i56:b" )
			)
			( pin "R9A17.1"
				( objectStatus "@baseboard_fab2_lib.baseboard_fab2(sch_1):page111_i57:a" )
			)
			( pin "R9A17.2"
				( objectStatus "@baseboard_fab2_lib.baseboard_fab2(sch_1):page111_i57:b" )
			)
			( pin "C9A4.1"
				( objectStatus "@baseboard_fab2_lib.baseboard_fab2(sch_1):page111_i59:a" )
			)
			( pin "C9A4.2"
				( objectStatus "@baseboard_fab2_lib.baseboard_fab2(sch_1):page111_i59:b" )
			)
			( pin "R9A15.1"
				( objectStatus "@baseboard_fab2_lib.baseboard_fab2(sch_1):page111_i60:a" )
			)
			( pin "R9A15.2"
				( objectStatus "@baseboard_fab2_lib.baseboard_fab2(sch_1):page111_i60:b" )
			)
			( pin "R1L28.1"
				( objectStatus "@baseboard_fab2_lib.baseboard_fab2(sch_1):page111_i66:a" )
			)
			( pin "R1L28.2"
				( objectStatus "@baseboard_fab2_lib.baseboard_fab2(sch_1):page111_i66:b" )
			)
			( pin "R1L29.1"
				( objectStatus "@baseboard_fab2_lib.baseboard_fab2(sch_1):page111_i68:a" )
			)
			( pin "R1L29.2"
				( objectStatus "@baseboard_fab2_lib.baseboard_fab2(sch_1):page111_i68:b" )
			)
			( pin "R9A3.1"
				( objectStatus "@baseboard_fab2_lib.baseboard_fab2(sch_1):page111_i74:a" )
			)
			( pin "R9A3.2"
				( objectStatus "@baseboard_fab2_lib.baseboard_fab2(sch_1):page111_i74:b" )
			)
			( pin "R9A2.1"
				( objectStatus "@baseboard_fab2_lib.baseboard_fab2(sch_1):page111_i83:a" )
			)
			( pin "R9A2.2"
				( objectStatus "@baseboard_fab2_lib.baseboard_fab2(sch_1):page111_i83:b" )
			)
			( pin "U1L4.2"
				( objectStatus "@baseboard_fab2_lib.baseboard_fab2(sch_1):page111_i85:a" )
			)
			( pin "U1L4.4"
				( objectStatus "@baseboard_fab2_lib.baseboard_fab2(sch_1):page111_i85:y" )
			)
			( pin "C1L11.1"
				( objectStatus "@baseboard_fab2_lib.baseboard_fab2(sch_1):page111_i87:a" )
			)
			( pin "C1L11.2"
				( objectStatus "@baseboard_fab2_lib.baseboard_fab2(sch_1):page111_i87:b" )
			)
			( pin "R8E2.1"
				( objectStatus "@baseboard_fab2_lib.baseboard_fab2(sch_1):page111_i89:a" )
			)
			( pin "R8E2.2"
				( objectStatus "@baseboard_fab2_lib.baseboard_fab2(sch_1):page111_i89:b" )
			)
			( pin "Q9A1.2"
				( objectStatus "@baseboard_fab2_lib.baseboard_fab2(sch_1):page111_i93:b(0)" )
			)
			( pin "Q9A1.6"
				( objectStatus "@baseboard_fab2_lib.baseboard_fab2(sch_1):page111_i93:c(0)" )
			)
			( pin "Q9A1.1"
				( objectStatus "@baseboard_fab2_lib.baseboard_fab2(sch_1):page111_i93:e(0)" )
			)
			( pin "Q9A1.5"
				( objectStatus "@baseboard_fab2_lib.baseboard_fab2(sch_1):page111_i94:b(0)" )
			)
			( pin "Q9A1.3"
				( objectStatus "@baseboard_fab2_lib.baseboard_fab2(sch_1):page111_i94:c(0)" )
			)
			( pin "Q9A1.4"
				( objectStatus "@baseboard_fab2_lib.baseboard_fab2(sch_1):page111_i94:e(0)" )
			)
			( pin "R9A1.1"
				( objectStatus "@baseboard_fab2_lib.baseboard_fab2(sch_1):page111_i95:a" )
			)
			( pin "R9A1.2"
				( objectStatus "@baseboard_fab2_lib.baseboard_fab2(sch_1):page111_i95:b" )
			)
			( pin "U1M7.4"
				( objectStatus "@baseboard_fab2_lib.baseboard_fab2(sch_1):page112_i40:a" )
			)
			( pin "U1M7.3"
				( objectStatus "@baseboard_fab2_lib.baseboard_fab2(sch_1):page112_i40:b0" )
			)
			( pin "U1M7.1"
				( objectStatus "@baseboard_fab2_lib.baseboard_fab2(sch_1):page112_i40:b1" )
			)
			( pin "U1M7.2"
				( objectStatus "@baseboard_fab2_lib.baseboard_fab2(sch_1):page112_i40:gnd" )
			)
			( pin "U1M7.6"
				( objectStatus "@baseboard_fab2_lib.baseboard_fab2(sch_1):page112_i40:s" )
			)
			( pin "U1M7.5"
				( objectStatus "@baseboard_fab2_lib.baseboard_fab2(sch_1):page112_i40:vcc" )
			)
			( pin "C1M36.1"
				( objectStatus "@baseboard_fab2_lib.baseboard_fab2(sch_1):page112_i42:a" )
			)
			( pin "C1M36.2"
				( objectStatus "@baseboard_fab2_lib.baseboard_fab2(sch_1):page112_i42:b" )
			)
			( pin "C1M37.1"
				( objectStatus "@baseboard_fab2_lib.baseboard_fab2(sch_1):page112_i47:a" )
			)
			( pin "C1M37.2"
				( objectStatus "@baseboard_fab2_lib.baseboard_fab2(sch_1):page112_i47:b" )
			)
			( pin "R6P46.1"
				( objectStatus "@baseboard_fab2_lib.baseboard_fab2(sch_1):page112_i49:a" )
			)
			( pin "R6P46.2"
				( objectStatus "@baseboard_fab2_lib.baseboard_fab2(sch_1):page112_i49:b" )
			)
			( pin "R7P30.1"
				( objectStatus "@baseboard_fab2_lib.baseboard_fab2(sch_1):page112_i50:a" )
			)
			( pin "R7P30.2"
				( objectStatus "@baseboard_fab2_lib.baseboard_fab2(sch_1):page112_i50:b" )
			)
			( pin "R1M3.1"
				( objectStatus "@baseboard_fab2_lib.baseboard_fab2(sch_1):page112_i51:a" )
			)
			( pin "R1M3.2"
				( objectStatus "@baseboard_fab2_lib.baseboard_fab2(sch_1):page112_i51:b" )
			)
			( pin "R4P15.1"
				( objectStatus "@baseboard_fab2_lib.baseboard_fab2(sch_1):page112_i53:a" )
			)
			( pin "R4P15.2"
				( objectStatus "@baseboard_fab2_lib.baseboard_fab2(sch_1):page112_i53:b" )
			)
			( pin "R1M4.1"
				( objectStatus "@baseboard_fab2_lib.baseboard_fab2(sch_1):page112_i54:a" )
			)
			( pin "R1M4.2"
				( objectStatus "@baseboard_fab2_lib.baseboard_fab2(sch_1):page112_i54:b" )
			)
			( pin "R6T7.1"
				( objectStatus "@baseboard_fab2_lib.baseboard_fab2(sch_1):page112_i55:a" )
			)
			( pin "R6T7.2"
				( objectStatus "@baseboard_fab2_lib.baseboard_fab2(sch_1):page112_i55:b" )
			)
			( pin "R6T6.1"
				( objectStatus "@baseboard_fab2_lib.baseboard_fab2(sch_1):page112_i56:a" )
			)
			( pin "R6T6.2"
				( objectStatus "@baseboard_fab2_lib.baseboard_fab2(sch_1):page112_i56:b" )
			)
			( pin "R4P12.1"
				( objectStatus "@baseboard_fab2_lib.baseboard_fab2(sch_1):page112_i57:a" )
			)
			( pin "R4P12.2"
				( objectStatus "@baseboard_fab2_lib.baseboard_fab2(sch_1):page112_i57:b" )
			)
			( pin "R4P23.1"
				( objectStatus "@baseboard_fab2_lib.baseboard_fab2(sch_1):page112_i58:a" )
			)
			( pin "R4P23.2"
				( objectStatus "@baseboard_fab2_lib.baseboard_fab2(sch_1):page112_i58:b" )
			)
			( pin "R4P24.1"
				( objectStatus "@baseboard_fab2_lib.baseboard_fab2(sch_1):page112_i59:a" )
			)
			( pin "R4P24.2"
				( objectStatus "@baseboard_fab2_lib.baseboard_fab2(sch_1):page112_i59:b" )
			)
			( pin "R1L15.1"
				( objectStatus "@baseboard_fab2_lib.baseboard_fab2(sch_1):page112_i60:a" )
			)
			( pin "R1L15.2"
				( objectStatus "@baseboard_fab2_lib.baseboard_fab2(sch_1):page112_i60:b" )
			)
			( pin "R7P29.1"
				( objectStatus "@baseboard_fab2_lib.baseboard_fab2(sch_1):page112_i61:a" )
			)
			( pin "R7P29.2"
				( objectStatus "@baseboard_fab2_lib.baseboard_fab2(sch_1):page112_i61:b" )
			)
			( pin "R6T5.1"
				( objectStatus "@baseboard_fab2_lib.baseboard_fab2(sch_1):page112_i62:a" )
			)
			( pin "R6T5.2"
				( objectStatus "@baseboard_fab2_lib.baseboard_fab2(sch_1):page112_i62:b" )
			)
			( pin "R1L39.1"
				( objectStatus "@baseboard_fab2_lib.baseboard_fab2(sch_1):page112_i76:a" )
			)
			( pin "R1L39.2"
				( objectStatus "@baseboard_fab2_lib.baseboard_fab2(sch_1):page112_i76:b" )
			)
			( pin "R1L41.1"
				( objectStatus "@baseboard_fab2_lib.baseboard_fab2(sch_1):page112_i77:a" )
			)
			( pin "R1L41.2"
				( objectStatus "@baseboard_fab2_lib.baseboard_fab2(sch_1):page112_i77:b" )
			)
			( pin "R9A11.1"
				( objectStatus "@baseboard_fab2_lib.baseboard_fab2(sch_1):page112_i78:a" )
			)
			( pin "R9A11.2"
				( objectStatus "@baseboard_fab2_lib.baseboard_fab2(sch_1):page112_i78:b" )
			)
			( pin "R8A13.1"
				( objectStatus "@baseboard_fab2_lib.baseboard_fab2(sch_1):page112_i79:a" )
			)
			( pin "R8A13.2"
				( objectStatus "@baseboard_fab2_lib.baseboard_fab2(sch_1):page112_i79:b" )
			)
			( pin "R8A14.1"
				( objectStatus "@baseboard_fab2_lib.baseboard_fab2(sch_1):page112_i80:a" )
			)
			( pin "R8A14.2"
				( objectStatus "@baseboard_fab2_lib.baseboard_fab2(sch_1):page112_i80:b" )
			)
			( pin "R3M10.1"
				( objectStatus "@baseboard_fab2_lib.baseboard_fab2(sch_1):page112_i85:a" )
			)
			( pin "R3M10.2"
				( objectStatus "@baseboard_fab2_lib.baseboard_fab2(sch_1):page112_i85:b" )
			)
			( pin "R8B2.1"
				( objectStatus "@baseboard_fab2_lib.baseboard_fab2(sch_1):page112_i94:a" )
			)
			( pin "R8B2.2"
				( objectStatus "@baseboard_fab2_lib.baseboard_fab2(sch_1):page112_i94:b" )
			)
			( pin "R8B1.1"
				( objectStatus "@baseboard_fab2_lib.baseboard_fab2(sch_1):page112_i95:a" )
			)
			( pin "R8B1.2"
				( objectStatus "@baseboard_fab2_lib.baseboard_fab2(sch_1):page112_i95:b" )
			)
			( pin "U1L1.12"
				( objectStatus "@baseboard_fab2_lib.baseboard_fab2(sch_1):page112_i108:a(0)" )
			)
			( pin "U1L1.9"
				( objectStatus "@baseboard_fab2_lib.baseboard_fab2(sch_1):page112_i108:a(1)" )
			)
			( pin "U1L1.5"
				( objectStatus "@baseboard_fab2_lib.baseboard_fab2(sch_1):page112_i108:a(2)" )
			)
			( pin "U1L1.2"
				( objectStatus "@baseboard_fab2_lib.baseboard_fab2(sch_1):page112_i108:a(3)" )
			)
			( pin "U1L1.11"
				( objectStatus "@baseboard_fab2_lib.baseboard_fab2(sch_1):page112_i108:b(0)" )
			)
			( pin "U1L1.8"
				( objectStatus "@baseboard_fab2_lib.baseboard_fab2(sch_1):page112_i108:b(1)" )
			)
			( pin "U1L1.6"
				( objectStatus "@baseboard_fab2_lib.baseboard_fab2(sch_1):page112_i108:b(2)" )
			)
			( pin "U1L1.3"
				( objectStatus "@baseboard_fab2_lib.baseboard_fab2(sch_1):page112_i108:b(3)" )
			)
			( pin "U1L1.13"
				( objectStatus "@baseboard_fab2_lib.baseboard_fab2(sch_1):page112_i108:oe(0)" )
			)
			( pin "U1L1.10"
				( objectStatus "@baseboard_fab2_lib.baseboard_fab2(sch_1):page112_i108:oe(1)" )
			)
			( pin "U1L1.4"
				( objectStatus "@baseboard_fab2_lib.baseboard_fab2(sch_1):page112_i108:oe(2)" )
			)
			( pin "U1L1.1"
				( objectStatus "@baseboard_fab2_lib.baseboard_fab2(sch_1):page112_i108:oe(3)" )
			)
			( pin "U1L5.12"
				( objectStatus "@baseboard_fab2_lib.baseboard_fab2(sch_1):page112_i109:a(0)" )
			)
			( pin "U1L5.9"
				( objectStatus "@baseboard_fab2_lib.baseboard_fab2(sch_1):page112_i109:a(1)" )
			)
			( pin "U1L5.5"
				( objectStatus "@baseboard_fab2_lib.baseboard_fab2(sch_1):page112_i109:a(2)" )
			)
			( pin "U1L5.2"
				( objectStatus "@baseboard_fab2_lib.baseboard_fab2(sch_1):page112_i109:a(3)" )
			)
			( pin "U1L5.11"
				( objectStatus "@baseboard_fab2_lib.baseboard_fab2(sch_1):page112_i109:b(0)" )
			)
			( pin "U1L5.8"
				( objectStatus "@baseboard_fab2_lib.baseboard_fab2(sch_1):page112_i109:b(1)" )
			)
			( pin "U1L5.6"
				( objectStatus "@baseboard_fab2_lib.baseboard_fab2(sch_1):page112_i109:b(2)" )
			)
			( pin "U1L5.3"
				( objectStatus "@baseboard_fab2_lib.baseboard_fab2(sch_1):page112_i109:b(3)" )
			)
			( pin "U1L5.13"
				( objectStatus "@baseboard_fab2_lib.baseboard_fab2(sch_1):page112_i109:oe(0)" )
			)
			( pin "U1L5.10"
				( objectStatus "@baseboard_fab2_lib.baseboard_fab2(sch_1):page112_i109:oe(1)" )
			)
			( pin "U1L5.4"
				( objectStatus "@baseboard_fab2_lib.baseboard_fab2(sch_1):page112_i109:oe(2)" )
			)
			( pin "U1L5.1"
				( objectStatus "@baseboard_fab2_lib.baseboard_fab2(sch_1):page112_i109:oe(3)" )
			)
			( pin "R6T9.1"
				( objectStatus "@baseboard_fab2_lib.baseboard_fab2(sch_1):page112_i120:a" )
			)
			( pin "R6T9.2"
				( objectStatus "@baseboard_fab2_lib.baseboard_fab2(sch_1):page112_i120:b" )
			)
			( pin "R6T8.1"
				( objectStatus "@baseboard_fab2_lib.baseboard_fab2(sch_1):page112_i121:a" )
			)
			( pin "R6T8.2"
				( objectStatus "@baseboard_fab2_lib.baseboard_fab2(sch_1):page112_i121:b" )
			)
			( pin "U1M4.2"
				( objectStatus "@baseboard_fab2_lib.baseboard_fab2(sch_1):page112_i127:a" )
			)
			( pin "U1M4.4"
				( objectStatus "@baseboard_fab2_lib.baseboard_fab2(sch_1):page112_i127:b" )
			)
			( pin "U1M4.1"
				( objectStatus "@baseboard_fab2_lib.baseboard_fab2(sch_1):page112_i127:oe_n" )
			)
			( pin "C1M30.1"
				( objectStatus "@baseboard_fab2_lib.baseboard_fab2(sch_1):page112_i131:a" )
			)
			( pin "C1M30.2"
				( objectStatus "@baseboard_fab2_lib.baseboard_fab2(sch_1):page112_i131:b" )
			)
			( pin "C1L1.1"
				( objectStatus "@baseboard_fab2_lib.baseboard_fab2(sch_1):page112_i136:a" )
			)
			( pin "C1L1.2"
				( objectStatus "@baseboard_fab2_lib.baseboard_fab2(sch_1):page112_i136:b" )
			)
			( pin "C1L19.1"
				( objectStatus "@baseboard_fab2_lib.baseboard_fab2(sch_1):page112_i140:a" )
			)
			( pin "C1L19.2"
				( objectStatus "@baseboard_fab2_lib.baseboard_fab2(sch_1):page112_i140:b" )
			)
			( pin "U1M2.4"
				( objectStatus "@baseboard_fab2_lib.baseboard_fab2(sch_1):page113_i107:a" )
			)
			( pin "U1M2.3"
				( objectStatus "@baseboard_fab2_lib.baseboard_fab2(sch_1):page113_i107:b0" )
			)
			( pin "U1M2.1"
				( objectStatus "@baseboard_fab2_lib.baseboard_fab2(sch_1):page113_i107:b1" )
			)
			( pin "U1M2.2"
				( objectStatus "@baseboard_fab2_lib.baseboard_fab2(sch_1):page113_i107:gnd" )
			)
			( pin "U1M2.6"
				( objectStatus "@baseboard_fab2_lib.baseboard_fab2(sch_1):page113_i107:s" )
			)
			( pin "U1M2.5"
				( objectStatus "@baseboard_fab2_lib.baseboard_fab2(sch_1):page113_i107:vcc" )
			)
			( pin "C1M31.1"
				( objectStatus "@baseboard_fab2_lib.baseboard_fab2(sch_1):page113_i116:a" )
			)
			( pin "C1M31.2"
				( objectStatus "@baseboard_fab2_lib.baseboard_fab2(sch_1):page113_i116:b" )
			)
			( pin "C1M32.1"
				( objectStatus "@baseboard_fab2_lib.baseboard_fab2(sch_1):page113_i117:a" )
			)
			( pin "C1M32.2"
				( objectStatus "@baseboard_fab2_lib.baseboard_fab2(sch_1):page113_i117:b" )
			)
			( pin "C1M28.1"
				( objectStatus "@baseboard_fab2_lib.baseboard_fab2(sch_1):page113_i119:a" )
			)
			( pin "C1M28.2"
				( objectStatus "@baseboard_fab2_lib.baseboard_fab2(sch_1):page113_i119:b" )
			)
			( pin "U1M6.2"
				( objectStatus "@baseboard_fab2_lib.baseboard_fab2(sch_1):page113_i127:a" )
			)
			( pin "U1M6.4"
				( objectStatus "@baseboard_fab2_lib.baseboard_fab2(sch_1):page113_i127:b" )
			)
			( pin "U1M6.1"
				( objectStatus "@baseboard_fab2_lib.baseboard_fab2(sch_1):page113_i127:oe_n" )
			)
			( pin "R4R6.1"
				( objectStatus "@baseboard_fab2_lib.baseboard_fab2(sch_1):page113_i134:a" )
			)
			( pin "R4R6.2"
				( objectStatus "@baseboard_fab2_lib.baseboard_fab2(sch_1):page113_i134:b" )
			)
			( pin "C1M29.1"
				( objectStatus "@baseboard_fab2_lib.baseboard_fab2(sch_1):page113_i147:a" )
			)
			( pin "C1M29.2"
				( objectStatus "@baseboard_fab2_lib.baseboard_fab2(sch_1):page113_i147:b" )
			)
			( pin "R9B14.1"
				( objectStatus "@baseboard_fab2_lib.baseboard_fab2(sch_1):page113_i168:a" )
			)
			( pin "R9B14.2"
				( objectStatus "@baseboard_fab2_lib.baseboard_fab2(sch_1):page113_i168:b" )
			)
			( pin "J9B4.1"
				( objectStatus "@baseboard_fab2_lib.baseboard_fab2(sch_1):page113_i175:io1" )
			)
			( pin "J9B4.2"
				( objectStatus "@baseboard_fab2_lib.baseboard_fab2(sch_1):page113_i175:io2" )
			)
			( pin "J9B4.3"
				( objectStatus "@baseboard_fab2_lib.baseboard_fab2(sch_1):page113_i175:io3" )
			)
			( pin "J9B4.4"
				( objectStatus "@baseboard_fab2_lib.baseboard_fab2(sch_1):page113_i175:io4" )
			)
			( pin "J9B4.5"
				( objectStatus "@baseboard_fab2_lib.baseboard_fab2(sch_1):page113_i175:io5" )
			)
			( pin "J9B4.6"
				( objectStatus "@baseboard_fab2_lib.baseboard_fab2(sch_1):page113_i175:io6" )
			)
			( pin "J9B4.7"
				( objectStatus "@baseboard_fab2_lib.baseboard_fab2(sch_1):page113_i175:io7" )
			)
			( pin "J9B4.8"
				( objectStatus "@baseboard_fab2_lib.baseboard_fab2(sch_1):page113_i175:io8" )
			)
			( pin "J9B4.9"
				( objectStatus "@baseboard_fab2_lib.baseboard_fab2(sch_1):page113_i175:io9" )
			)
			( pin "J9B4.10"
				( objectStatus "@baseboard_fab2_lib.baseboard_fab2(sch_1):page113_i175:io10" )
			)
			( pin "R9B9.1"
				( objectStatus "@baseboard_fab2_lib.baseboard_fab2(sch_1):page113_i179:a" )
			)
			( pin "R9B9.2"
				( objectStatus "@baseboard_fab2_lib.baseboard_fab2(sch_1):page113_i179:b" )
			)
			( pin "R9B10.1"
				( objectStatus "@baseboard_fab2_lib.baseboard_fab2(sch_1):page113_i180:a" )
			)
			( pin "R9B10.2"
				( objectStatus "@baseboard_fab2_lib.baseboard_fab2(sch_1):page113_i180:b" )
			)
			( pin "U9A5.2"
				( objectStatus "@baseboard_fab2_lib.baseboard_fab2(sch_1):page113_i185:a" )
			)
			( pin "U9A5.4"
				( objectStatus "@baseboard_fab2_lib.baseboard_fab2(sch_1):page113_i185:b" )
			)
			( pin "U9A5.1"
				( objectStatus "@baseboard_fab2_lib.baseboard_fab2(sch_1):page113_i185:oe_n" )
			)
			( pin "R6M8.1"
				( objectStatus "@baseboard_fab2_lib.baseboard_fab2(sch_1):page113_i188:a" )
			)
			( pin "R6M8.2"
				( objectStatus "@baseboard_fab2_lib.baseboard_fab2(sch_1):page113_i188:b" )
			)
			( pin "U6M1.2"
				( objectStatus "@baseboard_fab2_lib.baseboard_fab2(sch_1):page113_i190:a" )
			)
			( pin "U6M1.4"
				( objectStatus "@baseboard_fab2_lib.baseboard_fab2(sch_1):page113_i190:b" )
			)
			( pin "U6M1.1"
				( objectStatus "@baseboard_fab2_lib.baseboard_fab2(sch_1):page113_i190:oe_n" )
			)
			( pin "R1M22.1"
				( objectStatus "@baseboard_fab2_lib.baseboard_fab2(sch_1):page113_i195:a" )
			)
			( pin "R1M22.2"
				( objectStatus "@baseboard_fab2_lib.baseboard_fab2(sch_1):page113_i195:b" )
			)
			( pin "U1M5.2"
				( objectStatus "@baseboard_fab2_lib.baseboard_fab2(sch_1):page113_i196:a" )
			)
			( pin "U1M5.4"
				( objectStatus "@baseboard_fab2_lib.baseboard_fab2(sch_1):page113_i196:b" )
			)
			( pin "U1M5.1"
				( objectStatus "@baseboard_fab2_lib.baseboard_fab2(sch_1):page113_i196:oe_n" )
			)
			( pin "R1M23.1"
				( objectStatus "@baseboard_fab2_lib.baseboard_fab2(sch_1):page113_i199:a" )
			)
			( pin "R1M23.2"
				( objectStatus "@baseboard_fab2_lib.baseboard_fab2(sch_1):page113_i199:b" )
			)
			( pin "R1M19.1"
				( objectStatus "@baseboard_fab2_lib.baseboard_fab2(sch_1):page113_i202:a" )
			)
			( pin "R1M19.2"
				( objectStatus "@baseboard_fab2_lib.baseboard_fab2(sch_1):page113_i202:b" )
			)
			( pin "R9B12.1"
				( objectStatus "@baseboard_fab2_lib.baseboard_fab2(sch_1):page113_i203:a" )
			)
			( pin "R9B12.2"
				( objectStatus "@baseboard_fab2_lib.baseboard_fab2(sch_1):page113_i203:b" )
			)
			( pin "R1M20.1"
				( objectStatus "@baseboard_fab2_lib.baseboard_fab2(sch_1):page113_i204:a" )
			)
			( pin "R1M20.2"
				( objectStatus "@baseboard_fab2_lib.baseboard_fab2(sch_1):page113_i204:b" )
			)
			( pin "R1M21.1"
				( objectStatus "@baseboard_fab2_lib.baseboard_fab2(sch_1):page113_i205:a" )
			)
			( pin "R1M21.2"
				( objectStatus "@baseboard_fab2_lib.baseboard_fab2(sch_1):page113_i205:b" )
			)
			( pin "U4R1.2"
				( objectStatus "@baseboard_fab2_lib.baseboard_fab2(sch_1):page113_i206:a" )
			)
			( pin "U4R1.4"
				( objectStatus "@baseboard_fab2_lib.baseboard_fab2(sch_1):page113_i206:b" )
			)
			( pin "U4R1.1"
				( objectStatus "@baseboard_fab2_lib.baseboard_fab2(sch_1):page113_i206:oe_n" )
			)
			( pin "R9B11.1"
				( objectStatus "@baseboard_fab2_lib.baseboard_fab2(sch_1):page113_i239:a" )
			)
			( pin "R9B11.2"
				( objectStatus "@baseboard_fab2_lib.baseboard_fab2(sch_1):page113_i239:b" )
			)
			( pin "R9B13.1"
				( objectStatus "@baseboard_fab2_lib.baseboard_fab2(sch_1):page113_i240:a" )
			)
			( pin "R9B13.2"
				( objectStatus "@baseboard_fab2_lib.baseboard_fab2(sch_1):page113_i240:b" )
			)
			( pin "C4R2.1"
				( objectStatus "@baseboard_fab2_lib.baseboard_fab2(sch_1):page113_i246:a" )
			)
			( pin "C4R2.2"
				( objectStatus "@baseboard_fab2_lib.baseboard_fab2(sch_1):page113_i246:b" )
			)
			( pin "C1M33.1"
				( objectStatus "@baseboard_fab2_lib.baseboard_fab2(sch_1):page113_i248:a" )
			)
			( pin "C1M33.2"
				( objectStatus "@baseboard_fab2_lib.baseboard_fab2(sch_1):page113_i248:b" )
			)
			( pin "C6M6.1"
				( objectStatus "@baseboard_fab2_lib.baseboard_fab2(sch_1):page113_i250:a" )
			)
			( pin "C6M6.2"
				( objectStatus "@baseboard_fab2_lib.baseboard_fab2(sch_1):page113_i250:b" )
			)
			( pin "U2M1.4"
				( objectStatus "@baseboard_fab2_lib.baseboard_fab2(sch_1):page113_i255:a" )
			)
			( pin "U2M1.3"
				( objectStatus "@baseboard_fab2_lib.baseboard_fab2(sch_1):page113_i255:b0" )
			)
			( pin "U2M1.1"
				( objectStatus "@baseboard_fab2_lib.baseboard_fab2(sch_1):page113_i255:b1" )
			)
			( pin "U2M1.2"
				( objectStatus "@baseboard_fab2_lib.baseboard_fab2(sch_1):page113_i255:gnd" )
			)
			( pin "U2M1.6"
				( objectStatus "@baseboard_fab2_lib.baseboard_fab2(sch_1):page113_i255:s" )
			)
			( pin "U2M1.5"
				( objectStatus "@baseboard_fab2_lib.baseboard_fab2(sch_1):page113_i255:vcc" )
			)
			( pin "C1M34.1"
				( objectStatus "@baseboard_fab2_lib.baseboard_fab2(sch_1):page113_i265:a" )
			)
			( pin "C1M34.2"
				( objectStatus "@baseboard_fab2_lib.baseboard_fab2(sch_1):page113_i265:b" )
			)
			( pin "C1M35.1"
				( objectStatus "@baseboard_fab2_lib.baseboard_fab2(sch_1):page113_i266:a" )
			)
			( pin "C1M35.2"
				( objectStatus "@baseboard_fab2_lib.baseboard_fab2(sch_1):page113_i266:b" )
			)
			( pin "C1L20.1"
				( objectStatus "@baseboard_fab2_lib.baseboard_fab2(sch_1):page113_i267:a" )
			)
			( pin "C1L20.2"
				( objectStatus "@baseboard_fab2_lib.baseboard_fab2(sch_1):page113_i267:b" )
			)
			( pin "U7C1.A39"
				( objectStatus "@baseboard_fab2_lib.baseboard_fab2(sch_1):page114_i40:clkout_itpxdpn" )
			)
			( pin "U7C1.C39"
				( objectStatus "@baseboard_fab2_lib.baseboard_fab2(sch_1):page114_i40:clkout_itpxdpp" )
			)
			( pin "U7C1.A32"
				( objectStatus "@baseboard_fab2_lib.baseboard_fab2(sch_1):page114_i40:clkout_nssccap0n" )
			)
			( pin "U7C1.C32"
				( objectStatus "@baseboard_fab2_lib.baseboard_fab2(sch_1):page114_i40:clkout_nssccap0p" )
			)
			( pin "U7C1.B38"
				( objectStatus "@baseboard_fab2_lib.baseboard_fab2(sch_1):page114_i40:clkout_nssccap1n" )
			)
			( pin "U7C1.D38"
				( objectStatus "@baseboard_fab2_lib.baseboard_fab2(sch_1):page114_i40:clkout_nssccap1p" )
			)
			( pin "U7C1.B29"
				( objectStatus "@baseboard_fab2_lib.baseboard_fab2(sch_1):page114_i40:clkout_plat0n" )
			)
			( pin "U7C1.D29"
				( objectStatus "@baseboard_fab2_lib.baseboard_fab2(sch_1):page114_i40:clkout_plat0p" )
			)
			( pin "U7C1.B40"
				( objectStatus "@baseboard_fab2_lib.baseboard_fab2(sch_1):page114_i40:clkout_plat1n" )
			)
			( pin "U7C1.D40"
				( objectStatus "@baseboard_fab2_lib.baseboard_fab2(sch_1):page114_i40:clkout_plat1p" )
			)
			( pin "U7C1.K38"
				( objectStatus "@baseboard_fab2_lib.baseboard_fab2(sch_1):page114_i40:clkout_srcn(0)" )
			)
			( pin "U7C1.K35"
				( objectStatus "@baseboard_fab2_lib.baseboard_fab2(sch_1):page114_i40:clkout_srcn(1)" )
			)
			( pin "U7C1.J33"
				( objectStatus "@baseboard_fab2_lib.baseboard_fab2(sch_1):page114_i40:clkout_srcn(2)" )
			)
			( pin "U7C1.K42"
				( objectStatus "@baseboard_fab2_lib.baseboard_fab2(sch_1):page114_i40:clkout_srcn(3)" )
			)
			( pin "U7C1.A28"
				( objectStatus "@baseboard_fab2_lib.baseboard_fab2(sch_1):page114_i40:clkout_srcn(4)" )
			)
			( pin "U7C1.J40"
				( objectStatus "@baseboard_fab2_lib.baseboard_fab2(sch_1):page114_i40:clkout_srcn(5)" )
			)
			( pin "U7C1.D33"
				( objectStatus "@baseboard_fab2_lib.baseboard_fab2(sch_1):page114_i40:clkout_srcn(6)" )
			)
			( pin "U7C1.H31"
				( objectStatus "@baseboard_fab2_lib.baseboard_fab2(sch_1):page114_i40:clkout_srcn(7)" )
			)
			( pin "U7C1.D31"
				( objectStatus "@baseboard_fab2_lib.baseboard_fab2(sch_1):page114_i40:clkout_srcn(8)" )
			)
			( pin "U7C1.J26"
				( objectStatus "@baseboard_fab2_lib.baseboard_fab2(sch_1):page114_i40:clkout_srcn(9)" )
			)
			( pin "U7C1.B23"
				( objectStatus "@baseboard_fab2_lib.baseboard_fab2(sch_1):page114_i40:clkout_srcn(10)" )
			)
			( pin "U7C1.B21"
				( objectStatus "@baseboard_fab2_lib.baseboard_fab2(sch_1):page114_i40:clkout_srcn(11)" )
			)
			( pin "U7C1.K24"
				( objectStatus "@baseboard_fab2_lib.baseboard_fab2(sch_1):page114_i40:clkout_srcn(12)" )
			)
			( pin "U7C1.C24"
				( objectStatus "@baseboard_fab2_lib.baseboard_fab2(sch_1):page114_i40:clkout_srcn(13)" )
			)
			( pin "U7C1.C20"
				( objectStatus "@baseboard_fab2_lib.baseboard_fab2(sch_1):page114_i40:clkout_srcn(14)" )
			)
			( pin "U7C1.K27"
				( objectStatus "@baseboard_fab2_lib.baseboard_fab2(sch_1):page114_i40:clkout_srcn(15)" )
			)
			( pin "U7C1.H38"
				( objectStatus "@baseboard_fab2_lib.baseboard_fab2(sch_1):page114_i40:clkout_srcp(0)" )
			)
			( pin "U7C1.H35"
				( objectStatus "@baseboard_fab2_lib.baseboard_fab2(sch_1):page114_i40:clkout_srcp(1)" )
			)
			( pin "U7C1.G33"
				( objectStatus "@baseboard_fab2_lib.baseboard_fab2(sch_1):page114_i40:clkout_srcp(2)" )
			)
			( pin "U7C1.H42"
				( objectStatus "@baseboard_fab2_lib.baseboard_fab2(sch_1):page114_i40:clkout_srcp(3)" )
			)
			( pin "U7C1.C28"
				( objectStatus "@baseboard_fab2_lib.baseboard_fab2(sch_1):page114_i40:clkout_srcp(4)" )
			)
			( pin "U7C1.G40"
				( objectStatus "@baseboard_fab2_lib.baseboard_fab2(sch_1):page114_i40:clkout_srcp(5)" )
			)
			( pin "U7C1.B33"
				( objectStatus "@baseboard_fab2_lib.baseboard_fab2(sch_1):page114_i40:clkout_srcp(6)" )
			)
			( pin "U7C1.K31"
				( objectStatus "@baseboard_fab2_lib.baseboard_fab2(sch_1):page114_i40:clkout_srcp(7)" )
			)
			( pin "U7C1.B31"
				( objectStatus "@baseboard_fab2_lib.baseboard_fab2(sch_1):page114_i40:clkout_srcp(8)" )
			)
			( pin "U7C1.G26"
				( objectStatus "@baseboard_fab2_lib.baseboard_fab2(sch_1):page114_i40:clkout_srcp(9)" )
			)
			( pin "U7C1.D23"
				( objectStatus "@baseboard_fab2_lib.baseboard_fab2(sch_1):page114_i40:clkout_srcp(10)" )
			)
			( pin "U7C1.D21"
				( objectStatus "@baseboard_fab2_lib.baseboard_fab2(sch_1):page114_i40:clkout_srcp(11)" )
			)
			( pin "U7C1.H24"
				( objectStatus "@baseboard_fab2_lib.baseboard_fab2(sch_1):page114_i40:clkout_srcp(12)" )
			)
			( pin "U7C1.A24"
				( objectStatus "@baseboard_fab2_lib.baseboard_fab2(sch_1):page114_i40:clkout_srcp(13)" )
			)
			( pin "U7C1.A20"
				( objectStatus "@baseboard_fab2_lib.baseboard_fab2(sch_1):page114_i40:clkout_srcp(14)" )
			)
			( pin "U7C1.H27"
				( objectStatus "@baseboard_fab2_lib.baseboard_fab2(sch_1):page114_i40:clkout_srcp(15)" )
			)
			( pin "U7C1.BW50"
				( objectStatus "@baseboard_fab2_lib.baseboard_fab2(sch_1):page114_i40:clockse_bmcclk" )
			)
			( pin "U7C1.BY51"
				( objectStatus "@baseboard_fab2_lib.baseboard_fab2(sch_1):page114_i40:clockse_pmsyncclk1" )
			)
			( pin "U7C1.BV51"
				( objectStatus "@baseboard_fab2_lib.baseboard_fab2(sch_1):page114_i40:clockse_pmsyncclk2" )
			)
			( pin "U7C1.C26"
				( objectStatus "@baseboard_fab2_lib.baseboard_fab2(sch_1):page114_i40:rsvd(64)" )
			)
			( pin "U7C1.A26"
				( objectStatus "@baseboard_fab2_lib.baseboard_fab2(sch_1):page114_i40:rsvd(65)" )
			)
			( pin "U7C1.K17"
				( objectStatus "@baseboard_fab2_lib.baseboard_fab2(sch_1):page114_i40:rtcx1" )
			)
			( pin "U7C1.H17"
				( objectStatus "@baseboard_fab2_lib.baseboard_fab2(sch_1):page114_i40:rtcx2" )
			)
			( pin "U7C1.G44"
				( objectStatus "@baseboard_fab2_lib.baseboard_fab2(sch_1):page114_i40:xclk_biasref" )
			)
			( pin "U7C1.B35"
				( objectStatus "@baseboard_fab2_lib.baseboard_fab2(sch_1):page114_i40:xtal_in" )
			)
			( pin "U7C1.D35"
				( objectStatus "@baseboard_fab2_lib.baseboard_fab2(sch_1):page114_i40:xtal_out" )
			)
			( pin "C7C15.1"
				( objectStatus "@baseboard_fab2_lib.baseboard_fab2(sch_1):page114_i46:a" )
			)
			( pin "C7C15.2"
				( objectStatus "@baseboard_fab2_lib.baseboard_fab2(sch_1):page114_i46:b" )
			)
			( pin "C7C5.1"
				( objectStatus "@baseboard_fab2_lib.baseboard_fab2(sch_1):page114_i47:a" )
			)
			( pin "C7C5.2"
				( objectStatus "@baseboard_fab2_lib.baseboard_fab2(sch_1):page114_i47:b" )
			)
			( pin "R7C1.1"
				( objectStatus "@baseboard_fab2_lib.baseboard_fab2(sch_1):page114_i48:a" )
			)
			( pin "R7C1.2"
				( objectStatus "@baseboard_fab2_lib.baseboard_fab2(sch_1):page114_i48:b" )
			)
			( pin "Y7C1.1"
				( objectStatus "@baseboard_fab2_lib.baseboard_fab2(sch_1):page114_i49:a" )
			)
			( pin "Y7C1.3"
				( objectStatus "@baseboard_fab2_lib.baseboard_fab2(sch_1):page114_i49:b" )
			)
			( pin "C7C4.1"
				( objectStatus "@baseboard_fab2_lib.baseboard_fab2(sch_1):page114_i50:a" )
			)
			( pin "C7C4.2"
				( objectStatus "@baseboard_fab2_lib.baseboard_fab2(sch_1):page114_i50:b" )
			)
			( pin "R7C6.1"
				( objectStatus "@baseboard_fab2_lib.baseboard_fab2(sch_1):page114_i54:a" )
			)
			( pin "R7C6.2"
				( objectStatus "@baseboard_fab2_lib.baseboard_fab2(sch_1):page114_i54:b" )
			)
			( pin "Y7C2.1"
				( objectStatus "@baseboard_fab2_lib.baseboard_fab2(sch_1):page114_i55:a" )
			)
			( pin "Y7C2.2"
				( objectStatus "@baseboard_fab2_lib.baseboard_fab2(sch_1):page114_i55:b" )
			)
			( pin "C7C13.1"
				( objectStatus "@baseboard_fab2_lib.baseboard_fab2(sch_1):page114_i56:a" )
			)
			( pin "C7C13.2"
				( objectStatus "@baseboard_fab2_lib.baseboard_fab2(sch_1):page114_i56:b" )
			)
			( pin "R8B20.1"
				( objectStatus "@baseboard_fab2_lib.baseboard_fab2(sch_1):page114_i110:a" )
			)
			( pin "R8B20.2"
				( objectStatus "@baseboard_fab2_lib.baseboard_fab2(sch_1):page114_i110:b" )
			)
			( pin "R8B21.1"
				( objectStatus "@baseboard_fab2_lib.baseboard_fab2(sch_1):page114_i124:a" )
			)
			( pin "R8B21.2"
				( objectStatus "@baseboard_fab2_lib.baseboard_fab2(sch_1):page114_i124:b" )
			)
			( pin "R7C2.1"
				( objectStatus "@baseboard_fab2_lib.baseboard_fab2(sch_1):page114_i141:a" )
			)
			( pin "R7C2.2"
				( objectStatus "@baseboard_fab2_lib.baseboard_fab2(sch_1):page114_i141:b" )
			)
			( pin "R7C4.1"
				( objectStatus "@baseboard_fab2_lib.baseboard_fab2(sch_1):page114_i142:a" )
			)
			( pin "R7C4.2"
				( objectStatus "@baseboard_fab2_lib.baseboard_fab2(sch_1):page114_i142:b" )
			)
			( pin "R3N1.1"
				( objectStatus "@baseboard_fab2_lib.baseboard_fab2(sch_1):page114_i149:a" )
			)
			( pin "R3N1.2"
				( objectStatus "@baseboard_fab2_lib.baseboard_fab2(sch_1):page114_i149:b" )
			)
			( pin "U7C1.BN68"
				( objectStatus "@baseboard_fab2_lib.baseboard_fab2(sch_1):page115_i74:rsvd(55)" )
			)
			( pin "U7C1.BN70"
				( objectStatus "@baseboard_fab2_lib.baseboard_fab2(sch_1):page115_i74:usb2_comp" )
			)
			( pin "U7C1.BR67"
				( objectStatus "@baseboard_fab2_lib.baseboard_fab2(sch_1):page115_i74:usb2_vbus" )
			)
			( pin "U7C1.BY60"
				( objectStatus "@baseboard_fab2_lib.baseboard_fab2(sch_1):page115_i74:usb2n_1" )
			)
			( pin "U7C1.CA61"
				( objectStatus "@baseboard_fab2_lib.baseboard_fab2(sch_1):page115_i74:usb2n_2" )
			)
			( pin "U7C1.CA59"
				( objectStatus "@baseboard_fab2_lib.baseboard_fab2(sch_1):page115_i74:usb2n_3" )
			)
			( pin "U7C1.BY62"
				( objectStatus "@baseboard_fab2_lib.baseboard_fab2(sch_1):page115_i74:usb2n_4" )
			)
			( pin "U7C1.BY58"
				( objectStatus "@baseboard_fab2_lib.baseboard_fab2(sch_1):page115_i74:usb2n_5" )
			)
			( pin "U7C1.CA63"
				( objectStatus "@baseboard_fab2_lib.baseboard_fab2(sch_1):page115_i74:usb2n_6" )
			)
			( pin "U7C1.CA57"
				( objectStatus "@baseboard_fab2_lib.baseboard_fab2(sch_1):page115_i74:usb2n_7" )
			)
			( pin "U7C1.BY64"
				( objectStatus "@baseboard_fab2_lib.baseboard_fab2(sch_1):page115_i74:usb2n_8" )
			)
			( pin "U7C1.BY55"
				( objectStatus "@baseboard_fab2_lib.baseboard_fab2(sch_1):page115_i74:usb2n_9" )
			)
			( pin "U7C1.BW65"
				( objectStatus "@baseboard_fab2_lib.baseboard_fab2(sch_1):page115_i74:usb2n_10" )
			)
			( pin "U7C1.CA54"
				( objectStatus "@baseboard_fab2_lib.baseboard_fab2(sch_1):page115_i74:usb2n_11" )
			)
			( pin "U7C1.BW67"
				( objectStatus "@baseboard_fab2_lib.baseboard_fab2(sch_1):page115_i74:usb2n_12" )
			)
			( pin "U7C1.BY53"
				( objectStatus "@baseboard_fab2_lib.baseboard_fab2(sch_1):page115_i74:usb2n_13" )
			)
			( pin "U7C1.BW68"
				( objectStatus "@baseboard_fab2_lib.baseboard_fab2(sch_1):page115_i74:usb2n_14" )
			)
			( pin "U7C1.BV60"
				( objectStatus "@baseboard_fab2_lib.baseboard_fab2(sch_1):page115_i74:usb2p_1" )
			)
			( pin "U7C1.BW61"
				( objectStatus "@baseboard_fab2_lib.baseboard_fab2(sch_1):page115_i74:usb2p_2" )
			)
			( pin "U7C1.BW59"
				( objectStatus "@baseboard_fab2_lib.baseboard_fab2(sch_1):page115_i74:usb2p_3" )
			)
			( pin "U7C1.BV62"
				( objectStatus "@baseboard_fab2_lib.baseboard_fab2(sch_1):page115_i74:usb2p_4" )
			)
			( pin "U7C1.BV58"
				( objectStatus "@baseboard_fab2_lib.baseboard_fab2(sch_1):page115_i74:usb2p_5" )
			)
			( pin "U7C1.BW63"
				( objectStatus "@baseboard_fab2_lib.baseboard_fab2(sch_1):page115_i74:usb2p_6" )
			)
			( pin "U7C1.BW57"
				( objectStatus "@baseboard_fab2_lib.baseboard_fab2(sch_1):page115_i74:usb2p_7" )
			)
			( pin "U7C1.BV64"
				( objectStatus "@baseboard_fab2_lib.baseboard_fab2(sch_1):page115_i74:usb2p_8" )
			)
			( pin "U7C1.BV55"
				( objectStatus "@baseboard_fab2_lib.baseboard_fab2(sch_1):page115_i74:usb2p_9" )
			)
			( pin "U7C1.BU65"
				( objectStatus "@baseboard_fab2_lib.baseboard_fab2(sch_1):page115_i74:usb2p_10" )
			)
			( pin "U7C1.BW54"
				( objectStatus "@baseboard_fab2_lib.baseboard_fab2(sch_1):page115_i74:usb2p_11" )
			)
			( pin "U7C1.BV66"
				( objectStatus "@baseboard_fab2_lib.baseboard_fab2(sch_1):page115_i74:usb2p_12" )
			)
			( pin "U7C1.BV53"
				( objectStatus "@baseboard_fab2_lib.baseboard_fab2(sch_1):page115_i74:usb2p_13" )
			)
			( pin "U7C1.BU67"
				( objectStatus "@baseboard_fab2_lib.baseboard_fab2(sch_1):page115_i74:usb2p_14" )
			)
			( pin "U7C1.BK71"
				( objectStatus "@baseboard_fab2_lib.baseboard_fab2(sch_1):page115_i74:usb3_1_rxn" )
			)
			( pin "U7C1.BK69"
				( objectStatus "@baseboard_fab2_lib.baseboard_fab2(sch_1):page115_i74:usb3_1_rxp" )
			)
			( pin "U7C1.BL52"
				( objectStatus "@baseboard_fab2_lib.baseboard_fab2(sch_1):page115_i74:usb3_1_txn" )
			)
			( pin "U7C1.BK54"
				( objectStatus "@baseboard_fab2_lib.baseboard_fab2(sch_1):page115_i74:usb3_1_txp" )
			)
			( pin "U7C1.BJ72"
				( objectStatus "@baseboard_fab2_lib.baseboard_fab2(sch_1):page115_i74:usb3_2_rxn" )
			)
			( pin "U7C1.BJ70"
				( objectStatus "@baseboard_fab2_lib.baseboard_fab2(sch_1):page115_i74:usb3_2_rxp" )
			)
			( pin "U7C1.BL56"
				( objectStatus "@baseboard_fab2_lib.baseboard_fab2(sch_1):page115_i74:usb3_2_txn" )
			)
			( pin "U7C1.BJ56"
				( objectStatus "@baseboard_fab2_lib.baseboard_fab2(sch_1):page115_i74:usb3_2_txp" )
			)
			( pin "U7C1.BH71"
				( objectStatus "@baseboard_fab2_lib.baseboard_fab2(sch_1):page115_i74:usb3_3_rxn" )
			)
			( pin "U7C1.BH69"
				( objectStatus "@baseboard_fab2_lib.baseboard_fab2(sch_1):page115_i74:usb3_3_rxp" )
			)
			( pin "U7C1.BM54"
				( objectStatus "@baseboard_fab2_lib.baseboard_fab2(sch_1):page115_i74:usb3_3_txn" )
			)
			( pin "U7C1.BN56"
				( objectStatus "@baseboard_fab2_lib.baseboard_fab2(sch_1):page115_i74:usb3_3_txp" )
			)
			( pin "U7C1.BF72"
				( objectStatus "@baseboard_fab2_lib.baseboard_fab2(sch_1):page115_i74:usb3_4_rxn" )
			)
			( pin "U7C1.BF70"
				( objectStatus "@baseboard_fab2_lib.baseboard_fab2(sch_1):page115_i74:usb3_4_rxp" )
			)
			( pin "U7C1.BH58"
				( objectStatus "@baseboard_fab2_lib.baseboard_fab2(sch_1):page115_i74:usb3_4_txn" )
			)
			( pin "U7C1.BG56"
				( objectStatus "@baseboard_fab2_lib.baseboard_fab2(sch_1):page115_i74:usb3_4_txp" )
			)
			( pin "U7C1.BE71"
				( objectStatus "@baseboard_fab2_lib.baseboard_fab2(sch_1):page115_i74:usb3_5_rxn" )
			)
			( pin "U7C1.BE69"
				( objectStatus "@baseboard_fab2_lib.baseboard_fab2(sch_1):page115_i74:usb3_5_rxp" )
			)
			( pin "U7C1.BK58"
				( objectStatus "@baseboard_fab2_lib.baseboard_fab2(sch_1):page115_i74:usb3_5_txn" )
			)
			( pin "U7C1.BJ59"
				( objectStatus "@baseboard_fab2_lib.baseboard_fab2(sch_1):page115_i74:usb3_5_txp" )
			)
			( pin "U7C1.BD72"
				( objectStatus "@baseboard_fab2_lib.baseboard_fab2(sch_1):page115_i74:usb3_6_rxn" )
			)
			( pin "U7C1.BD70"
				( objectStatus "@baseboard_fab2_lib.baseboard_fab2(sch_1):page115_i74:usb3_6_rxp" )
			)
			( pin "U7C1.BL59"
				( objectStatus "@baseboard_fab2_lib.baseboard_fab2(sch_1):page115_i74:usb3_6_txn" )
			)
			( pin "U7C1.BM61"
				( objectStatus "@baseboard_fab2_lib.baseboard_fab2(sch_1):page115_i74:usb3_6_txp" )
			)
			( pin "R8B9.1"
				( objectStatus "@baseboard_fab2_lib.baseboard_fab2(sch_1):page115_i90:a" )
			)
			( pin "R8B9.2"
				( objectStatus "@baseboard_fab2_lib.baseboard_fab2(sch_1):page115_i90:b" )
			)
			( pin "R8B32.1"
				( objectStatus "@baseboard_fab2_lib.baseboard_fab2(sch_1):page115_i114:a" )
			)
			( pin "R8B32.2"
				( objectStatus "@baseboard_fab2_lib.baseboard_fab2(sch_1):page115_i114:b" )
			)
			( pin "R3M11.1"
				( objectStatus "@baseboard_fab2_lib.baseboard_fab2(sch_1):page116_i108:a" )
			)
			( pin "R3M11.2"
				( objectStatus "@baseboard_fab2_lib.baseboard_fab2(sch_1):page116_i108:b" )
			)
			( pin "R3M12.1"
				( objectStatus "@baseboard_fab2_lib.baseboard_fab2(sch_1):page116_i181:a" )
			)
			( pin "R3M12.2"
				( objectStatus "@baseboard_fab2_lib.baseboard_fab2(sch_1):page116_i181:b" )
			)
			( pin "C2M4.1"
				( objectStatus "@baseboard_fab2_lib.baseboard_fab2(sch_1):page116_i182:a" )
			)
			( pin "C2M4.2"
				( objectStatus "@baseboard_fab2_lib.baseboard_fab2(sch_1):page116_i182:b" )
			)
			( pin "C2M3.1"
				( objectStatus "@baseboard_fab2_lib.baseboard_fab2(sch_1):page116_i183:a" )
			)
			( pin "C2M3.2"
				( objectStatus "@baseboard_fab2_lib.baseboard_fab2(sch_1):page116_i183:b" )
			)
			( pin "U7C1.D66"
				( objectStatus "@baseboard_fab2_lib.baseboard_fab2(sch_1):page116_i220:extclkn" )
			)
			( pin "U7C1.E67"
				( objectStatus "@baseboard_fab2_lib.baseboard_fab2(sch_1):page116_i220:extclkp" )
			)
			( pin "U7C1.AN70"
				( objectStatus "@baseboard_fab2_lib.baseboard_fab2(sch_1):page116_i220:pcie4_gbe_rxn" )
			)
			( pin "U7C1.AN72"
				( objectStatus "@baseboard_fab2_lib.baseboard_fab2(sch_1):page116_i220:pcie4_gbe_rxp" )
			)
			( pin "U7C1.BG66"
				( objectStatus "@baseboard_fab2_lib.baseboard_fab2(sch_1):page116_i220:pcie4_gbe_txn" )
			)
			( pin "U7C1.BJ66"
				( objectStatus "@baseboard_fab2_lib.baseboard_fab2(sch_1):page116_i220:pcie4_gbe_txp" )
			)
			( pin "U7C1.AM69"
				( objectStatus "@baseboard_fab2_lib.baseboard_fab2(sch_1):page116_i220:pcie5_gbe_rxn" )
			)
			( pin "U7C1.AM71"
				( objectStatus "@baseboard_fab2_lib.baseboard_fab2(sch_1):page116_i220:pcie5_gbe_rxp" )
			)
			( pin "U7C1.BH65"
				( objectStatus "@baseboard_fab2_lib.baseboard_fab2(sch_1):page116_i220:pcie5_gbe_txn" )
			)
			( pin "U7C1.BJ63"
				( objectStatus "@baseboard_fab2_lib.baseboard_fab2(sch_1):page116_i220:pcie5_gbe_txp" )
			)
			( pin "U7C1.BB63"
				( objectStatus "@baseboard_fab2_lib.baseboard_fab2(sch_1):page116_i220:pcie6_ssata0_rxn" )
			)
			( pin "U7C1.BD61"
				( objectStatus "@baseboard_fab2_lib.baseboard_fab2(sch_1):page116_i220:pcie6_ssata0_rxp" )
			)
			( pin "U7C1.AJ70"
				( objectStatus "@baseboard_fab2_lib.baseboard_fab2(sch_1):page116_i220:pcie6_ssata0_txn" )
			)
			( pin "U7C1.AJ72"
				( objectStatus "@baseboard_fab2_lib.baseboard_fab2(sch_1):page116_i220:pcie6_ssata0_txp" )
			)
			( pin "U7C1.AY59"
				( objectStatus "@baseboard_fab2_lib.baseboard_fab2(sch_1):page116_i220:pcie7_ssata1_rxn" )
			)
			( pin "U7C1.BA61"
				( objectStatus "@baseboard_fab2_lib.baseboard_fab2(sch_1):page116_i220:pcie7_ssata1_rxp" )
			)
			( pin "U7C1.AH69"
				( objectStatus "@baseboard_fab2_lib.baseboard_fab2(sch_1):page116_i220:pcie7_ssata1_txn" )
			)
			( pin "U7C1.AH71"
				( objectStatus "@baseboard_fab2_lib.baseboard_fab2(sch_1):page116_i220:pcie7_ssata1_txp" )
			)
			( pin "U7C1.BA65"
				( objectStatus "@baseboard_fab2_lib.baseboard_fab2(sch_1):page116_i220:pcie8_ssata2_gbe_rxn" )
			)
			( pin "U7C1.BD65"
				( objectStatus "@baseboard_fab2_lib.baseboard_fab2(sch_1):page116_i220:pcie8_ssata2_gbe_rxp" )
			)
			( pin "U7C1.AF70"
				( objectStatus "@baseboard_fab2_lib.baseboard_fab2(sch_1):page116_i220:pcie8_ssata2_gbe_txn" )
			)
			( pin "U7C1.AF72"
				( objectStatus "@baseboard_fab2_lib.baseboard_fab2(sch_1):page116_i220:pcie8_ssata2_gbe_txp" )
			)
			( pin "U7C1.AW65"
				( objectStatus "@baseboard_fab2_lib.baseboard_fab2(sch_1):page116_i220:pcie9_ssata3_rxn" )
			)
			( pin "U7C1.AY66"
				( objectStatus "@baseboard_fab2_lib.baseboard_fab2(sch_1):page116_i220:pcie9_ssata3_rxp" )
			)
			( pin "U7C1.AE69"
				( objectStatus "@baseboard_fab2_lib.baseboard_fab2(sch_1):page116_i220:pcie9_ssata3_txn" )
			)
			( pin "U7C1.AE71"
				( objectStatus "@baseboard_fab2_lib.baseboard_fab2(sch_1):page116_i220:pcie9_ssata3_txp" )
			)
			( pin "U7C1.AV63"
				( objectStatus "@baseboard_fab2_lib.baseboard_fab2(sch_1):page116_i220:pcie10_ssata4_rxn" )
			)
			( pin "U7C1.AU65"
				( objectStatus "@baseboard_fab2_lib.baseboard_fab2(sch_1):page116_i220:pcie10_ssata4_rxp" )
			)
			( pin "U7C1.AD70"
				( objectStatus "@baseboard_fab2_lib.baseboard_fab2(sch_1):page116_i220:pcie10_ssata4_txn" )
			)
			( pin "U7C1.AD72"
				( objectStatus "@baseboard_fab2_lib.baseboard_fab2(sch_1):page116_i220:pcie10_ssata4_txp" )
			)
			( pin "U7C1.AT66"
				( objectStatus "@baseboard_fab2_lib.baseboard_fab2(sch_1):page116_i220:pcie11_ssata5_gbe_rxn" )
			)
			( pin "U7C1.AV66"
				( objectStatus "@baseboard_fab2_lib.baseboard_fab2(sch_1):page116_i220:pcie11_ssata5_gbe_rxp" )
			)
			( pin "U7C1.AC69"
				( objectStatus "@baseboard_fab2_lib.baseboard_fab2(sch_1):page116_i220:pcie11_ssata5_gbe_txn" )
			)
			( pin "U7C1.AC71"
				( objectStatus "@baseboard_fab2_lib.baseboard_fab2(sch_1):page116_i220:pcie11_ssata5_gbe_txp" )
			)
			( pin "U7C1.AR61"
				( objectStatus "@baseboard_fab2_lib.baseboard_fab2(sch_1):page116_i220:pcie12_up0_sata0_rxn" )
			)
			( pin "U7C1.AT63"
				( objectStatus "@baseboard_fab2_lib.baseboard_fab2(sch_1):page116_i220:pcie12_up0_sata0_rxp" )
			)
			( pin "U7C1.W69"
				( objectStatus "@baseboard_fab2_lib.baseboard_fab2(sch_1):page116_i220:pcie12_up0_sata0_txn" )
			)
			( pin "U7C1.W71"
				( objectStatus "@baseboard_fab2_lib.baseboard_fab2(sch_1):page116_i220:pcie12_up0_sata0_txp" )
			)
			( pin "U7C1.AL66"
				( objectStatus "@baseboard_fab2_lib.baseboard_fab2(sch_1):page116_i220:pcie13_up1_sata1_rxn" )
			)
			( pin "U7C1.AN65"
				( objectStatus "@baseboard_fab2_lib.baseboard_fab2(sch_1):page116_i220:pcie13_up1_sata1_rxp" )
			)
			( pin "U7C1.V70"
				( objectStatus "@baseboard_fab2_lib.baseboard_fab2(sch_1):page116_i220:pcie13_up1_sata1_txn" )
			)
			( pin "U7C1.V72"
				( objectStatus "@baseboard_fab2_lib.baseboard_fab2(sch_1):page116_i220:pcie13_up1_sata1_txp" )
			)
			( pin "U7C1.AK65"
				( objectStatus "@baseboard_fab2_lib.baseboard_fab2(sch_1):page116_i220:pcie14_up2_sata2_rxn" )
			)
			( pin "U7C1.AJ63"
				( objectStatus "@baseboard_fab2_lib.baseboard_fab2(sch_1):page116_i220:pcie14_up2_sata2_rxp" )
			)
			( pin "U7C1.T69"
				( objectStatus "@baseboard_fab2_lib.baseboard_fab2(sch_1):page116_i220:pcie14_up2_sata2_txn" )
			)
			( pin "U7C1.T71"
				( objectStatus "@baseboard_fab2_lib.baseboard_fab2(sch_1):page116_i220:pcie14_up2_sata2_txp" )
			)
			( pin "U7C1.AP63"
				( objectStatus "@baseboard_fab2_lib.baseboard_fab2(sch_1):page116_i220:pcie15_up3_sata3_rxn" )
			)
			( pin "U7C1.AL63"
				( objectStatus "@baseboard_fab2_lib.baseboard_fab2(sch_1):page116_i220:pcie15_up3_sata3_rxp" )
			)
			( pin "U7C1.R70"
				( objectStatus "@baseboard_fab2_lib.baseboard_fab2(sch_1):page116_i220:pcie15_up3_sata3_txn" )
			)
			( pin "U7C1.R72"
				( objectStatus "@baseboard_fab2_lib.baseboard_fab2(sch_1):page116_i220:pcie15_up3_sata3_txp" )
			)
			( pin "U7C1.AF65"
				( objectStatus "@baseboard_fab2_lib.baseboard_fab2(sch_1):page116_i220:pcie16_up4_sata4_rxn" )
			)
			( pin "U7C1.AH65"
				( objectStatus "@baseboard_fab2_lib.baseboard_fab2(sch_1):page116_i220:pcie16_up4_sata4_rxp" )
			)
			( pin "U7C1.P69"
				( objectStatus "@baseboard_fab2_lib.baseboard_fab2(sch_1):page116_i220:pcie16_up4_sata4_txn" )
			)
			( pin "U7C1.P71"
				( objectStatus "@baseboard_fab2_lib.baseboard_fab2(sch_1):page116_i220:pcie16_up4_sata4_txp" )
			)
			( pin "U7C1.AH61"
				( objectStatus "@baseboard_fab2_lib.baseboard_fab2(sch_1):page116_i220:pcie17_up5_sata5_rxn" )
			)
			( pin "U7C1.AG63"
				( objectStatus "@baseboard_fab2_lib.baseboard_fab2(sch_1):page116_i220:pcie17_up5_sata5_rxp" )
			)
			( pin "U7C1.N70"
				( objectStatus "@baseboard_fab2_lib.baseboard_fab2(sch_1):page116_i220:pcie17_up5_sata5_txn" )
			)
			( pin "U7C1.N72"
				( objectStatus "@baseboard_fab2_lib.baseboard_fab2(sch_1):page116_i220:pcie17_up5_sata5_txp" )
			)
			( pin "U7C1.AP59"
				( objectStatus "@baseboard_fab2_lib.baseboard_fab2(sch_1):page116_i220:pcie18_up6_sata6_rxn" )
			)
			( pin "U7C1.AN61"
				( objectStatus "@baseboard_fab2_lib.baseboard_fab2(sch_1):page116_i220:pcie18_up6_sata6_rxp" )
			)
			( pin "U7C1.M69"
				( objectStatus "@baseboard_fab2_lib.baseboard_fab2(sch_1):page116_i220:pcie18_up6_sata6_txn" )
			)
			( pin "U7C1.M71"
				( objectStatus "@baseboard_fab2_lib.baseboard_fab2(sch_1):page116_i220:pcie18_up6_sata6_txp" )
			)
			( pin "U7C1.AA61"
				( objectStatus "@baseboard_fab2_lib.baseboard_fab2(sch_1):page116_i220:pcie19_up7_sata7_rxn" )
			)
			( pin "U7C1.AD61"
				( objectStatus "@baseboard_fab2_lib.baseboard_fab2(sch_1):page116_i220:pcie19_up7_sata7_rxp" )
			)
			( pin "U7C1.L70"
				( objectStatus "@baseboard_fab2_lib.baseboard_fab2(sch_1):page116_i220:pcie19_up7_sata7_txn" )
			)
			( pin "U7C1.L72"
				( objectStatus "@baseboard_fab2_lib.baseboard_fab2(sch_1):page116_i220:pcie19_up7_sata7_txp" )
			)
			( pin "U7C1.BD58"
				( objectStatus "@baseboard_fab2_lib.baseboard_fab2(sch_1):page116_i220:pcie_rcompn" )
			)
			( pin "U7C1.BB56"
				( objectStatus "@baseboard_fab2_lib.baseboard_fab2(sch_1):page116_i220:pcie_rcompp" )
			)
			( pin "U7C1.AF58"
				( objectStatus "@baseboard_fab2_lib.baseboard_fab2(sch_1):page116_i220:pcieup_rcompn" )
			)
			( pin "U7C1.AH58"
				( objectStatus "@baseboard_fab2_lib.baseboard_fab2(sch_1):page116_i220:pcieup_rcompp" )
			)
			( pin "U7C1.AP69"
				( objectStatus "@baseboard_fab2_lib.baseboard_fab2(sch_1):page116_i220:rsvd(47)" )
			)
			( pin "U7C1.AP71"
				( objectStatus "@baseboard_fab2_lib.baseboard_fab2(sch_1):page116_i220:rsvd(48)" )
			)
			( pin "U7C1.G67"
				( objectStatus "@baseboard_fab2_lib.baseboard_fab2(sch_1):page116_i220:rsvd(49)" )
			)
			( pin "U7C1.H69"
				( objectStatus "@baseboard_fab2_lib.baseboard_fab2(sch_1):page116_i220:rsvd(50)" )
			)
			( pin "U7C1.AA69"
				( objectStatus "@baseboard_fab2_lib.baseboard_fab2(sch_1):page116_i220:rsvd(51)" )
			)
			( pin "U7C1.AA71"
				( objectStatus "@baseboard_fab2_lib.baseboard_fab2(sch_1):page116_i220:rsvd(52)" )
			)
			( pin "U7C1.BA71"
				( objectStatus "@baseboard_fab2_lib.baseboard_fab2(sch_1):page116_i220:usb3_7_pcie0_rxn" )
			)
			( pin "U7C1.BA69"
				( objectStatus "@baseboard_fab2_lib.baseboard_fab2(sch_1):page116_i220:usb3_7_pcie0_rxp" )
			)
			( pin "U7C1.BR61"
				( objectStatus "@baseboard_fab2_lib.baseboard_fab2(sch_1):page116_i220:usb3_7_pcie0_txn" )
			)
			( pin "U7C1.BN63"
				( objectStatus "@baseboard_fab2_lib.baseboard_fab2(sch_1):page116_i220:usb3_7_pcie0_txp" )
			)
			( pin "U7C1.AY72"
				( objectStatus "@baseboard_fab2_lib.baseboard_fab2(sch_1):page116_i220:usb3_8_pcie1_rxn" )
			)
			( pin "U7C1.AY70"
				( objectStatus "@baseboard_fab2_lib.baseboard_fab2(sch_1):page116_i220:usb3_8_pcie1_rxp" )
			)
			( pin "U7C1.BM65"
				( objectStatus "@baseboard_fab2_lib.baseboard_fab2(sch_1):page116_i220:usb3_8_pcie1_txn" )
			)
			( pin "U7C1.BR65"
				( objectStatus "@baseboard_fab2_lib.baseboard_fab2(sch_1):page116_i220:usb3_8_pcie1_txp" )
			)
			( pin "U7C1.AW71"
				( objectStatus "@baseboard_fab2_lib.baseboard_fab2(sch_1):page116_i220:usb3_9_pcie2_rxn" )
			)
			( pin "U7C1.AW69"
				( objectStatus "@baseboard_fab2_lib.baseboard_fab2(sch_1):page116_i220:usb3_9_pcie2_rxp" )
			)
			( pin "U7C1.BK65"
				( objectStatus "@baseboard_fab2_lib.baseboard_fab2(sch_1):page116_i220:usb3_9_pcie2_txn" )
			)
			( pin "U7C1.BL66"
				( objectStatus "@baseboard_fab2_lib.baseboard_fab2(sch_1):page116_i220:usb3_9_pcie2_txp" )
			)
			( pin "U7C1.AV72"
				( objectStatus "@baseboard_fab2_lib.baseboard_fab2(sch_1):page116_i220:usb3_10_pcie3_gbe_rxn" )
			)
			( pin "U7C1.AV70"
				( objectStatus "@baseboard_fab2_lib.baseboard_fab2(sch_1):page116_i220:usb3_10_pcie3_gbe_rxp" )
			)
			( pin "U7C1.BH61"
				( objectStatus "@baseboard_fab2_lib.baseboard_fab2(sch_1):page116_i220:usb3_10_pcie3_gbe_txn" )
			)
			( pin "U7C1.BK61"
				( objectStatus "@baseboard_fab2_lib.baseboard_fab2(sch_1):page116_i220:usb3_10_pcie3_gbe_txp" )
			)
			( pin "R7B8.1"
				( objectStatus "@baseboard_fab2_lib.baseboard_fab2(sch_1):page116_i229:a" )
			)
			( pin "R7B8.2"
				( objectStatus "@baseboard_fab2_lib.baseboard_fab2(sch_1):page116_i229:b" )
			)
			( pin "R7B7.1"
				( objectStatus "@baseboard_fab2_lib.baseboard_fab2(sch_1):page116_i230:a" )
			)
			( pin "R7B7.2"
				( objectStatus "@baseboard_fab2_lib.baseboard_fab2(sch_1):page116_i230:b" )
			)
			( pin "R3M9.1"
				( objectStatus "@baseboard_fab2_lib.baseboard_fab2(sch_1):page116_i234:a" )
			)
			( pin "R3M9.2"
				( objectStatus "@baseboard_fab2_lib.baseboard_fab2(sch_1):page116_i234:b" )
			)
			( pin "R3M8.1"
				( objectStatus "@baseboard_fab2_lib.baseboard_fab2(sch_1):page116_i235:a" )
			)
			( pin "R3M8.2"
				( objectStatus "@baseboard_fab2_lib.baseboard_fab2(sch_1):page116_i235:b" )
			)
			( pin "U7C1.D42"
				( objectStatus "@baseboard_fab2_lib.baseboard_fab2(sch_1):page117_i9:dmi_rxn(0)" )
			)
			( pin "U7C1.C43"
				( objectStatus "@baseboard_fab2_lib.baseboard_fab2(sch_1):page117_i9:dmi_rxn(1)" )
			)
			( pin "U7C1.D44"
				( objectStatus "@baseboard_fab2_lib.baseboard_fab2(sch_1):page117_i9:dmi_rxn(2)" )
			)
			( pin "U7C1.C45"
				( objectStatus "@baseboard_fab2_lib.baseboard_fab2(sch_1):page117_i9:dmi_rxn(3)" )
			)
			( pin "U7C1.B42"
				( objectStatus "@baseboard_fab2_lib.baseboard_fab2(sch_1):page117_i9:dmi_rxp(0)" )
			)
			( pin "U7C1.A43"
				( objectStatus "@baseboard_fab2_lib.baseboard_fab2(sch_1):page117_i9:dmi_rxp(1)" )
			)
			( pin "U7C1.B44"
				( objectStatus "@baseboard_fab2_lib.baseboard_fab2(sch_1):page117_i9:dmi_rxp(2)" )
			)
			( pin "U7C1.A45"
				( objectStatus "@baseboard_fab2_lib.baseboard_fab2(sch_1):page117_i9:dmi_rxp(3)" )
			)
			( pin "U7C1.H46"
				( objectStatus "@baseboard_fab2_lib.baseboard_fab2(sch_1):page117_i9:dmi_txn(0)" )
			)
			( pin "U7C1.J48"
				( objectStatus "@baseboard_fab2_lib.baseboard_fab2(sch_1):page117_i9:dmi_txn(1)" )
			)
			( pin "U7C1.K50"
				( objectStatus "@baseboard_fab2_lib.baseboard_fab2(sch_1):page117_i9:dmi_txn(2)" )
			)
			( pin "U7C1.P52"
				( objectStatus "@baseboard_fab2_lib.baseboard_fab2(sch_1):page117_i9:dmi_txn(3)" )
			)
			( pin "U7C1.K46"
				( objectStatus "@baseboard_fab2_lib.baseboard_fab2(sch_1):page117_i9:dmi_txp(0)" )
			)
			( pin "U7C1.H50"
				( objectStatus "@baseboard_fab2_lib.baseboard_fab2(sch_1):page117_i9:dmi_txp(1)" )
			)
			( pin "U7C1.M52"
				( objectStatus "@baseboard_fab2_lib.baseboard_fab2(sch_1):page117_i9:dmi_txp(2)" )
			)
			( pin "U7C1.N54"
				( objectStatus "@baseboard_fab2_lib.baseboard_fab2(sch_1):page117_i9:dmi_txp(3)" )
			)
			( pin "U7C1.C48"
				( objectStatus "@baseboard_fab2_lib.baseboard_fab2(sch_1):page117_i9:pcieup_0_rxn" )
			)
			( pin "U7C1.A48"
				( objectStatus "@baseboard_fab2_lib.baseboard_fab2(sch_1):page117_i9:pcieup_0_rxp" )
			)
			( pin "U7C1.J52"
				( objectStatus "@baseboard_fab2_lib.baseboard_fab2(sch_1):page117_i9:pcieup_0_txn" )
			)
			( pin "U7C1.G52"
				( objectStatus "@baseboard_fab2_lib.baseboard_fab2(sch_1):page117_i9:pcieup_0_txp" )
			)
			( pin "U7C1.D49"
				( objectStatus "@baseboard_fab2_lib.baseboard_fab2(sch_1):page117_i9:pcieup_1_rxn" )
			)
			( pin "U7C1.B49"
				( objectStatus "@baseboard_fab2_lib.baseboard_fab2(sch_1):page117_i9:pcieup_1_rxp" )
			)
			( pin "U7C1.P56"
				( objectStatus "@baseboard_fab2_lib.baseboard_fab2(sch_1):page117_i9:pcieup_1_txn" )
			)
			( pin "U7C1.M56"
				( objectStatus "@baseboard_fab2_lib.baseboard_fab2(sch_1):page117_i9:pcieup_1_txp" )
			)
			( pin "U7C1.C50"
				( objectStatus "@baseboard_fab2_lib.baseboard_fab2(sch_1):page117_i9:pcieup_2_rxn" )
			)
			( pin "U7C1.A50"
				( objectStatus "@baseboard_fab2_lib.baseboard_fab2(sch_1):page117_i9:pcieup_2_rxp" )
			)
			( pin "U7C1.H54"
				( objectStatus "@baseboard_fab2_lib.baseboard_fab2(sch_1):page117_i9:pcieup_2_txn" )
			)
			( pin "U7C1.G56"
				( objectStatus "@baseboard_fab2_lib.baseboard_fab2(sch_1):page117_i9:pcieup_2_txp" )
			)
			( pin "U7C1.D51"
				( objectStatus "@baseboard_fab2_lib.baseboard_fab2(sch_1):page117_i9:pcieup_3_rxn" )
			)
			( pin "U7C1.B51"
				( objectStatus "@baseboard_fab2_lib.baseboard_fab2(sch_1):page117_i9:pcieup_3_rxp" )
			)
			( pin "U7C1.J56"
				( objectStatus "@baseboard_fab2_lib.baseboard_fab2(sch_1):page117_i9:pcieup_3_txn" )
			)
			( pin "U7C1.K58"
				( objectStatus "@baseboard_fab2_lib.baseboard_fab2(sch_1):page117_i9:pcieup_3_txp" )
			)
			( pin "U7C1.C52"
				( objectStatus "@baseboard_fab2_lib.baseboard_fab2(sch_1):page117_i9:pcieup_4_rxn" )
			)
			( pin "U7C1.A52"
				( objectStatus "@baseboard_fab2_lib.baseboard_fab2(sch_1):page117_i9:pcieup_4_rxp" )
			)
			( pin "U7C1.N58"
				( objectStatus "@baseboard_fab2_lib.baseboard_fab2(sch_1):page117_i9:pcieup_4_txn" )
			)
			( pin "U7C1.M59"
				( objectStatus "@baseboard_fab2_lib.baseboard_fab2(sch_1):page117_i9:pcieup_4_txp" )
			)
			( pin "U7C1.D53"
				( objectStatus "@baseboard_fab2_lib.baseboard_fab2(sch_1):page117_i9:pcieup_5_rxn" )
			)
			( pin "U7C1.B53"
				( objectStatus "@baseboard_fab2_lib.baseboard_fab2(sch_1):page117_i9:pcieup_5_rxp" )
			)
			( pin "U7C1.N61"
				( objectStatus "@baseboard_fab2_lib.baseboard_fab2(sch_1):page117_i9:pcieup_5_txn" )
			)
			( pin "U7C1.K61"
				( objectStatus "@baseboard_fab2_lib.baseboard_fab2(sch_1):page117_i9:pcieup_5_txp" )
			)
			( pin "U7C1.C54"
				( objectStatus "@baseboard_fab2_lib.baseboard_fab2(sch_1):page117_i9:pcieup_6_rxn" )
			)
			( pin "U7C1.A54"
				( objectStatus "@baseboard_fab2_lib.baseboard_fab2(sch_1):page117_i9:pcieup_6_rxp" )
			)
			( pin "U7C1.H61"
				( objectStatus "@baseboard_fab2_lib.baseboard_fab2(sch_1):page117_i9:pcieup_6_txn" )
			)
			( pin "U7C1.J63"
				( objectStatus "@baseboard_fab2_lib.baseboard_fab2(sch_1):page117_i9:pcieup_6_txp" )
			)
			( pin "U7C1.D55"
				( objectStatus "@baseboard_fab2_lib.baseboard_fab2(sch_1):page117_i9:pcieup_7_rxn" )
			)
			( pin "U7C1.B55"
				( objectStatus "@baseboard_fab2_lib.baseboard_fab2(sch_1):page117_i9:pcieup_7_rxp" )
			)
			( pin "U7C1.P59"
				( objectStatus "@baseboard_fab2_lib.baseboard_fab2(sch_1):page117_i9:pcieup_7_txn" )
			)
			( pin "U7C1.R61"
				( objectStatus "@baseboard_fab2_lib.baseboard_fab2(sch_1):page117_i9:pcieup_7_txp" )
			)
			( pin "U7C1.C57"
				( objectStatus "@baseboard_fab2_lib.baseboard_fab2(sch_1):page117_i9:pcieup_8_rxn" )
			)
			( pin "U7C1.A57"
				( objectStatus "@baseboard_fab2_lib.baseboard_fab2(sch_1):page117_i9:pcieup_8_rxp" )
			)
			( pin "U7C1.K65"
				( objectStatus "@baseboard_fab2_lib.baseboard_fab2(sch_1):page117_i9:pcieup_8_txn" )
			)
			( pin "U7C1.M63"
				( objectStatus "@baseboard_fab2_lib.baseboard_fab2(sch_1):page117_i9:pcieup_8_txp" )
			)
			( pin "U7C1.D58"
				( objectStatus "@baseboard_fab2_lib.baseboard_fab2(sch_1):page117_i9:pcieup_9_rxn" )
			)
			( pin "U7C1.B58"
				( objectStatus "@baseboard_fab2_lib.baseboard_fab2(sch_1):page117_i9:pcieup_9_rxp" )
			)
			( pin "U7C1.J66"
				( objectStatus "@baseboard_fab2_lib.baseboard_fab2(sch_1):page117_i9:pcieup_9_txn" )
			)
			( pin "U7C1.M66"
				( objectStatus "@baseboard_fab2_lib.baseboard_fab2(sch_1):page117_i9:pcieup_9_txp" )
			)
			( pin "U7C1.C59"
				( objectStatus "@baseboard_fab2_lib.baseboard_fab2(sch_1):page117_i9:pcieup_10_rxn" )
			)
			( pin "U7C1.A59"
				( objectStatus "@baseboard_fab2_lib.baseboard_fab2(sch_1):page117_i9:pcieup_10_rxp" )
			)
			( pin "U7C1.N65"
				( objectStatus "@baseboard_fab2_lib.baseboard_fab2(sch_1):page117_i9:pcieup_10_txn" )
			)
			( pin "U7C1.P66"
				( objectStatus "@baseboard_fab2_lib.baseboard_fab2(sch_1):page117_i9:pcieup_10_txp" )
			)
			( pin "U7C1.D60"
				( objectStatus "@baseboard_fab2_lib.baseboard_fab2(sch_1):page117_i9:pcieup_11_rxn" )
			)
			( pin "U7C1.B60"
				( objectStatus "@baseboard_fab2_lib.baseboard_fab2(sch_1):page117_i9:pcieup_11_rxp" )
			)
			( pin "U7C1.T59"
				( objectStatus "@baseboard_fab2_lib.baseboard_fab2(sch_1):page117_i9:pcieup_11_txn" )
			)
			( pin "U7C1.V59"
				( objectStatus "@baseboard_fab2_lib.baseboard_fab2(sch_1):page117_i9:pcieup_11_txp" )
			)
			( pin "U7C1.C61"
				( objectStatus "@baseboard_fab2_lib.baseboard_fab2(sch_1):page117_i9:pcieup_12_rxn" )
			)
			( pin "U7C1.A61"
				( objectStatus "@baseboard_fab2_lib.baseboard_fab2(sch_1):page117_i9:pcieup_12_rxp" )
			)
			( pin "U7C1.R65"
				( objectStatus "@baseboard_fab2_lib.baseboard_fab2(sch_1):page117_i9:pcieup_12_txn" )
			)
			( pin "U7C1.U65"
				( objectStatus "@baseboard_fab2_lib.baseboard_fab2(sch_1):page117_i9:pcieup_12_txp" )
			)
			( pin "U7C1.D62"
				( objectStatus "@baseboard_fab2_lib.baseboard_fab2(sch_1):page117_i9:pcieup_13_rxn" )
			)
			( pin "U7C1.B62"
				( objectStatus "@baseboard_fab2_lib.baseboard_fab2(sch_1):page117_i9:pcieup_13_rxp" )
			)
			( pin "U7C1.T63"
				( objectStatus "@baseboard_fab2_lib.baseboard_fab2(sch_1):page117_i9:pcieup_13_txn" )
			)
			( pin "U7C1.U61"
				( objectStatus "@baseboard_fab2_lib.baseboard_fab2(sch_1):page117_i9:pcieup_13_txp" )
			)
			( pin "U7C1.C63"
				( objectStatus "@baseboard_fab2_lib.baseboard_fab2(sch_1):page117_i9:pcieup_14_rxn" )
			)
			( pin "U7C1.A63"
				( objectStatus "@baseboard_fab2_lib.baseboard_fab2(sch_1):page117_i9:pcieup_14_rxp" )
			)
			( pin "U7C1.W65"
				( objectStatus "@baseboard_fab2_lib.baseboard_fab2(sch_1):page117_i9:pcieup_14_txn" )
			)
			( pin "U7C1.V63"
				( objectStatus "@baseboard_fab2_lib.baseboard_fab2(sch_1):page117_i9:pcieup_14_txp" )
			)
			( pin "U7C1.D64"
				( objectStatus "@baseboard_fab2_lib.baseboard_fab2(sch_1):page117_i9:pcieup_15_rxn" )
			)
			( pin "U7C1.B64"
				( objectStatus "@baseboard_fab2_lib.baseboard_fab2(sch_1):page117_i9:pcieup_15_rxp" )
			)
			( pin "U7C1.Y66"
				( objectStatus "@baseboard_fab2_lib.baseboard_fab2(sch_1):page117_i9:pcieup_15_txn" )
			)
			( pin "U7C1.AA65"
				( objectStatus "@baseboard_fab2_lib.baseboard_fab2(sch_1):page117_i9:pcieup_15_txp" )
			)
			( pin "R3N9.1"
				( objectStatus "@baseboard_fab2_lib.baseboard_fab2(sch_1):page118_i66:a" )
			)
			( pin "R3N9.2"
				( objectStatus "@baseboard_fab2_lib.baseboard_fab2(sch_1):page118_i66:b" )
			)
			( pin "R3N14.1"
				( objectStatus "@baseboard_fab2_lib.baseboard_fab2(sch_1):page118_i67:a" )
			)
			( pin "R3N14.2"
				( objectStatus "@baseboard_fab2_lib.baseboard_fab2(sch_1):page118_i67:b" )
			)
			( pin "R3N13.1"
				( objectStatus "@baseboard_fab2_lib.baseboard_fab2(sch_1):page118_i71:a" )
			)
			( pin "R3N13.2"
				( objectStatus "@baseboard_fab2_lib.baseboard_fab2(sch_1):page118_i71:b" )
			)
			( pin "U7C1.AT56"
				( objectStatus "@baseboard_fab2_lib.baseboard_fab2(sch_1):page118_i73:cpu_trst_n" )
			)
			( pin "U7C1.K13"
				( objectStatus "@baseboard_fab2_lib.baseboard_fab2(sch_1):page118_i73:dsw_pwrok" )
			)
			( pin "U7C1.G15"
				( objectStatus "@baseboard_fab2_lib.baseboard_fab2(sch_1):page118_i73:gpd0" )
			)
			( pin "U7C1.H13"
				( objectStatus "@baseboard_fab2_lib.baseboard_fab2(sch_1):page118_i73:gpd1_acpresent" )
			)
			( pin "U7C1.M11"
				( objectStatus "@baseboard_fab2_lib.baseboard_fab2(sch_1):page118_i73:gpd2_gbe_wake_n" )
			)
			( pin "U7C1.C15"
				( objectStatus "@baseboard_fab2_lib.baseboard_fab2(sch_1):page118_i73:gpd3_pwrbtn_n" )
			)
			( pin "U7C1.D14"
				( objectStatus "@baseboard_fab2_lib.baseboard_fab2(sch_1):page118_i73:gpd4_slp_s3_n" )
			)
			( pin "U7C1.B16"
				( objectStatus "@baseboard_fab2_lib.baseboard_fab2(sch_1):page118_i73:gpd5_slp_s4_n" )
			)
			( pin "U7C1.G11"
				( objectStatus "@baseboard_fab2_lib.baseboard_fab2(sch_1):page118_i73:gpd6_slp_a_n" )
			)
			( pin "U7C1.H9"
				( objectStatus "@baseboard_fab2_lib.baseboard_fab2(sch_1):page118_i73:gpd7" )
			)
			( pin "U7C1.C13"
				( objectStatus "@baseboard_fab2_lib.baseboard_fab2(sch_1):page118_i73:gpd8_susclk" )
			)
			( pin "U7C1.A15"
				( objectStatus "@baseboard_fab2_lib.baseboard_fab2(sch_1):page118_i73:gpd9" )
			)
			( pin "U7C1.B14"
				( objectStatus "@baseboard_fab2_lib.baseboard_fab2(sch_1):page118_i73:gpd10_slp_s5_n" )
			)
			( pin "U7C1.A13"
				( objectStatus "@baseboard_fab2_lib.baseboard_fab2(sch_1):page118_i73:gpd11_gbephy" )
			)
			( pin "U7C1.AR54"
				( objectStatus "@baseboard_fab2_lib.baseboard_fab2(sch_1):page118_i73:itp_pmode" )
			)
			( pin "U7C1.AL56"
				( objectStatus "@baseboard_fab2_lib.baseboard_fab2(sch_1):page118_i73:jtag_tck" )
			)
			( pin "U7C1.AN54"
				( objectStatus "@baseboard_fab2_lib.baseboard_fab2(sch_1):page118_i73:jtag_tdi" )
			)
			( pin "U7C1.AP56"
				( objectStatus "@baseboard_fab2_lib.baseboard_fab2(sch_1):page118_i73:jtag_tdo" )
			)
			( pin "U7C1.AH54"
				( objectStatus "@baseboard_fab2_lib.baseboard_fab2(sch_1):page118_i73:jtag_tms" )
			)
			( pin "U7C1.AF54"
				( objectStatus "@baseboard_fab2_lib.baseboard_fab2(sch_1):page118_i73:jtagx" )
			)
			( pin "U7C1.BB29"
				( objectStatus "@baseboard_fab2_lib.baseboard_fab2(sch_1):page118_i73:lan_rbias_0" )
			)
			( pin "U7C1.BD42"
				( objectStatus "@baseboard_fab2_lib.baseboard_fab2(sch_1):page118_i73:lan_rbias_1" )
			)
			( pin "U7C1.BH31"
				( objectStatus "@baseboard_fab2_lib.baseboard_fab2(sch_1):page118_i73:lan_rx_p0n" )
			)
			( pin "U7C1.BF31"
				( objectStatus "@baseboard_fab2_lib.baseboard_fab2(sch_1):page118_i73:lan_rx_p0p" )
			)
			( pin "U7C1.BG29"
				( objectStatus "@baseboard_fab2_lib.baseboard_fab2(sch_1):page118_i73:lan_rx_p1n" )
			)
			( pin "U7C1.BJ29"
				( objectStatus "@baseboard_fab2_lib.baseboard_fab2(sch_1):page118_i73:lan_rx_p1p" )
			)
			( pin "U7C1.BJ37"
				( objectStatus "@baseboard_fab2_lib.baseboard_fab2(sch_1):page118_i73:lan_rx_p2n" )
			)
			( pin "U7C1.BG37"
				( objectStatus "@baseboard_fab2_lib.baseboard_fab2(sch_1):page118_i73:lan_rx_p2p" )
			)
			( pin "U7C1.BF35"
				( objectStatus "@baseboard_fab2_lib.baseboard_fab2(sch_1):page118_i73:lan_rx_p3n" )
			)
			( pin "U7C1.BH35"
				( objectStatus "@baseboard_fab2_lib.baseboard_fab2(sch_1):page118_i73:lan_rx_p3p" )
			)
			( pin "U7C1.BM27"
				( objectStatus "@baseboard_fab2_lib.baseboard_fab2(sch_1):page118_i73:lan_tx_p0n" )
			)
			( pin "U7C1.BR27"
				( objectStatus "@baseboard_fab2_lib.baseboard_fab2(sch_1):page118_i73:lan_tx_p0p" )
			)
			( pin "U7C1.BM24"
				( objectStatus "@baseboard_fab2_lib.baseboard_fab2(sch_1):page118_i73:lan_tx_p1n" )
			)
			( pin "U7C1.BR24"
				( objectStatus "@baseboard_fab2_lib.baseboard_fab2(sch_1):page118_i73:lan_tx_p1p" )
			)
			( pin "U7C1.BM35"
				( objectStatus "@baseboard_fab2_lib.baseboard_fab2(sch_1):page118_i73:lan_tx_p2n" )
			)
			( pin "U7C1.BR35"
				( objectStatus "@baseboard_fab2_lib.baseboard_fab2(sch_1):page118_i73:lan_tx_p2p" )
			)
			( pin "U7C1.BR31"
				( objectStatus "@baseboard_fab2_lib.baseboard_fab2(sch_1):page118_i73:lan_tx_p3n" )
			)
			( pin "U7C1.BM31"
				( objectStatus "@baseboard_fab2_lib.baseboard_fab2(sch_1):page118_i73:lan_tx_p3p" )
			)
			( pin "U7C1.BV16"
				( objectStatus "@baseboard_fab2_lib.baseboard_fab2(sch_1):page118_i73:lan_xtal_in" )
			)
			( pin "U7C1.BY16"
				( objectStatus "@baseboard_fab2_lib.baseboard_fab2(sch_1):page118_i73:lan_xtal_out" )
			)
			( pin "U7C1.R17"
				( objectStatus "@baseboard_fab2_lib.baseboard_fab2(sch_1):page118_i73:pch_pwrok" )
			)
			( pin "U7C1.U9"
				( objectStatus "@baseboard_fab2_lib.baseboard_fab2(sch_1):page118_i73:peci" )
			)
			( pin "U7C1.U17"
				( objectStatus "@baseboard_fab2_lib.baseboard_fab2(sch_1):page118_i73:pltrst_cpu_n" )
			)
			( pin "U7C1.U13"
				( objectStatus "@baseboard_fab2_lib.baseboard_fab2(sch_1):page118_i73:pm_sync" )
			)
			( pin "U7C1.V7"
				( objectStatus "@baseboard_fab2_lib.baseboard_fab2(sch_1):page118_i73:pm_sync2" )
			)
			( pin "U7C1.AD54"
				( objectStatus "@baseboard_fab2_lib.baseboard_fab2(sch_1):page118_i73:prdy_n" )
			)
			( pin "U7C1.U54"
				( objectStatus "@baseboard_fab2_lib.baseboard_fab2(sch_1):page118_i73:preq_n" )
			)
			( pin "U7C1.R9"
				( objectStatus "@baseboard_fab2_lib.baseboard_fab2(sch_1):page118_i73:proc_pwrgd" )
			)
			( pin "U7C1.P15"
				( objectStatus "@baseboard_fab2_lib.baseboard_fab2(sch_1):page118_i73:rsmrst_n" )
			)
			( pin "U7C1.AA54"
				( objectStatus "@baseboard_fab2_lib.baseboard_fab2(sch_1):page118_i73:rsvd(32)" )
			)
			( pin "U7C1.V56"
				( objectStatus "@baseboard_fab2_lib.baseboard_fab2(sch_1):page118_i73:rsvd(33)" )
			)
			( pin "U7C1.Y56"
				( objectStatus "@baseboard_fab2_lib.baseboard_fab2(sch_1):page118_i73:rsvd(34)" )
			)
			( pin "U7C1.W54"
				( objectStatus "@baseboard_fab2_lib.baseboard_fab2(sch_1):page118_i73:rsvd(35)" )
			)
			( pin "U7C1.AK54"
				( objectStatus "@baseboard_fab2_lib.baseboard_fab2(sch_1):page118_i73:rsvd(36)" )
			)
			( pin "U7C1.BN29"
				( objectStatus "@baseboard_fab2_lib.baseboard_fab2(sch_1):page118_i73:rsvd(37)" )
			)
			( pin "U7C1.BL29"
				( objectStatus "@baseboard_fab2_lib.baseboard_fab2(sch_1):page118_i73:rsvd(38)" )
			)
			( pin "U7C1.BL26"
				( objectStatus "@baseboard_fab2_lib.baseboard_fab2(sch_1):page118_i73:rsvd(39)" )
			)
			( pin "U7C1.BN26"
				( objectStatus "@baseboard_fab2_lib.baseboard_fab2(sch_1):page118_i73:rsvd(40)" )
			)
			( pin "U7C1.BJ40"
				( objectStatus "@baseboard_fab2_lib.baseboard_fab2(sch_1):page118_i73:rsvd(41)" )
			)
			( pin "U7C1.BG40"
				( objectStatus "@baseboard_fab2_lib.baseboard_fab2(sch_1):page118_i73:rsvd(42)" )
			)
			( pin "U7C1.BL33"
				( objectStatus "@baseboard_fab2_lib.baseboard_fab2(sch_1):page118_i73:rsvd(43)" )
			)
			( pin "U7C1.BN33"
				( objectStatus "@baseboard_fab2_lib.baseboard_fab2(sch_1):page118_i73:rsvd(44)" )
			)
			( pin "U7C1.P22"
				( objectStatus "@baseboard_fab2_lib.baseboard_fab2(sch_1):page118_i73:rsvd(45)" )
			)
			( pin "U7C1.P26"
				( objectStatus "@baseboard_fab2_lib.baseboard_fab2(sch_1):page118_i73:rsvd(53)" )
			)
			( pin "U7C1.R24"
				( objectStatus "@baseboard_fab2_lib.baseboard_fab2(sch_1):page118_i73:rsvd(54)" )
			)
			( pin "U7C1.M15"
				( objectStatus "@baseboard_fab2_lib.baseboard_fab2(sch_1):page118_i73:slp_gbe_n" )
			)
			( pin "U7C1.P7"
				( objectStatus "@baseboard_fab2_lib.baseboard_fab2(sch_1):page118_i73:slp_sus_n" )
			)
			( pin "U7C1.BY19"
				( objectStatus "@baseboard_fab2_lib.baseboard_fab2(sch_1):page118_i73:sys_pwrok" )
			)
			( pin "U7C1.BV19"
				( objectStatus "@baseboard_fab2_lib.baseboard_fab2(sch_1):page118_i73:sys_reset_n" )
			)
			( pin "U7C1.V15"
				( objectStatus "@baseboard_fab2_lib.baseboard_fab2(sch_1):page118_i73:thrmtrip_n" )
			)
			( pin "U7C1.M7"
				( objectStatus "@baseboard_fab2_lib.baseboard_fab2(sch_1):page118_i73:trigger_in" )
			)
			( pin "U7C1.R13"
				( objectStatus "@baseboard_fab2_lib.baseboard_fab2(sch_1):page118_i73:trigger_out" )
			)
			( pin "U7C1.K9"
				( objectStatus "@baseboard_fab2_lib.baseboard_fab2(sch_1):page118_i73:wake_n" )
			)
			( pin "Y8C1.1"
				( objectStatus "@baseboard_fab2_lib.baseboard_fab2(sch_1):page118_i76:a" )
			)
			( pin "Y8C1.3"
				( objectStatus "@baseboard_fab2_lib.baseboard_fab2(sch_1):page118_i76:b" )
			)
			( pin "C8C2.1"
				( objectStatus "@baseboard_fab2_lib.baseboard_fab2(sch_1):page118_i77:a" )
			)
			( pin "C8C2.2"
				( objectStatus "@baseboard_fab2_lib.baseboard_fab2(sch_1):page118_i77:b" )
			)
			( pin "C8C1.1"
				( objectStatus "@baseboard_fab2_lib.baseboard_fab2(sch_1):page118_i79:a" )
			)
			( pin "C8C1.2"
				( objectStatus "@baseboard_fab2_lib.baseboard_fab2(sch_1):page118_i79:b" )
			)
			( pin "R2N4.1"
				( objectStatus "@baseboard_fab2_lib.baseboard_fab2(sch_1):page118_i96:a" )
			)
			( pin "R2N4.2"
				( objectStatus "@baseboard_fab2_lib.baseboard_fab2(sch_1):page118_i96:b" )
			)
			( pin "R2M6.1"
				( objectStatus "@baseboard_fab2_lib.baseboard_fab2(sch_1):page118_i99:a" )
			)
			( pin "R2M6.2"
				( objectStatus "@baseboard_fab2_lib.baseboard_fab2(sch_1):page118_i99:b" )
			)
			( pin "R8C24.1"
				( objectStatus "@baseboard_fab2_lib.baseboard_fab2(sch_1):page118_i120:a" )
			)
			( pin "R8C24.2"
				( objectStatus "@baseboard_fab2_lib.baseboard_fab2(sch_1):page118_i120:b" )
			)
			( pin "R8C23.1"
				( objectStatus "@baseboard_fab2_lib.baseboard_fab2(sch_1):page118_i125:a" )
			)
			( pin "R8C23.2"
				( objectStatus "@baseboard_fab2_lib.baseboard_fab2(sch_1):page118_i125:b" )
			)
			( pin "R2N6.1"
				( objectStatus "@baseboard_fab2_lib.baseboard_fab2(sch_1):page118_i128:a" )
			)
			( pin "R2N6.2"
				( objectStatus "@baseboard_fab2_lib.baseboard_fab2(sch_1):page118_i128:b" )
			)
			( pin "R7D23.1"
				( objectStatus "@baseboard_fab2_lib.baseboard_fab2(sch_1):page118_i131:a" )
			)
			( pin "R7D23.2"
				( objectStatus "@baseboard_fab2_lib.baseboard_fab2(sch_1):page118_i131:b" )
			)
			( pin "C7D1.1"
				( objectStatus "@baseboard_fab2_lib.baseboard_fab2(sch_1):page118_i136:a" )
			)
			( pin "C7D1.2"
				( objectStatus "@baseboard_fab2_lib.baseboard_fab2(sch_1):page118_i136:b" )
			)
			( pin "U7D1.2"
				( objectStatus "@baseboard_fab2_lib.baseboard_fab2(sch_1):page118_i142:a" )
			)
			( pin "U7D1.4"
				( objectStatus "@baseboard_fab2_lib.baseboard_fab2(sch_1):page118_i142:b" )
			)
			( pin "U7D1.1"
				( objectStatus "@baseboard_fab2_lib.baseboard_fab2(sch_1):page118_i142:oe_n" )
			)
			( pin "R7C23.1"
				( objectStatus "@baseboard_fab2_lib.baseboard_fab2(sch_1):page118_i144:a" )
			)
			( pin "R7C23.2"
				( objectStatus "@baseboard_fab2_lib.baseboard_fab2(sch_1):page118_i144:b" )
			)
			( pin "U7C1.N3"
				( objectStatus "@baseboard_fab2_lib.baseboard_fab2(sch_1):page119_i115:gpp_a0_rcin_n_espi_alert1_n" )
			)
			( pin "U7C1.Y3"
				( objectStatus "@baseboard_fab2_lib.baseboard_fab2(sch_1):page119_i115:gpp_a1_lad0_espi_io0" )
			)
			( pin "U7C1.N1"
				( objectStatus "@baseboard_fab2_lib.baseboard_fab2(sch_1):page119_i115:gpp_a2_lad1_espi_io1" )
			)
			( pin "U7C1.W2"
				( objectStatus "@baseboard_fab2_lib.baseboard_fab2(sch_1):page119_i115:gpp_a3_lad2_espi_io2" )
			)
			( pin "U7C1.Y1"
				( objectStatus "@baseboard_fab2_lib.baseboard_fab2(sch_1):page119_i115:gpp_a4_lad3_espi_io3" )
			)
			( pin "U7C1.P4"
				( objectStatus "@baseboard_fab2_lib.baseboard_fab2(sch_1):page119_i115:gpp_a5_lframe_n_espi_cs0_n" )
			)
			( pin "U7C1.P2"
				( objectStatus "@baseboard_fab2_lib.baseboard_fab2(sch_1):page119_i115:gpp_a6_serirq_espi_cs1_n" )
			)
			( pin "U7C1.AA2"
				( objectStatus "@baseboard_fab2_lib.baseboard_fab2(sch_1):page119_i115:gpp_a7_pirqa_n_espi_alert0_n" )
			)
			( pin "U7C1.AB1"
				( objectStatus "@baseboard_fab2_lib.baseboard_fab2(sch_1):page119_i115:gpp_a8_clkrun_n" )
			)
			( pin "U7C1.R3"
				( objectStatus "@baseboard_fab2_lib.baseboard_fab2(sch_1):page119_i115:gpp_a9_clkout_lpc0_espi_clk" )
			)
			( pin "U7C1.AA4"
				( objectStatus "@baseboard_fab2_lib.baseboard_fab2(sch_1):page119_i115:gpp_a10_clkout_lpc1" )
			)
			( pin "U7C1.AC2"
				( objectStatus "@baseboard_fab2_lib.baseboard_fab2(sch_1):page119_i115:gpp_a11_pme_n" )
			)
			( pin "U7C1.R1"
				( objectStatus "@baseboard_fab2_lib.baseboard_fab2(sch_1):page119_i115:gpp_a12_bmbusy_n_sxexithldoff_n" )
			)
			( pin "U7C1.T4"
				( objectStatus "@baseboard_fab2_lib.baseboard_fab2(sch_1):page119_i115:gpp_a13_suswarn_n_suspwrdnack" )
			)
			( pin "U7C1.AB3"
				( objectStatus "@baseboard_fab2_lib.baseboard_fab2(sch_1):page119_i115:gpp_a14_espi_reset_n" )
			)
			( pin "U7C1.AC4"
				( objectStatus "@baseboard_fab2_lib.baseboard_fab2(sch_1):page119_i115:gpp_a15_susack_n" )
			)
			( pin "U7C1.T2"
				( objectStatus "@baseboard_fab2_lib.baseboard_fab2(sch_1):page119_i115:gpp_a16_clkout_lpc2" )
			)
			( pin "U7C1.AD1"
				( objectStatus "@baseboard_fab2_lib.baseboard_fab2(sch_1):page119_i115:gpp_a17" )
			)
			( pin "U7C1.AD3"
				( objectStatus "@baseboard_fab2_lib.baseboard_fab2(sch_1):page119_i115:gpp_a18" )
			)
			( pin "U7C1.V3"
				( objectStatus "@baseboard_fab2_lib.baseboard_fab2(sch_1):page119_i115:gpp_a19" )
			)
			( pin "U7C1.W4"
				( objectStatus "@baseboard_fab2_lib.baseboard_fab2(sch_1):page119_i115:gpp_a20" )
			)
			( pin "U7C1.AE2"
				( objectStatus "@baseboard_fab2_lib.baseboard_fab2(sch_1):page119_i115:gpp_a21" )
			)
			( pin "U7C1.AE4"
				( objectStatus "@baseboard_fab2_lib.baseboard_fab2(sch_1):page119_i115:gpp_a22" )
			)
			( pin "U7C1.V1"
				( objectStatus "@baseboard_fab2_lib.baseboard_fab2(sch_1):page119_i115:gpp_a23" )
			)
			( pin "U7C1.BL7"
				( objectStatus "@baseboard_fab2_lib.baseboard_fab2(sch_1):page119_i115:gpp_b0_core_vid0" )
			)
			( pin "U7C1.BH9"
				( objectStatus "@baseboard_fab2_lib.baseboard_fab2(sch_1):page119_i115:gpp_b1_core_vid1" )
			)
			( pin "U7C1.BN15"
				( objectStatus "@baseboard_fab2_lib.baseboard_fab2(sch_1):page119_i115:gpp_b2" )
			)
			( pin "U7C1.BR9"
				( objectStatus "@baseboard_fab2_lib.baseboard_fab2(sch_1):page119_i115:gpp_b3_cpu_gp2" )
			)
			( pin "U7C1.BN7"
				( objectStatus "@baseboard_fab2_lib.baseboard_fab2(sch_1):page119_i115:gpp_b4_cpu_gp3" )
			)
			( pin "U7C1.BK17"
				( objectStatus "@baseboard_fab2_lib.baseboard_fab2(sch_1):page119_i115:gpp_b5_srcclkreq0_n" )
			)
			( pin "U7C1.BG18"
				( objectStatus "@baseboard_fab2_lib.baseboard_fab2(sch_1):page119_i115:gpp_b6_srcclkreq1_n" )
			)
			( pin "U7C1.BR13"
				( objectStatus "@baseboard_fab2_lib.baseboard_fab2(sch_1):page119_i115:gpp_b7_srcclkreq2_n" )
			)
			( pin "U7C1.BN11"
				( objectStatus "@baseboard_fab2_lib.baseboard_fab2(sch_1):page119_i115:gpp_b8_srcclkreq3_n" )
			)
			( pin "U7C1.BH20"
				( objectStatus "@baseboard_fab2_lib.baseboard_fab2(sch_1):page119_i115:gpp_b9_srcclkreq4_n" )
			)
			( pin "U7C1.BL11"
				( objectStatus "@baseboard_fab2_lib.baseboard_fab2(sch_1):page119_i115:gpp_b10_srcclkreq5_n" )
			)
			( pin "U7C1.BK9"
				( objectStatus "@baseboard_fab2_lib.baseboard_fab2(sch_1):page119_i115:gpp_b11" )
			)
			( pin "U7C1.BL18"
				( objectStatus "@baseboard_fab2_lib.baseboard_fab2(sch_1):page119_i115:gpp_b12_glb_rst_warn_n" )
			)
			( pin "U7C1.BN18"
				( objectStatus "@baseboard_fab2_lib.baseboard_fab2(sch_1):page119_i115:gpp_b13_pltrst_n" )
			)
			( pin "U7C1.BH13"
				( objectStatus "@baseboard_fab2_lib.baseboard_fab2(sch_1):page119_i115:gpp_b14_spkr" )
			)
			( pin "U7C1.BK13"
				( objectStatus "@baseboard_fab2_lib.baseboard_fab2(sch_1):page119_i115:gpp_b15" )
			)
			( pin "U7C1.BG22"
				( objectStatus "@baseboard_fab2_lib.baseboard_fab2(sch_1):page119_i115:gpp_b16" )
			)
			( pin "U7C1.BG15"
				( objectStatus "@baseboard_fab2_lib.baseboard_fab2(sch_1):page119_i115:gpp_b17" )
			)
			( pin "U7C1.BL15"
				( objectStatus "@baseboard_fab2_lib.baseboard_fab2(sch_1):page119_i115:gpp_b18" )
			)
			( pin "U7C1.BK20"
				( objectStatus "@baseboard_fab2_lib.baseboard_fab2(sch_1):page119_i115:gpp_b19" )
			)
			( pin "U7C1.BJ22"
				( objectStatus "@baseboard_fab2_lib.baseboard_fab2(sch_1):page119_i115:gpp_b20" )
			)
			( pin "U7C1.BH17"
				( objectStatus "@baseboard_fab2_lib.baseboard_fab2(sch_1):page119_i115:gpp_b21" )
			)
			( pin "U7C1.BR17"
				( objectStatus "@baseboard_fab2_lib.baseboard_fab2(sch_1):page119_i115:gpp_b22" )
			)
			( pin "U7C1.BM20"
				( objectStatus "@baseboard_fab2_lib.baseboard_fab2(sch_1):page119_i115:gpp_b23_meie_sml1alrt_n_phot_n" )
			)
			( pin "U7C1.BW28"
				( objectStatus "@baseboard_fab2_lib.baseboard_fab2(sch_1):page119_i115:gpp_c0_smbclk" )
			)
			( pin "U7C1.BV27"
				( objectStatus "@baseboard_fab2_lib.baseboard_fab2(sch_1):page119_i115:gpp_c1_smbdata" )
			)
			( pin "U7C1.BY27"
				( objectStatus "@baseboard_fab2_lib.baseboard_fab2(sch_1):page119_i115:gpp_c2_smbalert_n" )
			)
			( pin "U7C1.BV29"
				( objectStatus "@baseboard_fab2_lib.baseboard_fab2(sch_1):page119_i115:gpp_c3_sml0clk_ie" )
			)
			( pin "U7C1.BW30"
				( objectStatus "@baseboard_fab2_lib.baseboard_fab2(sch_1):page119_i115:gpp_c4_sml0data_ie" )
			)
			( pin "U7C1.BW34"
				( objectStatus "@baseboard_fab2_lib.baseboard_fab2(sch_1):page119_i115:gpp_c5_sml0alert_ie_n" )
			)
			( pin "U7C1.CA28"
				( objectStatus "@baseboard_fab2_lib.baseboard_fab2(sch_1):page119_i115:gpp_c6_sml1clk_ie" )
			)
			( pin "U7C1.BV35"
				( objectStatus "@baseboard_fab2_lib.baseboard_fab2(sch_1):page119_i115:gpp_c7_sml1data_ie" )
			)
			( pin "U7C1.BW32"
				( objectStatus "@baseboard_fab2_lib.baseboard_fab2(sch_1):page119_i115:gpp_c8" )
			)
			( pin "U7C1.BY29"
				( objectStatus "@baseboard_fab2_lib.baseboard_fab2(sch_1):page119_i115:gpp_c9" )
			)
			( pin "U7C1.BV31"
				( objectStatus "@baseboard_fab2_lib.baseboard_fab2(sch_1):page119_i115:gpp_c10" )
			)
			( pin "U7C1.BV33"
				( objectStatus "@baseboard_fab2_lib.baseboard_fab2(sch_1):page119_i115:gpp_c11" )
			)
			( pin "U7C1.CA30"
				( objectStatus "@baseboard_fab2_lib.baseboard_fab2(sch_1):page119_i115:gpp_c12" )
			)
			( pin "U7C1.BV38"
				( objectStatus "@baseboard_fab2_lib.baseboard_fab2(sch_1):page119_i115:gpp_c13" )
			)
			( pin "U7C1.BY38"
				( objectStatus "@baseboard_fab2_lib.baseboard_fab2(sch_1):page119_i115:gpp_c14" )
			)
			( pin "U7C1.CA32"
				( objectStatus "@baseboard_fab2_lib.baseboard_fab2(sch_1):page119_i115:gpp_c15" )
			)
			( pin "U7C1.BW37"
				( objectStatus "@baseboard_fab2_lib.baseboard_fab2(sch_1):page119_i115:gpp_c16" )
			)
			( pin "U7C1.BY31"
				( objectStatus "@baseboard_fab2_lib.baseboard_fab2(sch_1):page119_i115:gpp_c17" )
			)
			( pin "U7C1.BY35"
				( objectStatus "@baseboard_fab2_lib.baseboard_fab2(sch_1):page119_i115:gpp_c18" )
			)
			( pin "U7C1.BW39"
				( objectStatus "@baseboard_fab2_lib.baseboard_fab2(sch_1):page119_i115:gpp_c19" )
			)
			( pin "U7C1.CA39"
				( objectStatus "@baseboard_fab2_lib.baseboard_fab2(sch_1):page119_i115:gpp_c20" )
			)
			( pin "U7C1.BY33"
				( objectStatus "@baseboard_fab2_lib.baseboard_fab2(sch_1):page119_i115:gpp_c21" )
			)
			( pin "U7C1.CA34"
				( objectStatus "@baseboard_fab2_lib.baseboard_fab2(sch_1):page119_i115:gpp_c22" )
			)
			( pin "U7C1.CA37"
				( objectStatus "@baseboard_fab2_lib.baseboard_fab2(sch_1):page119_i115:gpp_c23" )
			)
			( pin "U7C1.BR42"
				( objectStatus "@baseboard_fab2_lib.baseboard_fab2(sch_1):page119_i115:gpp_d0" )
			)
			( pin "U7C1.BK46"
				( objectStatus "@baseboard_fab2_lib.baseboard_fab2(sch_1):page119_i115:gpp_d1" )
			)
			( pin "U7C1.BJ44"
				( objectStatus "@baseboard_fab2_lib.baseboard_fab2(sch_1):page119_i115:gpp_d2" )
			)
			( pin "U7C1.BW45"
				( objectStatus "@baseboard_fab2_lib.baseboard_fab2(sch_1):page119_i115:gpp_d3" )
			)
			( pin "U7C1.BM42"
				( objectStatus "@baseboard_fab2_lib.baseboard_fab2(sch_1):page119_i115:gpp_d4" )
			)
			( pin "U7C1.BM38"
				( objectStatus "@baseboard_fab2_lib.baseboard_fab2(sch_1):page119_i115:gpp_d5" )
			)
			( pin "U7C1.BW41"
				( objectStatus "@baseboard_fab2_lib.baseboard_fab2(sch_1):page119_i115:gpp_d6" )
			)
			( pin "U7C1.CA45"
				( objectStatus "@baseboard_fab2_lib.baseboard_fab2(sch_1):page119_i115:gpp_d7" )
			)
			( pin "U7C1.BR38"
				( objectStatus "@baseboard_fab2_lib.baseboard_fab2(sch_1):page119_i115:gpp_d8" )
			)
			( pin "U7C1.BY42"
				( objectStatus "@baseboard_fab2_lib.baseboard_fab2(sch_1):page119_i115:gpp_d9_ssata_devslp3" )
			)
			( pin "U7C1.BV47"
				( objectStatus "@baseboard_fab2_lib.baseboard_fab2(sch_1):page119_i115:gpp_d10_ssata_devslp4" )
			)
			( pin "U7C1.BY47"
				( objectStatus "@baseboard_fab2_lib.baseboard_fab2(sch_1):page119_i115:gpp_d11_ssata_devslp5" )
			)
			( pin "U7C1.BN40"
				( objectStatus "@baseboard_fab2_lib.baseboard_fab2(sch_1):page119_i115:gpp_d12_ssata_sdataout1" )
			)
			( pin "U7C1.BY44"
				( objectStatus "@baseboard_fab2_lib.baseboard_fab2(sch_1):page119_i115:gpp_d13_sml0bclk_ie" )
			)
			( pin "U7C1.BL44"
				( objectStatus "@baseboard_fab2_lib.baseboard_fab2(sch_1):page119_i115:gpp_d14_sml0bdata_ie" )
			)
			( pin "U7C1.BW43"
				( objectStatus "@baseboard_fab2_lib.baseboard_fab2(sch_1):page119_i115:gpp_d15_ssata_sdataout0" )
			)
			( pin "U7C1.BV42"
				( objectStatus "@baseboard_fab2_lib.baseboard_fab2(sch_1):page119_i115:gpp_d16_sml0balert_ie_n" )
			)
			( pin "U7C1.BW48"
				( objectStatus "@baseboard_fab2_lib.baseboard_fab2(sch_1):page119_i115:gpp_d17" )
			)
			( pin "U7C1.CA41"
				( objectStatus "@baseboard_fab2_lib.baseboard_fab2(sch_1):page119_i115:gpp_d18" )
			)
			( pin "U7C1.CA43"
				( objectStatus "@baseboard_fab2_lib.baseboard_fab2(sch_1):page119_i115:gpp_d19" )
			)
			( pin "U7C1.CA48"
				( objectStatus "@baseboard_fab2_lib.baseboard_fab2(sch_1):page119_i115:gpp_d20" )
			)
			( pin "U7C1.BV44"
				( objectStatus "@baseboard_fab2_lib.baseboard_fab2(sch_1):page119_i115:gpp_d21_ie_uart_rx" )
			)
			( pin "U7C1.BR46"
				( objectStatus "@baseboard_fab2_lib.baseboard_fab2(sch_1):page119_i115:gpp_d22_ie_uart_tx" )
			)
			( pin "U7C1.BN44"
				( objectStatus "@baseboard_fab2_lib.baseboard_fab2(sch_1):page119_i115:gpp_d23" )
			)
			( pin "R2M3.1"
				( objectStatus "@baseboard_fab2_lib.baseboard_fab2(sch_1):page119_i172:a" )
			)
			( pin "R2M3.2"
				( objectStatus "@baseboard_fab2_lib.baseboard_fab2(sch_1):page119_i172:b" )
			)
			( pin "R2N1.1"
				( objectStatus "@baseboard_fab2_lib.baseboard_fab2(sch_1):page119_i173:a" )
			)
			( pin "R2N1.2"
				( objectStatus "@baseboard_fab2_lib.baseboard_fab2(sch_1):page119_i173:b" )
			)
			( pin "R2M7.1"
				( objectStatus "@baseboard_fab2_lib.baseboard_fab2(sch_1):page119_i174:a" )
			)
			( pin "R2M7.2"
				( objectStatus "@baseboard_fab2_lib.baseboard_fab2(sch_1):page119_i174:b" )
			)
			( pin "Q9A2.6"
				( objectStatus "@baseboard_fab2_lib.baseboard_fab2(sch_1):page119_i175:drain(0)" )
			)
			( pin "Q9A2.2"
				( objectStatus "@baseboard_fab2_lib.baseboard_fab2(sch_1):page119_i175:gate(0)" )
			)
			( pin "Q9A2.1"
				( objectStatus "@baseboard_fab2_lib.baseboard_fab2(sch_1):page119_i175:source(0)" )
			)
			( pin "R9A20.1"
				( objectStatus "@baseboard_fab2_lib.baseboard_fab2(sch_1):page119_i178:a" )
			)
			( pin "R9A20.2"
				( objectStatus "@baseboard_fab2_lib.baseboard_fab2(sch_1):page119_i178:b" )
			)
			( pin "DS9A5.1"
				( objectStatus "@baseboard_fab2_lib.baseboard_fab2(sch_1):page119_i179:a" )
			)
			( pin "DS9A5.2"
				( objectStatus "@baseboard_fab2_lib.baseboard_fab2(sch_1):page119_i179:c" )
			)
			( pin "Q9A2.3"
				( objectStatus "@baseboard_fab2_lib.baseboard_fab2(sch_1):page119_i180:drain(0)" )
			)
			( pin "Q9A2.5"
				( objectStatus "@baseboard_fab2_lib.baseboard_fab2(sch_1):page119_i180:gate(0)" )
			)
			( pin "Q9A2.4"
				( objectStatus "@baseboard_fab2_lib.baseboard_fab2(sch_1):page119_i180:source(0)" )
			)
			( pin "R9A18.1"
				( objectStatus "@baseboard_fab2_lib.baseboard_fab2(sch_1):page119_i183:a" )
			)
			( pin "R9A18.2"
				( objectStatus "@baseboard_fab2_lib.baseboard_fab2(sch_1):page119_i183:b" )
			)
			( pin "R9A21.1"
				( objectStatus "@baseboard_fab2_lib.baseboard_fab2(sch_1):page119_i186:a" )
			)
			( pin "R9A21.2"
				( objectStatus "@baseboard_fab2_lib.baseboard_fab2(sch_1):page119_i186:b" )
			)
			( pin "R7C26.1"
				( objectStatus "@baseboard_fab2_lib.baseboard_fab2(sch_1):page119_i189:a" )
			)
			( pin "R7C26.2"
				( objectStatus "@baseboard_fab2_lib.baseboard_fab2(sch_1):page119_i189:b" )
			)
			( pin "R2U48.1"
				( objectStatus "@baseboard_fab2_lib.baseboard_fab2(sch_1):page119_i213:a" )
			)
			( pin "R2U48.2"
				( objectStatus "@baseboard_fab2_lib.baseboard_fab2(sch_1):page119_i213:b" )
			)
			( pin "R2U50.1"
				( objectStatus "@baseboard_fab2_lib.baseboard_fab2(sch_1):page119_i215:a" )
			)
			( pin "R2U50.2"
				( objectStatus "@baseboard_fab2_lib.baseboard_fab2(sch_1):page119_i215:b" )
			)
			( pin "U7C1.BY25"
				( objectStatus "@baseboard_fab2_lib.baseboard_fab2(sch_1):page120_i147:gpio_rcomp_3p3" )
			)
			( pin "U7C1.BH50"
				( objectStatus "@baseboard_fab2_lib.baseboard_fab2(sch_1):page120_i147:gpp_e0_sataxpcie0_satagp0" )
			)
			( pin "U7C1.AY52"
				( objectStatus "@baseboard_fab2_lib.baseboard_fab2(sch_1):page120_i147:gpp_e1_sataxpcie1_satagp1" )
			)
			( pin "U7C1.BG52"
				( objectStatus "@baseboard_fab2_lib.baseboard_fab2(sch_1):page120_i147:gpp_e2_sataxpcie2_satagp2" )
			)
			( pin "U7C1.BE52"
				( objectStatus "@baseboard_fab2_lib.baseboard_fab2(sch_1):page120_i147:gpp_e3_cpu_gp0" )
			)
			( pin "U7C1.AV52"
				( objectStatus "@baseboard_fab2_lib.baseboard_fab2(sch_1):page120_i147:gpp_e4_sata_devslp0" )
			)
			( pin "U7C1.AT52"
				( objectStatus "@baseboard_fab2_lib.baseboard_fab2(sch_1):page120_i147:gpp_e5_sata_devslp1" )
			)
			( pin "U7C1.BB52"
				( objectStatus "@baseboard_fab2_lib.baseboard_fab2(sch_1):page120_i147:gpp_e6_sata_devslp2" )
			)
			( pin "U7C1.BJ48"
				( objectStatus "@baseboard_fab2_lib.baseboard_fab2(sch_1):page120_i147:gpp_e7_cpu_gp1" )
			)
			( pin "U7C1.AV56"
				( objectStatus "@baseboard_fab2_lib.baseboard_fab2(sch_1):page120_i147:gpp_e8_sata_led_n" )
			)
			( pin "U7C1.BL48"
				( objectStatus "@baseboard_fab2_lib.baseboard_fab2(sch_1):page120_i147:gpp_e9_usb2_oc0_n" )
			)
			( pin "U7C1.BN48"
				( objectStatus "@baseboard_fab2_lib.baseboard_fab2(sch_1):page120_i147:gpp_e10_usb2_oc1_n" )
			)
			( pin "U7C1.AW54"
				( objectStatus "@baseboard_fab2_lib.baseboard_fab2(sch_1):page120_i147:gpp_e11_usb2_oc2_n" )
			)
			( pin "U7C1.AU58"
				( objectStatus "@baseboard_fab2_lib.baseboard_fab2(sch_1):page120_i147:gpp_e12_usb2_oc3_n" )
			)
			( pin "U7C1.AG7"
				( objectStatus "@baseboard_fab2_lib.baseboard_fab2(sch_1):page120_i147:gpp_f0_sataxpcie3_satagp3" )
			)
			( pin "U7C1.AK9"
				( objectStatus "@baseboard_fab2_lib.baseboard_fab2(sch_1):page120_i147:gpp_f1_sataxpcie4_satagp4" )
			)
			( pin "U7C1.AK20"
				( objectStatus "@baseboard_fab2_lib.baseboard_fab2(sch_1):page120_i147:gpp_f2_sataxpcie5_satagp5" )
			)
			( pin "U7C1.AK13"
				( objectStatus "@baseboard_fab2_lib.baseboard_fab2(sch_1):page120_i147:gpp_f3_sataxpcie6_satagp6" )
			)
			( pin "U7C1.AH13"
				( objectStatus "@baseboard_fab2_lib.baseboard_fab2(sch_1):page120_i147:gpp_f4_sataxpcie7_satagp7" )
			)
			( pin "U7C1.AH17"
				( objectStatus "@baseboard_fab2_lib.baseboard_fab2(sch_1):page120_i147:gpp_f5_sata_devslp3" )
			)
			( pin "U7C1.AL18"
				( objectStatus "@baseboard_fab2_lib.baseboard_fab2(sch_1):page120_i147:gpp_f6_sata_devslp4" )
			)
			( pin "U7C1.AK17"
				( objectStatus "@baseboard_fab2_lib.baseboard_fab2(sch_1):page120_i147:gpp_f7_sata_devslp5" )
			)
			( pin "U7C1.AH9"
				( objectStatus "@baseboard_fab2_lib.baseboard_fab2(sch_1):page120_i147:gpp_f8_sata_devslp6" )
			)
			( pin "U7C1.AR20"
				( objectStatus "@baseboard_fab2_lib.baseboard_fab2(sch_1):page120_i147:gpp_f9_sata_devslp7" )
			)
			( pin "U7C1.AL7"
				( objectStatus "@baseboard_fab2_lib.baseboard_fab2(sch_1):page120_i147:gpp_f10_sata_sclock" )
			)
			( pin "U7C1.AR9"
				( objectStatus "@baseboard_fab2_lib.baseboard_fab2(sch_1):page120_i147:gpp_f11_sata_sload" )
			)
			( pin "U7C1.AP7"
				( objectStatus "@baseboard_fab2_lib.baseboard_fab2(sch_1):page120_i147:gpp_f12_sata_sdataout1" )
			)
			( pin "U7C1.AP11"
				( objectStatus "@baseboard_fab2_lib.baseboard_fab2(sch_1):page120_i147:gpp_f13_sata_sdataout0" )
			)
			( pin "U7C1.AL11"
				( objectStatus "@baseboard_fab2_lib.baseboard_fab2(sch_1):page120_i147:gpp_f14_ssata_led_n" )
			)
			( pin "U7C1.AR13"
				( objectStatus "@baseboard_fab2_lib.baseboard_fab2(sch_1):page120_i147:gpp_f15_usb2_oc4_n" )
			)
			( pin "U7C1.AU13"
				( objectStatus "@baseboard_fab2_lib.baseboard_fab2(sch_1):page120_i147:gpp_f16_usb2_oc5_n" )
			)
			( pin "U7C1.AP15"
				( objectStatus "@baseboard_fab2_lib.baseboard_fab2(sch_1):page120_i147:gpp_f17_usb2_oc6_n" )
			)
			( pin "U7C1.AL15"
				( objectStatus "@baseboard_fab2_lib.baseboard_fab2(sch_1):page120_i147:gpp_f18_usb2_oc7_n" )
			)
			( pin "U7C1.AU9"
				( objectStatus "@baseboard_fab2_lib.baseboard_fab2(sch_1):page120_i147:gpp_f19_lan_smbclk" )
			)
			( pin "U7C1.AU20"
				( objectStatus "@baseboard_fab2_lib.baseboard_fab2(sch_1):page120_i147:gpp_f20_lan_smbdata" )
			)
			( pin "U7C1.AR17"
				( objectStatus "@baseboard_fab2_lib.baseboard_fab2(sch_1):page120_i147:gpp_f21_lan_smbalrt_n" )
			)
			( pin "U7C1.AP18"
				( objectStatus "@baseboard_fab2_lib.baseboard_fab2(sch_1):page120_i147:gpp_f22_ssata_sclock" )
			)
			( pin "U7C1.AU17"
				( objectStatus "@baseboard_fab2_lib.baseboard_fab2(sch_1):page120_i147:gpp_f23_ssata_sload" )
			)
			( pin "U7C1.AY11"
				( objectStatus "@baseboard_fab2_lib.baseboard_fab2(sch_1):page120_i147:gpp_g0_fantach0_fantach0ie" )
			)
			( pin "U7C1.AV15"
				( objectStatus "@baseboard_fab2_lib.baseboard_fab2(sch_1):page120_i147:gpp_g1_fantach1_fantach1ie" )
			)
			( pin "U7C1.BE22"
				( objectStatus "@baseboard_fab2_lib.baseboard_fab2(sch_1):page120_i147:gpp_g2_fantach2_fantach2ie" )
			)
			( pin "U7C1.AY7"
				( objectStatus "@baseboard_fab2_lib.baseboard_fab2(sch_1):page120_i147:gpp_g3_fantach3_fantach3ie" )
			)
			( pin "U7C1.BA9"
				( objectStatus "@baseboard_fab2_lib.baseboard_fab2(sch_1):page120_i147:gpp_g4_fantach4_fantach4ie" )
			)
			( pin "U7C1.AW20"
				( objectStatus "@baseboard_fab2_lib.baseboard_fab2(sch_1):page120_i147:gpp_g5_fantach5_fantach5ie" )
			)
			( pin "U7C1.AV18"
				( objectStatus "@baseboard_fab2_lib.baseboard_fab2(sch_1):page120_i147:gpp_g6_fantach6_fantach6ie" )
			)
			( pin "U7C1.AY15"
				( objectStatus "@baseboard_fab2_lib.baseboard_fab2(sch_1):page120_i147:gpp_g7_fantach7_fantach7ie" )
			)
			( pin "U7C1.BG11"
				( objectStatus "@baseboard_fab2_lib.baseboard_fab2(sch_1):page120_i147:gpp_g8_fanpwm0_fanpwm0ie" )
			)
			( pin "U7C1.AV11"
				( objectStatus "@baseboard_fab2_lib.baseboard_fab2(sch_1):page120_i147:gpp_g9_fanpwm1_fampwm1ie" )
			)
			( pin "U7C1.BE11"
				( objectStatus "@baseboard_fab2_lib.baseboard_fab2(sch_1):page120_i147:gpp_g10_fanpwm2_fanpwm2ie" )
			)
			( pin "U7C1.BA20"
				( objectStatus "@baseboard_fab2_lib.baseboard_fab2(sch_1):page120_i147:gpp_g11_fanpwm3_fanpmw3ie" )
			)
			( pin "U7C1.BD13"
				( objectStatus "@baseboard_fab2_lib.baseboard_fab2(sch_1):page120_i147:gpp_g12" )
			)
			( pin "U7C1.AY18"
				( objectStatus "@baseboard_fab2_lib.baseboard_fab2(sch_1):page120_i147:gpp_g13" )
			)
			( pin "U7C1.AV7"
				( objectStatus "@baseboard_fab2_lib.baseboard_fab2(sch_1):page120_i147:gpp_g14" )
			)
			( pin "U7C1.BE18"
				( objectStatus "@baseboard_fab2_lib.baseboard_fab2(sch_1):page120_i147:gpp_g15" )
			)
			( pin "U7C1.BD17"
				( objectStatus "@baseboard_fab2_lib.baseboard_fab2(sch_1):page120_i147:gpp_g16" )
			)
			( pin "U7C1.BD9"
				( objectStatus "@baseboard_fab2_lib.baseboard_fab2(sch_1):page120_i147:gpp_g17_adr_complete" )
			)
			( pin "U7C1.BE7"
				( objectStatus "@baseboard_fab2_lib.baseboard_fab2(sch_1):page120_i147:gpp_g18_nmi_n" )
			)
			( pin "U7C1.BE15"
				( objectStatus "@baseboard_fab2_lib.baseboard_fab2(sch_1):page120_i147:gpp_g19_smi_n" )
			)
			( pin "U7C1.BA17"
				( objectStatus "@baseboard_fab2_lib.baseboard_fab2(sch_1):page120_i147:gpp_g20_ssata_devslp0" )
			)
			( pin "U7C1.BG7"
				( objectStatus "@baseboard_fab2_lib.baseboard_fab2(sch_1):page120_i147:gpp_g21_ssata_devslp1" )
			)
			( pin "U7C1.BD20"
				( objectStatus "@baseboard_fab2_lib.baseboard_fab2(sch_1):page120_i147:gpp_g22_ssata_devslp2" )
			)
			( pin "U7C1.BA13"
				( objectStatus "@baseboard_fab2_lib.baseboard_fab2(sch_1):page120_i147:gpp_g23_ssataxpcie0_ssatagp0" )
			)
			( pin "U7C1.AT4"
				( objectStatus "@baseboard_fab2_lib.baseboard_fab2(sch_1):page120_i147:gpp_h0_srcclkreq6_n" )
			)
			( pin "U7C1.AW4"
				( objectStatus "@baseboard_fab2_lib.baseboard_fab2(sch_1):page120_i147:gpp_h1_srcclkreq7_n" )
			)
			( pin "U7C1.AV3"
				( objectStatus "@baseboard_fab2_lib.baseboard_fab2(sch_1):page120_i147:gpp_h2_srcclkreq8_n" )
			)
			( pin "U7C1.AR1"
				( objectStatus "@baseboard_fab2_lib.baseboard_fab2(sch_1):page120_i147:gpp_h3_srcclkreq9_n" )
			)
			( pin "U7C1.AT2"
				( objectStatus "@baseboard_fab2_lib.baseboard_fab2(sch_1):page120_i147:gpp_h4_srcclkreq10_n" )
			)
			( pin "U7C1.AY3"
				( objectStatus "@baseboard_fab2_lib.baseboard_fab2(sch_1):page120_i147:gpp_h5_srcclkreq11_n" )
			)
			( pin "U7C1.AW2"
				( objectStatus "@baseboard_fab2_lib.baseboard_fab2(sch_1):page120_i147:gpp_h6_srcclkreq12_n" )
			)
			( pin "U7C1.AV1"
				( objectStatus "@baseboard_fab2_lib.baseboard_fab2(sch_1):page120_i147:gpp_h7_srcclkreq13_n" )
			)
			( pin "U7C1.AR3"
				( objectStatus "@baseboard_fab2_lib.baseboard_fab2(sch_1):page120_i147:gpp_h8_srcclkreq14_n" )
			)
			( pin "U7C1.BE2"
				( objectStatus "@baseboard_fab2_lib.baseboard_fab2(sch_1):page120_i147:gpp_h9_srcclkreq15_n" )
			)
			( pin "U7C1.BA4"
				( objectStatus "@baseboard_fab2_lib.baseboard_fab2(sch_1):page120_i147:gpp_h10_sml2clk_ie" )
			)
			( pin "U7C1.BD1"
				( objectStatus "@baseboard_fab2_lib.baseboard_fab2(sch_1):page120_i147:gpp_h11_sml2data_ie" )
			)
			( pin "U7C1.BB1"
				( objectStatus "@baseboard_fab2_lib.baseboard_fab2(sch_1):page120_i147:gpp_h12_sml2alert_n_ie_n" )
			)
			( pin "U7C1.AY1"
				( objectStatus "@baseboard_fab2_lib.baseboard_fab2(sch_1):page120_i147:gpp_h13_sml3clk_ie" )
			)
			( pin "U7C1.BC2"
				( objectStatus "@baseboard_fab2_lib.baseboard_fab2(sch_1):page120_i147:gpp_h14_sml3data_ie" )
			)
			( pin "U7C1.BB3"
				( objectStatus "@baseboard_fab2_lib.baseboard_fab2(sch_1):page120_i147:gpp_h15_sml3alert_n_ie_n" )
			)
			( pin "U7C1.BF1"
				( objectStatus "@baseboard_fab2_lib.baseboard_fab2(sch_1):page120_i147:gpp_h16_sml4clk_ie" )
			)
			( pin "U7C1.BE4"
				( objectStatus "@baseboard_fab2_lib.baseboard_fab2(sch_1):page120_i147:gpp_h17_sml4data_ie" )
			)
			( pin "U7C1.BC4"
				( objectStatus "@baseboard_fab2_lib.baseboard_fab2(sch_1):page120_i147:gpp_h18_sml4alert_n_ie_n" )
			)
			( pin "U7C1.BD3"
				( objectStatus "@baseboard_fab2_lib.baseboard_fab2(sch_1):page120_i147:gpp_h19_ssataxpcie1_ssatagp1" )
			)
			( pin "U7C1.BF3"
				( objectStatus "@baseboard_fab2_lib.baseboard_fab2(sch_1):page120_i147:gpp_h20_ssataxpcie2_ssatagp2" )
			)
			( pin "U7C1.BA2"
				( objectStatus "@baseboard_fab2_lib.baseboard_fab2(sch_1):page120_i147:gpp_h21_ssataxpcie3_ssatagp3" )
			)
			( pin "U7C1.BH2"
				( objectStatus "@baseboard_fab2_lib.baseboard_fab2(sch_1):page120_i147:gpp_h22_ssataxpcie4_ssatagp4" )
			)
			( pin "U7C1.BH4"
				( objectStatus "@baseboard_fab2_lib.baseboard_fab2(sch_1):page120_i147:gpp_h23_ssataxpcie5_ssatagp5" )
			)
			( pin "U7C1.CA20"
				( objectStatus "@baseboard_fab2_lib.baseboard_fab2(sch_1):page120_i147:gpp_i0_lan_tdo" )
			)
			( pin "U7C1.BV21"
				( objectStatus "@baseboard_fab2_lib.baseboard_fab2(sch_1):page120_i147:gpp_i1_lan_tck" )
			)
			( pin "U7C1.CA22"
				( objectStatus "@baseboard_fab2_lib.baseboard_fab2(sch_1):page120_i147:gpp_i2_lan_tms" )
			)
			( pin "U7C1.BY23"
				( objectStatus "@baseboard_fab2_lib.baseboard_fab2(sch_1):page120_i147:gpp_i3_lan_tdi" )
			)
			( pin "U7C1.BW20"
				( objectStatus "@baseboard_fab2_lib.baseboard_fab2(sch_1):page120_i147:gpp_i4_do_reset_in_n" )
			)
			( pin "U7C1.BW24"
				( objectStatus "@baseboard_fab2_lib.baseboard_fab2(sch_1):page120_i147:gpp_i5_do_reset_out_n" )
			)
			( pin "U7C1.BV23"
				( objectStatus "@baseboard_fab2_lib.baseboard_fab2(sch_1):page120_i147:gpp_i6_reset_done" )
			)
			( pin "U7C1.CA24"
				( objectStatus "@baseboard_fab2_lib.baseboard_fab2(sch_1):page120_i147:gpp_i7_lan_trst_n" )
			)
			( pin "U7C1.BW22"
				( objectStatus "@baseboard_fab2_lib.baseboard_fab2(sch_1):page120_i147:gpp_i8_pci_dis_n" )
			)
			( pin "U7C1.BY21"
				( objectStatus "@baseboard_fab2_lib.baseboard_fab2(sch_1):page120_i147:gpp_i9_lan_dis_n" )
			)
			( pin "U7C1.BV25"
				( objectStatus "@baseboard_fab2_lib.baseboard_fab2(sch_1):page120_i147:gpp_i10" )
			)
			( pin "U7C1.BL1"
				( objectStatus "@baseboard_fab2_lib.baseboard_fab2(sch_1):page120_i147:gpp_j0_lan_led_p0_0" )
			)
			( pin "U7C1.BK4"
				( objectStatus "@baseboard_fab2_lib.baseboard_fab2(sch_1):page120_i147:gpp_j1_lan_led_p0_1" )
			)
			( pin "U7C1.BP4"
				( objectStatus "@baseboard_fab2_lib.baseboard_fab2(sch_1):page120_i147:gpp_j2_lan_led_p1_0" )
			)
			( pin "U7C1.BK2"
				( objectStatus "@baseboard_fab2_lib.baseboard_fab2(sch_1):page120_i147:gpp_j3_lan_led_p1_1" )
			)
			( pin "U7C1.BL3"
				( objectStatus "@baseboard_fab2_lib.baseboard_fab2(sch_1):page120_i147:gpp_j4_lan_led_p2_0" )
			)
			( pin "U7C1.BU6"
				( objectStatus "@baseboard_fab2_lib.baseboard_fab2(sch_1):page120_i147:gpp_j5_lan_led_p2_1" )
			)
			( pin "U7C1.CA13"
				( objectStatus "@baseboard_fab2_lib.baseboard_fab2(sch_1):page120_i147:gpp_j6_lan_led_p3_0" )
			)
			( pin "U7C1.BM2"
				( objectStatus "@baseboard_fab2_lib.baseboard_fab2(sch_1):page120_i147:gpp_j7_lan_led_p3_1" )
			)
			( pin "U7C1.BM4"
				( objectStatus "@baseboard_fab2_lib.baseboard_fab2(sch_1):page120_i147:gpp_j8_lan_i2c_scl_mdc_p0" )
			)
			( pin "U7C1.BN3"
				( objectStatus "@baseboard_fab2_lib.baseboard_fab2(sch_1):page120_i147:gpp_j9_lan_i2c_sda_mdio_p0" )
			)
			( pin "U7C1.BW5"
				( objectStatus "@baseboard_fab2_lib.baseboard_fab2(sch_1):page120_i147:gpp_j10_lan_i2c_scl_mdc_p1" )
			)
			( pin "U7C1.BV8"
				( objectStatus "@baseboard_fab2_lib.baseboard_fab2(sch_1):page120_i147:gpp_j11_lan_i2c_sda_mdio_p1" )
			)
			( pin "U7C1.BT5"
				( objectStatus "@baseboard_fab2_lib.baseboard_fab2(sch_1):page120_i147:gpp_j12_lan_i2c_scl_mdc_p2" )
			)
			( pin "U7C1.BW11"
				( objectStatus "@baseboard_fab2_lib.baseboard_fab2(sch_1):page120_i147:gpp_j13_lan_i2c_sda_mdio_p2" )
			)
			( pin "U7C1.BW6"
				( objectStatus "@baseboard_fab2_lib.baseboard_fab2(sch_1):page120_i147:gpp_j14_lan_i2c_scl_mdc_p3" )
			)
			( pin "U7C1.BW9"
				( objectStatus "@baseboard_fab2_lib.baseboard_fab2(sch_1):page120_i147:gpp_j15_lan_i2c_sda_mdio_p3" )
			)
			( pin "U7C1.BV10"
				( objectStatus "@baseboard_fab2_lib.baseboard_fab2(sch_1):page120_i147:gpp_j16_lan_sdp_p0_0" )
			)
			( pin "U7C1.CA11"
				( objectStatus "@baseboard_fab2_lib.baseboard_fab2(sch_1):page120_i147:gpp_j17_lan_sdp_p0_1" )
			)
			( pin "U7C1.BY10"
				( objectStatus "@baseboard_fab2_lib.baseboard_fab2(sch_1):page120_i147:gpp_j18_lan_sdp_p1_0" )
			)
			( pin "U7C1.BY14"
				( objectStatus "@baseboard_fab2_lib.baseboard_fab2(sch_1):page120_i147:gpp_j19_lan_sdp_p1_1" )
			)
			( pin "U7C1.BW13"
				( objectStatus "@baseboard_fab2_lib.baseboard_fab2(sch_1):page120_i147:gpp_j20_lan_sdp_p2_0" )
			)
			( pin "U7C1.BV12"
				( objectStatus "@baseboard_fab2_lib.baseboard_fab2(sch_1):page120_i147:gpp_j21_lan_sdp_p2_1" )
			)
			( pin "U7C1.BY12"
				( objectStatus "@baseboard_fab2_lib.baseboard_fab2(sch_1):page120_i147:gpp_j22_lan_sdp_p3_0" )
			)
			( pin "U7C1.BV14"
				( objectStatus "@baseboard_fab2_lib.baseboard_fab2(sch_1):page120_i147:gpp_j23_lan_sdp_p3_1" )
			)
			( pin "R8C21.1"
				( objectStatus "@baseboard_fab2_lib.baseboard_fab2(sch_1):page120_i148:a" )
			)
			( pin "R8C21.2"
				( objectStatus "@baseboard_fab2_lib.baseboard_fab2(sch_1):page120_i148:b" )
			)
			( pin "R2M1.1"
				( objectStatus "@baseboard_fab2_lib.baseboard_fab2(sch_1):page120_i218:a" )
			)
			( pin "R2M1.2"
				( objectStatus "@baseboard_fab2_lib.baseboard_fab2(sch_1):page120_i218:b" )
			)
			( pin "R2N26.1"
				( objectStatus "@baseboard_fab2_lib.baseboard_fab2(sch_1):page120_i219:a" )
			)
			( pin "R2N26.2"
				( objectStatus "@baseboard_fab2_lib.baseboard_fab2(sch_1):page120_i219:b" )
			)
			( pin "R7C15.1"
				( objectStatus "@baseboard_fab2_lib.baseboard_fab2(sch_1):page121_i31:a" )
			)
			( pin "R7C15.2"
				( objectStatus "@baseboard_fab2_lib.baseboard_fab2(sch_1):page121_i31:b" )
			)
			( pin "R7C16.1"
				( objectStatus "@baseboard_fab2_lib.baseboard_fab2(sch_1):page121_i33:a" )
			)
			( pin "R7C16.2"
				( objectStatus "@baseboard_fab2_lib.baseboard_fab2(sch_1):page121_i33:b" )
			)
			( pin "U7C1.C70"
				( objectStatus "@baseboard_fab2_lib.baseboard_fab2(sch_1):page121_i34:cgc_dut_detect_n" )
			)
			( pin "U7C1.AM4"
				( objectStatus "@baseboard_fab2_lib.baseboard_fab2(sch_1):page121_i34:gpio_rcomp_1p8_3p3" )
			)
			( pin "U7C1.AJ1"
				( objectStatus "@baseboard_fab2_lib.baseboard_fab2(sch_1):page121_i34:gpp_k0_lan_ncsi_clk_in" )
			)
			( pin "U7C1.AM2"
				( objectStatus "@baseboard_fab2_lib.baseboard_fab2(sch_1):page121_i34:gpp_k1_lan_ncsi_txd0" )
			)
			( pin "U7C1.AK2"
				( objectStatus "@baseboard_fab2_lib.baseboard_fab2(sch_1):page121_i34:gpp_k2_lan_ncsi_txd1" )
			)
			( pin "U7C1.AL3"
				( objectStatus "@baseboard_fab2_lib.baseboard_fab2(sch_1):page121_i34:gpp_k3_lan_ncsi_tx_en" )
			)
			( pin "U7C1.AN3"
				( objectStatus "@baseboard_fab2_lib.baseboard_fab2(sch_1):page121_i34:gpp_k4_lan_ncsi_crs_dv" )
			)
			( pin "U7C1.AL1"
				( objectStatus "@baseboard_fab2_lib.baseboard_fab2(sch_1):page121_i34:gpp_k5_lan_ncsi_rxd0" )
			)
			( pin "U7C1.AN1"
				( objectStatus "@baseboard_fab2_lib.baseboard_fab2(sch_1):page121_i34:gpp_k6_lan_ncsi_rxd1" )
			)
			( pin "U7C1.AH2"
				( objectStatus "@baseboard_fab2_lib.baseboard_fab2(sch_1):page121_i34:gpp_k7" )
			)
			( pin "U7C1.AJ3"
				( objectStatus "@baseboard_fab2_lib.baseboard_fab2(sch_1):page121_i34:gpp_k8_lan_ncsi_arb_in" )
			)
			( pin "U7C1.AK4"
				( objectStatus "@baseboard_fab2_lib.baseboard_fab2(sch_1):page121_i34:gpp_k9_lan_ncsi_arb_out" )
			)
			( pin "U7C1.AH4"
				( objectStatus "@baseboard_fab2_lib.baseboard_fab2(sch_1):page121_i34:gpp_k10_pe_rst_n" )
			)
			( pin "U7C1.AE18"
				( objectStatus "@baseboard_fab2_lib.baseboard_fab2(sch_1):page121_i34:gpp_l2_testch0_d0" )
			)
			( pin "U7C1.AE15"
				( objectStatus "@baseboard_fab2_lib.baseboard_fab2(sch_1):page121_i34:gpp_l3_testch0_d1" )
			)
			( pin "U7C1.AE11"
				( objectStatus "@baseboard_fab2_lib.baseboard_fab2(sch_1):page121_i34:gpp_l4_testch0_d2" )
			)
			( pin "U7C1.Y18"
				( objectStatus "@baseboard_fab2_lib.baseboard_fab2(sch_1):page121_i34:gpp_l5_testch0_d3" )
			)
			( pin "U7C1.AA20"
				( objectStatus "@baseboard_fab2_lib.baseboard_fab2(sch_1):page121_i34:gpp_l6_testch0_d4" )
			)
			( pin "U7C1.AA17"
				( objectStatus "@baseboard_fab2_lib.baseboard_fab2(sch_1):page121_i34:gpp_l7_testch0_d5" )
			)
			( pin "U7C1.AD9"
				( objectStatus "@baseboard_fab2_lib.baseboard_fab2(sch_1):page121_i34:gpp_l8_testch0_d6" )
			)
			( pin "U7C1.AD17"
				( objectStatus "@baseboard_fab2_lib.baseboard_fab2(sch_1):page121_i34:gpp_l9_testch0_d7" )
			)
			( pin "U7C1.AF20"
				( objectStatus "@baseboard_fab2_lib.baseboard_fab2(sch_1):page121_i34:gpp_l10_testch0_clk" )
			)
			( pin "U7C1.AD20"
				( objectStatus "@baseboard_fab2_lib.baseboard_fab2(sch_1):page121_i34:gpp_l11_testch1_d0" )
			)
			( pin "U7C1.Y15"
				( objectStatus "@baseboard_fab2_lib.baseboard_fab2(sch_1):page121_i34:gpp_l12_testch1_d1" )
			)
			( pin "U7C1.AD13"
				( objectStatus "@baseboard_fab2_lib.baseboard_fab2(sch_1):page121_i34:gpp_l13_testch1_d2" )
			)
			( pin "U7C1.AA13"
				( objectStatus "@baseboard_fab2_lib.baseboard_fab2(sch_1):page121_i34:gpp_l14_testch1_d3" )
			)
			( pin "U7C1.Y11"
				( objectStatus "@baseboard_fab2_lib.baseboard_fab2(sch_1):page121_i34:gpp_l15_testch1_d4" )
			)
			( pin "U7C1.Y7"
				( objectStatus "@baseboard_fab2_lib.baseboard_fab2(sch_1):page121_i34:gpp_l16_testch1_d5" )
			)
			( pin "U7C1.AA9"
				( objectStatus "@baseboard_fab2_lib.baseboard_fab2(sch_1):page121_i34:gpp_l17_testch1_d6" )
			)
			( pin "U7C1.AE7"
				( objectStatus "@baseboard_fab2_lib.baseboard_fab2(sch_1):page121_i34:gpp_l18_testch1_d7" )
			)
			( pin "U7C1.AG11"
				( objectStatus "@baseboard_fab2_lib.baseboard_fab2(sch_1):page121_i34:gpp_l19_testch1_clk" )
			)
			( pin "U7C1.P18"
				( objectStatus "@baseboard_fab2_lib.baseboard_fab2(sch_1):page121_i34:hda_bclk" )
			)
			( pin "U7C1.M18"
				( objectStatus "@baseboard_fab2_lib.baseboard_fab2(sch_1):page121_i34:hda_rst_n" )
			)
			( pin "U7C1.K20"
				( objectStatus "@baseboard_fab2_lib.baseboard_fab2(sch_1):page121_i34:hda_sdi_0" )
			)
			( pin "U7C1.V18"
				( objectStatus "@baseboard_fab2_lib.baseboard_fab2(sch_1):page121_i34:hda_sdi_1" )
			)
			( pin "U7C1.U24"
				( objectStatus "@baseboard_fab2_lib.baseboard_fab2(sch_1):page121_i34:hda_sdo" )
			)
			( pin "U7C1.H20"
				( objectStatus "@baseboard_fab2_lib.baseboard_fab2(sch_1):page121_i34:hda_sync" )
			)
			( pin "U7C1.AG18"
				( objectStatus "@baseboard_fab2_lib.baseboard_fab2(sch_1):page121_i34:intruder_n" )
			)
			( pin "U7C1.AF61"
				( objectStatus "@baseboard_fab2_lib.baseboard_fab2(sch_1):page121_i34:rsvd(0)" )
			)
			( pin "U7C1.AC56"
				( objectStatus "@baseboard_fab2_lib.baseboard_fab2(sch_1):page121_i34:rsvd(1)" )
			)
			( pin "U7C1.AA58"
				( objectStatus "@baseboard_fab2_lib.baseboard_fab2(sch_1):page121_i34:rsvd(2)" )
			)
			( pin "U7C1.V11"
				( objectStatus "@baseboard_fab2_lib.baseboard_fab2(sch_1):page121_i34:rsvd(3)" )
			)
			( pin "U7C1.P37"
				( objectStatus "@baseboard_fab2_lib.baseboard_fab2(sch_1):page121_i34:rsvd(4)" )
			)
			( pin "U7C1.AG15"
				( objectStatus "@baseboard_fab2_lib.baseboard_fab2(sch_1):page121_i34:rsvd(5)" )
			)
			( pin "U7C1.AT69"
				( objectStatus "@baseboard_fab2_lib.baseboard_fab2(sch_1):page121_i34:rsvd(6)" )
			)
			( pin "U7C1.F8"
				( objectStatus "@baseboard_fab2_lib.baseboard_fab2(sch_1):page121_i34:rsvd(7)" )
			)
			( pin "U7C1.F69"
				( objectStatus "@baseboard_fab2_lib.baseboard_fab2(sch_1):page121_i34:rsvd(8)" )
			)
			( pin "U7C1.F66"
				( objectStatus "@baseboard_fab2_lib.baseboard_fab2(sch_1):page121_i34:rsvd(9)" )
			)
			( pin "U7C1.D8"
				( objectStatus "@baseboard_fab2_lib.baseboard_fab2(sch_1):page121_i34:rsvd(10)" )
			)
			( pin "U7C1.C18"
				( objectStatus "@baseboard_fab2_lib.baseboard_fab2(sch_1):page121_i34:rsvd(11)" )
			)
			( pin "U7C1.C68"
				( objectStatus "@baseboard_fab2_lib.baseboard_fab2(sch_1):page121_i34:rsvd(12)" )
			)
			( pin "U7C1.C67"
				( objectStatus "@baseboard_fab2_lib.baseboard_fab2(sch_1):page121_i34:rsvd(13)" )
			)
			( pin "U7C1.E18"
				( objectStatus "@baseboard_fab2_lib.baseboard_fab2(sch_1):page121_i34:rsvd(14)" )
			)
			( pin "U7C1.C6"
				( objectStatus "@baseboard_fab2_lib.baseboard_fab2(sch_1):page121_i34:rsvd(15)" )
			)
			( pin "U7C1.C5"
				( objectStatus "@baseboard_fab2_lib.baseboard_fab2(sch_1):page121_i34:rsvd(16)" )
			)
			( pin "U7C1.B10"
				( objectStatus "@baseboard_fab2_lib.baseboard_fab2(sch_1):page121_i34:rsvd(17)" )
			)
			( pin "U7C1.C11"
				( objectStatus "@baseboard_fab2_lib.baseboard_fab2(sch_1):page121_i34:rsvd(18)" )
			)
			( pin "U7C1.C9"
				( objectStatus "@baseboard_fab2_lib.baseboard_fab2(sch_1):page121_i34:rsvd(19)" )
			)
			( pin "U7C1.D10"
				( objectStatus "@baseboard_fab2_lib.baseboard_fab2(sch_1):page121_i34:rsvd(20)" )
			)
			( pin "U7C1.A11"
				( objectStatus "@baseboard_fab2_lib.baseboard_fab2(sch_1):page121_i34:rsvd(21)" )
			)
			( pin "U7C1.AT71"
				( objectStatus "@baseboard_fab2_lib.baseboard_fab2(sch_1):page121_i34:rsvd(22)" )
			)
			( pin "U7C1.P40"
				( objectStatus "@baseboard_fab2_lib.baseboard_fab2(sch_1):page121_i34:rsvd(23)" )
			)
			( pin "U7C1.P44"
				( objectStatus "@baseboard_fab2_lib.baseboard_fab2(sch_1):page121_i34:rsvd(24)" )
			)
			( pin "U7C1.P48"
				( objectStatus "@baseboard_fab2_lib.baseboard_fab2(sch_1):page121_i34:rsvd(25)" )
			)
			( pin "U7C1.BH24"
				( objectStatus "@baseboard_fab2_lib.baseboard_fab2(sch_1):page121_i34:rsvd(26)" )
			)
			( pin "U7C1.BG26"
				( objectStatus "@baseboard_fab2_lib.baseboard_fab2(sch_1):page121_i34:rsvd(27)" )
			)
			( pin "U7C1.BW3"
				( objectStatus "@baseboard_fab2_lib.baseboard_fab2(sch_1):page121_i34:rsvd(46)" )
			)
			( pin "U7C1.U20"
				( objectStatus "@baseboard_fab2_lib.baseboard_fab2(sch_1):page121_i34:rsvd(66)" )
			)
			( pin "U7C1.R20"
				( objectStatus "@baseboard_fab2_lib.baseboard_fab2(sch_1):page121_i34:rsvd(67)" )
			)
			( pin "U7C1.V22"
				( objectStatus "@baseboard_fab2_lib.baseboard_fab2(sch_1):page121_i34:rsvd(68)" )
			)
			( pin "U7C1.P11"
				( objectStatus "@baseboard_fab2_lib.baseboard_fab2(sch_1):page121_i34:rtcrst_n" )
			)
			( pin "U7C1.K2"
				( objectStatus "@baseboard_fab2_lib.baseboard_fab2(sch_1):page121_i34:spi0_clk" )
			)
			( pin "U7C1.J3"
				( objectStatus "@baseboard_fab2_lib.baseboard_fab2(sch_1):page121_i34:spi0_flash_cs0_n" )
			)
			( pin "U7C1.G7"
				( objectStatus "@baseboard_fab2_lib.baseboard_fab2(sch_1):page121_i34:spi0_flash_cs1_n" )
			)
			( pin "U7C1.F5"
				( objectStatus "@baseboard_fab2_lib.baseboard_fab2(sch_1):page121_i34:spi0_io2" )
			)
			( pin "U7C1.L1"
				( objectStatus "@baseboard_fab2_lib.baseboard_fab2(sch_1):page121_i34:spi0_io3" )
			)
			( pin "U7C1.L3"
				( objectStatus "@baseboard_fab2_lib.baseboard_fab2(sch_1):page121_i34:spi0_miso_io1" )
			)
			( pin "U7C1.H4"
				( objectStatus "@baseboard_fab2_lib.baseboard_fab2(sch_1):page121_i34:spi0_mosi_io0" )
			)
			( pin "U7C1.K4"
				( objectStatus "@baseboard_fab2_lib.baseboard_fab2(sch_1):page121_i34:spi0_tpm_cs_n" )
			)
			( pin "U7C1.G18"
				( objectStatus "@baseboard_fab2_lib.baseboard_fab2(sch_1):page121_i34:srtcrst_n" )
			)
			( pin "R8C26.1"
				( objectStatus "@baseboard_fab2_lib.baseboard_fab2(sch_1):page121_i35:a" )
			)
			( pin "R8C26.2"
				( objectStatus "@baseboard_fab2_lib.baseboard_fab2(sch_1):page121_i35:b" )
			)
			( pin "R3N10.1"
				( objectStatus "@baseboard_fab2_lib.baseboard_fab2(sch_1):page121_i37:a" )
			)
			( pin "R3N10.2"
				( objectStatus "@baseboard_fab2_lib.baseboard_fab2(sch_1):page121_i37:b" )
			)
			( pin "R7C20.1"
				( objectStatus "@baseboard_fab2_lib.baseboard_fab2(sch_1):page121_i73:a" )
			)
			( pin "R7C20.2"
				( objectStatus "@baseboard_fab2_lib.baseboard_fab2(sch_1):page121_i73:b" )
			)
			( pin "R3P3.1"
				( objectStatus "@baseboard_fab2_lib.baseboard_fab2(sch_1):page121_i89:a" )
			)
			( pin "R3P3.2"
				( objectStatus "@baseboard_fab2_lib.baseboard_fab2(sch_1):page121_i89:b" )
			)
			( pin "R3P2.1"
				( objectStatus "@baseboard_fab2_lib.baseboard_fab2(sch_1):page121_i90:a" )
			)
			( pin "R3P2.2"
				( objectStatus "@baseboard_fab2_lib.baseboard_fab2(sch_1):page121_i90:b" )
			)
			( pin "R2P1.1"
				( objectStatus "@baseboard_fab2_lib.baseboard_fab2(sch_1):page121_i91:a" )
			)
			( pin "R2P1.2"
				( objectStatus "@baseboard_fab2_lib.baseboard_fab2(sch_1):page121_i91:b" )
			)
			( pin "R7C14.1"
				( objectStatus "@baseboard_fab2_lib.baseboard_fab2(sch_1):page121_i98:a" )
			)
			( pin "R7C14.2"
				( objectStatus "@baseboard_fab2_lib.baseboard_fab2(sch_1):page121_i98:b" )
			)
			( pin "R8D11.1"
				( objectStatus "@baseboard_fab2_lib.baseboard_fab2(sch_1):page121_i101:a" )
			)
			( pin "R8D11.2"
				( objectStatus "@baseboard_fab2_lib.baseboard_fab2(sch_1):page121_i101:b" )
			)
			( pin "U7C1.R35"
				( objectStatus "@baseboard_fab2_lib.baseboard_fab2(sch_1):page122_i63:rsvd(28)" )
			)
			( pin "U7C1.P33"
				( objectStatus "@baseboard_fab2_lib.baseboard_fab2(sch_1):page122_i63:rsvd(29)" )
			)
			( pin "U7C1.R31"
				( objectStatus "@baseboard_fab2_lib.baseboard_fab2(sch_1):page122_i63:rsvd(30)" )
			)
			( pin "U7C1.P29"
				( objectStatus "@baseboard_fab2_lib.baseboard_fab2(sch_1):page122_i63:rsvd(31)" )
			)
			( pin "U7C1.AP27"
				( objectStatus "@baseboard_fab2_lib.baseboard_fab2(sch_1):page122_i63:rsvd(58)" )
			)
			( pin "U7C1.AT27"
				( objectStatus "@baseboard_fab2_lib.baseboard_fab2(sch_1):page122_i63:rsvd(59)" )
			)
			( pin "U7C1.W50"
				( objectStatus "@baseboard_fab2_lib.baseboard_fab2(sch_1):page122_i63:vcca_clkfilt_1p05(0)" )
			)
			( pin "U7C1.AG45"
				( objectStatus "@baseboard_fab2_lib.baseboard_fab2(sch_1):page122_i63:vcca_clkfilt_1p05(1)" )
			)
			( pin "U7C1.AJ46"
				( objectStatus "@baseboard_fab2_lib.baseboard_fab2(sch_1):page122_i63:vcca_clkfilt_1p05(2)" )
			)
			( pin "U7C1.AJ48"
				( objectStatus "@baseboard_fab2_lib.baseboard_fab2(sch_1):page122_i63:vcca_clkfilt_1p05(3)" )
			)
			( pin "U7C1.AE46"
				( objectStatus "@baseboard_fab2_lib.baseboard_fab2(sch_1):page122_i63:vcca_clkfilt_1p05(4)" )
			)
			( pin "U7C1.AH50"
				( objectStatus "@baseboard_fab2_lib.baseboard_fab2(sch_1):page122_i63:vcca_clkunf_1p05(0)" )
			)
			( pin "U7C1.U50"
				( objectStatus "@baseboard_fab2_lib.baseboard_fab2(sch_1):page122_i63:vcca_clkunf_1p05(1)" )
			)
			( pin "U7C1.AD50"
				( objectStatus "@baseboard_fab2_lib.baseboard_fab2(sch_1):page122_i63:vcca_clkxtal_1p05" )
			)
			( pin "U7C1.AG48"
				( objectStatus "@baseboard_fab2_lib.baseboard_fab2(sch_1):page122_i63:vcca_pll0_1p05" )
			)
			( pin "U7C1.AE45"
				( objectStatus "@baseboard_fab2_lib.baseboard_fab2(sch_1):page122_i63:vcca_pll1_1p05" )
			)
			( pin "U7C1.AW45"
				( objectStatus "@baseboard_fab2_lib.baseboard_fab2(sch_1):page122_i63:vccmphy_1p05(0)" )
			)
			( pin "U7C1.AW43"
				( objectStatus "@baseboard_fab2_lib.baseboard_fab2(sch_1):page122_i63:vccmphy_1p05(1)" )
			)
			( pin "U7C1.AJ43"
				( objectStatus "@baseboard_fab2_lib.baseboard_fab2(sch_1):page122_i63:vccmphy_1p05(2)" )
			)
			( pin "U7C1.AU45"
				( objectStatus "@baseboard_fab2_lib.baseboard_fab2(sch_1):page122_i63:vccmphy_1p05(3)" )
			)
			( pin "U7C1.AU43"
				( objectStatus "@baseboard_fab2_lib.baseboard_fab2(sch_1):page122_i63:vccmphy_1p05(4)" )
			)
			( pin "U7C1.AT45"
				( objectStatus "@baseboard_fab2_lib.baseboard_fab2(sch_1):page122_i63:vccmphy_1p05(5)" )
			)
			( pin "U7C1.AT43"
				( objectStatus "@baseboard_fab2_lib.baseboard_fab2(sch_1):page122_i63:vccmphy_1p05(6)" )
			)
			( pin "U7C1.AP45"
				( objectStatus "@baseboard_fab2_lib.baseboard_fab2(sch_1):page122_i63:vccmphy_1p05(7)" )
			)
			( pin "U7C1.AP43"
				( objectStatus "@baseboard_fab2_lib.baseboard_fab2(sch_1):page122_i63:vccmphy_1p05(8)" )
			)
			( pin "U7C1.AM45"
				( objectStatus "@baseboard_fab2_lib.baseboard_fab2(sch_1):page122_i63:vccmphy_1p05(9)" )
			)
			( pin "U7C1.AM43"
				( objectStatus "@baseboard_fab2_lib.baseboard_fab2(sch_1):page122_i63:vccmphy_1p05(10)" )
			)
			( pin "U7C1.AK45"
				( objectStatus "@baseboard_fab2_lib.baseboard_fab2(sch_1):page122_i63:vccmphy_1p05(11)" )
			)
			( pin "U7C1.AK43"
				( objectStatus "@baseboard_fab2_lib.baseboard_fab2(sch_1):page122_i63:vccmphy_1p05(12)" )
			)
			( pin "U7C1.BA29"
				( objectStatus "@baseboard_fab2_lib.baseboard_fab2(sch_1):page122_i63:vccp10gbe_hv_1p8(0)" )
			)
			( pin "U7C1.BA27"
				( objectStatus "@baseboard_fab2_lib.baseboard_fab2(sch_1):page122_i63:vccp10gbe_hv_1p8(1)" )
			)
			( pin "U7C1.BB37"
				( objectStatus "@baseboard_fab2_lib.baseboard_fab2(sch_1):page122_i63:vccp10gbe_lv_1p05(0)" )
			)
			( pin "U7C1.BB33"
				( objectStatus "@baseboard_fab2_lib.baseboard_fab2(sch_1):page122_i63:vccp10gbe_lv_1p05(1)" )
			)
			( pin "U7C1.BA37"
				( objectStatus "@baseboard_fab2_lib.baseboard_fab2(sch_1):page122_i63:vccp10gbe_lv_1p05(2)" )
			)
			( pin "U7C1.BA36"
				( objectStatus "@baseboard_fab2_lib.baseboard_fab2(sch_1):page122_i63:vccp10gbe_lv_1p05(3)" )
			)
			( pin "U7C1.BA34"
				( objectStatus "@baseboard_fab2_lib.baseboard_fab2(sch_1):page122_i63:vccp10gbe_lv_1p05(4)" )
			)
			( pin "U7C1.BA32"
				( objectStatus "@baseboard_fab2_lib.baseboard_fab2(sch_1):page122_i63:vccp10gbe_lv_1p05(5)" )
			)
			( pin "U7C1.BA30"
				( objectStatus "@baseboard_fab2_lib.baseboard_fab2(sch_1):page122_i63:vccp10gbe_lv_1p05(6)" )
			)
			( pin "U7C1.BD38"
				( objectStatus "@baseboard_fab2_lib.baseboard_fab2(sch_1):page122_i63:vccp10gbepll_1p05(0)" )
			)
			( pin "U7C1.BB40"
				( objectStatus "@baseboard_fab2_lib.baseboard_fab2(sch_1):page122_i63:vccp10gbepll_1p05(1)" )
			)
			( pin "U7C1.BA41"
				( objectStatus "@baseboard_fab2_lib.baseboard_fab2(sch_1):page122_i63:vccp10gbepll_1p05(2)" )
			)
			( pin "U7C1.BA39"
				( objectStatus "@baseboard_fab2_lib.baseboard_fab2(sch_1):page122_i63:vccp10gbepll_1p05(3)" )
			)
			( pin "U7C1.BD46"
				( objectStatus "@baseboard_fab2_lib.baseboard_fab2(sch_1):page122_i63:vccp_1p8(0)" )
			)
			( pin "U7C1.AE26"
				( objectStatus "@baseboard_fab2_lib.baseboard_fab2(sch_1):page122_i63:vccp_1p8(1)" )
			)
			( pin "U7C1.BA46"
				( objectStatus "@baseboard_fab2_lib.baseboard_fab2(sch_1):page122_i63:vccp_3p3(0)" )
			)
			( pin "U7C1.BA45"
				( objectStatus "@baseboard_fab2_lib.baseboard_fab2(sch_1):page122_i63:vccp_3p3(1)" )
			)
			( pin "U7C1.AD24"
				( objectStatus "@baseboard_fab2_lib.baseboard_fab2(sch_1):page122_i63:vccp_3p3(2)" )
			)
			( pin "U7C1.AN24"
				( objectStatus "@baseboard_fab2_lib.baseboard_fab2(sch_1):page122_i63:vccp_3p3(5)" )
			)
			( pin "U7C1.AW48"
				( objectStatus "@baseboard_fab2_lib.baseboard_fab2(sch_1):page122_i63:vccp_hsiopll_1p05(0)" )
			)
			( pin "U7C1.AU48"
				( objectStatus "@baseboard_fab2_lib.baseboard_fab2(sch_1):page122_i63:vccp_hsiopll_1p05(2)" )
			)
			( pin "U7C1.AP48"
				( objectStatus "@baseboard_fab2_lib.baseboard_fab2(sch_1):page122_i63:vccp_hsiopll_1p05(3)" )
			)
			( pin "U7C1.AT48"
				( objectStatus "@baseboard_fab2_lib.baseboard_fab2(sch_1):page122_i63:vccp_hsiopllunf_1p05" )
			)
			( pin "U7C1.AN50"
				( objectStatus "@baseboard_fab2_lib.baseboard_fab2(sch_1):page122_i63:vccp_uppll_1p05(0)" )
			)
			( pin "U7C1.AK50"
				( objectStatus "@baseboard_fab2_lib.baseboard_fab2(sch_1):page122_i63:vccp_uppll_1p05(2)" )
			)
			( pin "U7C1.AM48"
				( objectStatus "@baseboard_fab2_lib.baseboard_fab2(sch_1):page122_i63:vccp_uppllunf_1p05" )
			)
			( pin "U7C1.AH24"
				( objectStatus "@baseboard_fab2_lib.baseboard_fab2(sch_1):page122_i63:vccpdsw_3p3" )
			)
			( pin "U7C1.AU29"
				( objectStatus "@baseboard_fab2_lib.baseboard_fab2(sch_1):page122_i63:vccpgpp_1p8(0)" )
			)
			( pin "U7C1.AW29"
				( objectStatus "@baseboard_fab2_lib.baseboard_fab2(sch_1):page122_i63:vccpgpp_1p8(1)" )
			)
			( pin "U7C1.AT29"
				( objectStatus "@baseboard_fab2_lib.baseboard_fab2(sch_1):page122_i63:vccpgpp_1p8(2)" )
			)
			( pin "U7C1.AM29"
				( objectStatus "@baseboard_fab2_lib.baseboard_fab2(sch_1):page122_i63:vccpgpp_1p8(3)" )
			)
			( pin "U7C1.AP29"
				( objectStatus "@baseboard_fab2_lib.baseboard_fab2(sch_1):page122_i63:vccpgpp_1p8(4)" )
			)
			( pin "U7C1.AW27"
				( objectStatus "@baseboard_fab2_lib.baseboard_fab2(sch_1):page122_i63:vccpgpp_1p8(5)" )
			)
			( pin "U7C1.AK24"
				( objectStatus "@baseboard_fab2_lib.baseboard_fab2(sch_1):page122_i63:vccpgpp_1p8(6)" )
			)
			( pin "U7C1.AW24"
				( objectStatus "@baseboard_fab2_lib.baseboard_fab2(sch_1):page122_i63:vccpgppa" )
			)
			( pin "U7C1.BE26"
				( objectStatus "@baseboard_fab2_lib.baseboard_fab2(sch_1):page122_i63:vccpgppb" )
			)
			( pin "U7C1.BE40"
				( objectStatus "@baseboard_fab2_lib.baseboard_fab2(sch_1):page122_i63:vccpgppc" )
			)
			( pin "U7C1.BA43"
				( objectStatus "@baseboard_fab2_lib.baseboard_fab2(sch_1):page122_i63:vccpgppd" )
			)
			( pin "U7C1.BE44"
				( objectStatus "@baseboard_fab2_lib.baseboard_fab2(sch_1):page122_i63:vccpgppe" )
			)
			( pin "U7C1.AU27"
				( objectStatus "@baseboard_fab2_lib.baseboard_fab2(sch_1):page122_i63:vccpgppf" )
			)
			( pin "U7C1.BA26"
				( objectStatus "@baseboard_fab2_lib.baseboard_fab2(sch_1):page122_i63:vccpgppg" )
			)
			( pin "U7C1.BA24"
				( objectStatus "@baseboard_fab2_lib.baseboard_fab2(sch_1):page122_i63:vccpgpph" )
			)
			( pin "U7C1.BB26"
				( objectStatus "@baseboard_fab2_lib.baseboard_fab2(sch_1):page122_i63:vccpgppj" )
			)
			( pin "U7C1.AU24"
				( objectStatus "@baseboard_fab2_lib.baseboard_fab2(sch_1):page122_i63:vccpgppk" )
			)
			( pin "U7C1.AG27"
				( objectStatus "@baseboard_fab2_lib.baseboard_fab2(sch_1):page122_i63:vccphda_1p8" )
			)
			( pin "U7C1.BF46"
				( objectStatus "@baseboard_fab2_lib.baseboard_fab2(sch_1):page122_i63:vccprim_1p05(0)" )
			)
			( pin "U7C1.BE48"
				( objectStatus "@baseboard_fab2_lib.baseboard_fab2(sch_1):page122_i63:vccprim_1p05(1)" )
			)
			( pin "U7C1.AU39"
				( objectStatus "@baseboard_fab2_lib.baseboard_fab2(sch_1):page122_i63:vccprim_1p05(2)" )
			)
			( pin "U7C1.AU37"
				( objectStatus "@baseboard_fab2_lib.baseboard_fab2(sch_1):page122_i63:vccprim_1p05(3)" )
			)
			( pin "U7C1.AT39"
				( objectStatus "@baseboard_fab2_lib.baseboard_fab2(sch_1):page122_i63:vccprim_1p05(4)" )
			)
			( pin "U7C1.AM27"
				( objectStatus "@baseboard_fab2_lib.baseboard_fab2(sch_1):page122_i63:vccprim_1p05(5)" )
			)
			( pin "U7C1.AJ29"
				( objectStatus "@baseboard_fab2_lib.baseboard_fab2(sch_1):page122_i63:vccprim_1p05(6)" )
			)
			( pin "U7C1.AC26"
				( objectStatus "@baseboard_fab2_lib.baseboard_fab2(sch_1):page122_i63:vccprim_1p05(7)" )
			)
			( pin "U7C1.AA46"
				( objectStatus "@baseboard_fab2_lib.baseboard_fab2(sch_1):page122_i63:vccprim_1p05(8)" )
			)
			( pin "U7C1.AA45"
				( objectStatus "@baseboard_fab2_lib.baseboard_fab2(sch_1):page122_i63:vccprim_1p05(9)" )
			)
			( pin "U7C1.Y46"
				( objectStatus "@baseboard_fab2_lib.baseboard_fab2(sch_1):page122_i63:vccprim_1p05(10)" )
			)
			( pin "U7C1.Y45"
				( objectStatus "@baseboard_fab2_lib.baseboard_fab2(sch_1):page122_i63:vccprim_1p05(11)" )
			)
			( pin "U7C1.V44"
				( objectStatus "@baseboard_fab2_lib.baseboard_fab2(sch_1):page122_i63:vccprim_1p05(12)" )
			)
			( pin "U7C1.U46"
				( objectStatus "@baseboard_fab2_lib.baseboard_fab2(sch_1):page122_i63:vccprim_1p05(13)" )
			)
			( pin "U7C1.T44"
				( objectStatus "@baseboard_fab2_lib.baseboard_fab2(sch_1):page122_i63:vccprim_1p05(14)" )
			)
			( pin "U7C1.R46"
				( objectStatus "@baseboard_fab2_lib.baseboard_fab2(sch_1):page122_i63:vccprim_1p05(15)" )
			)
			( pin "U7C1.R42"
				( objectStatus "@baseboard_fab2_lib.baseboard_fab2(sch_1):page122_i63:vccprim_1p05(16)" )
			)
			( pin "U7C1.AK27"
				( objectStatus "@baseboard_fab2_lib.baseboard_fab2(sch_1):page122_i63:vccprim_1p05(17)" )
			)
			( pin "U7C1.AA24"
				( objectStatus "@baseboard_fab2_lib.baseboard_fab2(sch_1):page122_i63:vccprim_1p05(18)" )
			)
			( pin "U7C1.Y26"
				( objectStatus "@baseboard_fab2_lib.baseboard_fab2(sch_1):page122_i63:vccprim_1p05(19)" )
			)
			( pin "U7C1.AJ27"
				( objectStatus "@baseboard_fab2_lib.baseboard_fab2(sch_1):page122_i63:vccprtc" )
			)
			( pin "U7C1.AG29"
				( objectStatus "@baseboard_fab2_lib.baseboard_fab2(sch_1):page122_i63:vccprtcprim_3p3" )
			)
			( pin "U7C1.AR24"
				( objectStatus "@baseboard_fab2_lib.baseboard_fab2(sch_1):page122_i63:vccpspi" )
			)
			( pin "U7C1.AK29"
				( objectStatus "@baseboard_fab2_lib.baseboard_fab2(sch_1):page122_i63:vccpspi_1p8" )
			)
			( pin "U7C1.BA48"
				( objectStatus "@baseboard_fab2_lib.baseboard_fab2(sch_1):page122_i63:vccpusbdsw_3p3" )
			)
			( pin "U7C1.AG22"
				( objectStatus "@baseboard_fab2_lib.baseboard_fab2(sch_1):page122_i63:vccrtcext" )
			)
			( pin "U7C1.N31"
				( objectStatus "@baseboard_fab2_lib.baseboard_fab2(sch_1):page123_i13:vss(355)" )
			)
			( pin "U7C1.N27"
				( objectStatus "@baseboard_fab2_lib.baseboard_fab2(sch_1):page123_i13:vss(356)" )
			)
			( pin "U7C1.N24"
				( objectStatus "@baseboard_fab2_lib.baseboard_fab2(sch_1):page123_i13:vss(357)" )
			)
			( pin "U7C1.N20"
				( objectStatus "@baseboard_fab2_lib.baseboard_fab2(sch_1):page123_i13:vss(358)" )
			)
			( pin "U7C1.N17"
				( objectStatus "@baseboard_fab2_lib.baseboard_fab2(sch_1):page123_i13:vss(359)" )
			)
			( pin "U7C1.N13"
				( objectStatus "@baseboard_fab2_lib.baseboard_fab2(sch_1):page123_i13:vss(360)" )
			)
			( pin "U7C1.M48"
				( objectStatus "@baseboard_fab2_lib.baseboard_fab2(sch_1):page123_i13:vss(361)" )
			)
			( pin "U7C1.M44"
				( objectStatus "@baseboard_fab2_lib.baseboard_fab2(sch_1):page123_i13:vss(362)" )
			)
			( pin "U7C1.N50"
				( objectStatus "@baseboard_fab2_lib.baseboard_fab2(sch_1):page123_i13:vss(363)" )
			)
			( pin "U7C1.N42"
				( objectStatus "@baseboard_fab2_lib.baseboard_fab2(sch_1):page123_i13:vss(364)" )
			)
			( pin "U7C1.M40"
				( objectStatus "@baseboard_fab2_lib.baseboard_fab2(sch_1):page123_i13:vss(365)" )
			)
			( pin "U7C1.M4"
				( objectStatus "@baseboard_fab2_lib.baseboard_fab2(sch_1):page123_i13:vss(366)" )
			)
			( pin "U7C1.M37"
				( objectStatus "@baseboard_fab2_lib.baseboard_fab2(sch_1):page123_i13:vss(367)" )
			)
			( pin "U7C1.M33"
				( objectStatus "@baseboard_fab2_lib.baseboard_fab2(sch_1):page123_i13:vss(368)" )
			)
			( pin "U7C1.M29"
				( objectStatus "@baseboard_fab2_lib.baseboard_fab2(sch_1):page123_i13:vss(369)" )
			)
			( pin "U7C1.M26"
				( objectStatus "@baseboard_fab2_lib.baseboard_fab2(sch_1):page123_i13:vss(370)" )
			)
			( pin "U7C1.M22"
				( objectStatus "@baseboard_fab2_lib.baseboard_fab2(sch_1):page123_i13:vss(371)" )
			)
			( pin "U7C1.M2"
				( objectStatus "@baseboard_fab2_lib.baseboard_fab2(sch_1):page123_i13:vss(372)" )
			)
			( pin "U7C1.L68"
				( objectStatus "@baseboard_fab2_lib.baseboard_fab2(sch_1):page123_i13:vss(373)" )
			)
			( pin "U7C1.L5"
				( objectStatus "@baseboard_fab2_lib.baseboard_fab2(sch_1):page123_i13:vss(374)" )
			)
			( pin "U7C1.K71"
				( objectStatus "@baseboard_fab2_lib.baseboard_fab2(sch_1):page123_i13:vss(375)" )
			)
			( pin "U7C1.K69"
				( objectStatus "@baseboard_fab2_lib.baseboard_fab2(sch_1):page123_i13:vss(376)" )
			)
			( pin "U7C1.K54"
				( objectStatus "@baseboard_fab2_lib.baseboard_fab2(sch_1):page123_i13:vss(377)" )
			)
			( pin "U7C1.J70"
				( objectStatus "@baseboard_fab2_lib.baseboard_fab2(sch_1):page123_i13:vss(378)" )
			)
			( pin "U7C1.J68"
				( objectStatus "@baseboard_fab2_lib.baseboard_fab2(sch_1):page123_i13:vss(379)" )
			)
			( pin "U7C1.J59"
				( objectStatus "@baseboard_fab2_lib.baseboard_fab2(sch_1):page123_i13:vss(380)" )
			)
			( pin "U7C1.J44"
				( objectStatus "@baseboard_fab2_lib.baseboard_fab2(sch_1):page123_i13:vss(381)" )
			)
			( pin "U7C1.J37"
				( objectStatus "@baseboard_fab2_lib.baseboard_fab2(sch_1):page123_i13:vss(382)" )
			)
			( pin "U7C1.J22"
				( objectStatus "@baseboard_fab2_lib.baseboard_fab2(sch_1):page123_i13:vss(383)" )
			)
			( pin "U7C1.J15"
				( objectStatus "@baseboard_fab2_lib.baseboard_fab2(sch_1):page123_i13:vss(384)" )
			)
			( pin "U7C1.J11"
				( objectStatus "@baseboard_fab2_lib.baseboard_fab2(sch_1):page123_i13:vss(385)" )
			)
			( pin "U7C1.H65"
				( objectStatus "@baseboard_fab2_lib.baseboard_fab2(sch_1):page123_i13:vss(386)" )
			)
			( pin "U7C1.J7"
				( objectStatus "@baseboard_fab2_lib.baseboard_fab2(sch_1):page123_i13:vss(387)" )
			)
			( pin "U7C1.J5"
				( objectStatus "@baseboard_fab2_lib.baseboard_fab2(sch_1):page123_i13:vss(388)" )
			)
			( pin "U7C1.J29"
				( objectStatus "@baseboard_fab2_lib.baseboard_fab2(sch_1):page123_i13:vss(389)" )
			)
			( pin "U7C1.H58"
				( objectStatus "@baseboard_fab2_lib.baseboard_fab2(sch_1):page123_i13:vss(390)" )
			)
			( pin "U7C1.G66"
				( objectStatus "@baseboard_fab2_lib.baseboard_fab2(sch_1):page123_i13:vss(391)" )
			)
			( pin "U7C1.G63"
				( objectStatus "@baseboard_fab2_lib.baseboard_fab2(sch_1):page123_i13:vss(392)" )
			)
			( pin "U7C1.G6"
				( objectStatus "@baseboard_fab2_lib.baseboard_fab2(sch_1):page123_i13:vss(393)" )
			)
			( pin "U7C1.G48"
				( objectStatus "@baseboard_fab2_lib.baseboard_fab2(sch_1):page123_i13:vss(394)" )
			)
			( pin "U7C1.G37"
				( objectStatus "@baseboard_fab2_lib.baseboard_fab2(sch_1):page123_i13:vss(395)" )
			)
			( pin "U7C1.G29"
				( objectStatus "@baseboard_fab2_lib.baseboard_fab2(sch_1):page123_i13:vss(396)" )
			)
			( pin "U7C1.G22"
				( objectStatus "@baseboard_fab2_lib.baseboard_fab2(sch_1):page123_i13:vss(397)" )
			)
			( pin "U7C1.E9"
				( objectStatus "@baseboard_fab2_lib.baseboard_fab2(sch_1):page123_i13:vss(398)" )
			)
			( pin "U7C1.G59"
				( objectStatus "@baseboard_fab2_lib.baseboard_fab2(sch_1):page123_i13:vss(399)" )
			)
			( pin "U7C1.E63"
				( objectStatus "@baseboard_fab2_lib.baseboard_fab2(sch_1):page123_i13:vss(400)" )
			)
			( pin "U7C1.E61"
				( objectStatus "@baseboard_fab2_lib.baseboard_fab2(sch_1):page123_i13:vss(401)" )
			)
			( pin "U7C1.E6"
				( objectStatus "@baseboard_fab2_lib.baseboard_fab2(sch_1):page123_i13:vss(402)" )
			)
			( pin "U7C1.E57"
				( objectStatus "@baseboard_fab2_lib.baseboard_fab2(sch_1):page123_i13:vss(403)" )
			)
			( pin "U7C1.E54"
				( objectStatus "@baseboard_fab2_lib.baseboard_fab2(sch_1):page123_i13:vss(404)" )
			)
			( pin "U7C1.E52"
				( objectStatus "@baseboard_fab2_lib.baseboard_fab2(sch_1):page123_i13:vss(405)" )
			)
			( pin "U7C1.E50"
				( objectStatus "@baseboard_fab2_lib.baseboard_fab2(sch_1):page123_i13:vss(406)" )
			)
			( pin "U7C1.E48"
				( objectStatus "@baseboard_fab2_lib.baseboard_fab2(sch_1):page123_i13:vss(407)" )
			)
			( pin "U7C1.E45"
				( objectStatus "@baseboard_fab2_lib.baseboard_fab2(sch_1):page123_i13:vss(408)" )
			)
			( pin "U7C1.E43"
				( objectStatus "@baseboard_fab2_lib.baseboard_fab2(sch_1):page123_i13:vss(409)" )
			)
			( pin "U7C1.E41"
				( objectStatus "@baseboard_fab2_lib.baseboard_fab2(sch_1):page123_i13:vss(410)" )
			)
			( pin "U7C1.E39"
				( objectStatus "@baseboard_fab2_lib.baseboard_fab2(sch_1):page123_i13:vss(411)" )
			)
			( pin "U7C1.E37"
				( objectStatus "@baseboard_fab2_lib.baseboard_fab2(sch_1):page123_i13:vss(412)" )
			)
			( pin "U7C1.E34"
				( objectStatus "@baseboard_fab2_lib.baseboard_fab2(sch_1):page123_i13:vss(413)" )
			)
			( pin "U7C1.E32"
				( objectStatus "@baseboard_fab2_lib.baseboard_fab2(sch_1):page123_i13:vss(414)" )
			)
			( pin "U7C1.E30"
				( objectStatus "@baseboard_fab2_lib.baseboard_fab2(sch_1):page123_i13:vss(415)" )
			)
			( pin "U7C1.E28"
				( objectStatus "@baseboard_fab2_lib.baseboard_fab2(sch_1):page123_i13:vss(416)" )
			)
			( pin "U7C1.E26"
				( objectStatus "@baseboard_fab2_lib.baseboard_fab2(sch_1):page123_i13:vss(417)" )
			)
			( pin "U7C1.E24"
				( objectStatus "@baseboard_fab2_lib.baseboard_fab2(sch_1):page123_i13:vss(418)" )
			)
			( pin "U7C1.E22"
				( objectStatus "@baseboard_fab2_lib.baseboard_fab2(sch_1):page123_i13:vss(419)" )
			)
			( pin "U7C1.E20"
				( objectStatus "@baseboard_fab2_lib.baseboard_fab2(sch_1):page123_i13:vss(420)" )
			)
			( pin "U7C1.E15"
				( objectStatus "@baseboard_fab2_lib.baseboard_fab2(sch_1):page123_i13:vss(421)" )
			)
			( pin "U7C1.E13"
				( objectStatus "@baseboard_fab2_lib.baseboard_fab2(sch_1):page123_i13:vss(422)" )
			)
			( pin "U7C1.E11"
				( objectStatus "@baseboard_fab2_lib.baseboard_fab2(sch_1):page123_i13:vss(423)" )
			)
			( pin "U7C1.D47"
				( objectStatus "@baseboard_fab2_lib.baseboard_fab2(sch_1):page123_i13:vss(424)" )
			)
			( pin "U7C1.E65"
				( objectStatus "@baseboard_fab2_lib.baseboard_fab2(sch_1):page123_i13:vss(425)" )
			)
			( pin "U7C1.E59"
				( objectStatus "@baseboard_fab2_lib.baseboard_fab2(sch_1):page123_i13:vss(426)" )
			)
			( pin "U7C1.D27"
				( objectStatus "@baseboard_fab2_lib.baseboard_fab2(sch_1):page123_i13:vss(427)" )
			)
			( pin "U7C1.D25"
				( objectStatus "@baseboard_fab2_lib.baseboard_fab2(sch_1):page123_i13:vss(428)" )
			)
			( pin "U7C1.D19"
				( objectStatus "@baseboard_fab2_lib.baseboard_fab2(sch_1):page123_i13:vss(429)" )
			)
			( pin "U7C1.D16"
				( objectStatus "@baseboard_fab2_lib.baseboard_fab2(sch_1):page123_i13:vss(430)" )
			)
			( pin "U7C1.D12"
				( objectStatus "@baseboard_fab2_lib.baseboard_fab2(sch_1):page123_i13:vss(431)" )
			)
			( pin "U7C1.C65"
				( objectStatus "@baseboard_fab2_lib.baseboard_fab2(sch_1):page123_i13:vss(432)" )
			)
			( pin "U7C1.C41"
				( objectStatus "@baseboard_fab2_lib.baseboard_fab2(sch_1):page123_i13:vss(433)" )
			)
			( pin "U7C1.C37"
				( objectStatus "@baseboard_fab2_lib.baseboard_fab2(sch_1):page123_i13:vss(434)" )
			)
			( pin "U7C1.C34"
				( objectStatus "@baseboard_fab2_lib.baseboard_fab2(sch_1):page123_i13:vss(435)" )
			)
			( pin "U7C1.C30"
				( objectStatus "@baseboard_fab2_lib.baseboard_fab2(sch_1):page123_i13:vss(436)" )
			)
			( pin "U7C1.C22"
				( objectStatus "@baseboard_fab2_lib.baseboard_fab2(sch_1):page123_i13:vss(437)" )
			)
			( pin "U7C1.B47"
				( objectStatus "@baseboard_fab2_lib.baseboard_fab2(sch_1):page123_i13:vss(438)" )
			)
			( pin "U7C1.B27"
				( objectStatus "@baseboard_fab2_lib.baseboard_fab2(sch_1):page123_i13:vss(439)" )
			)
			( pin "U7C1.B25"
				( objectStatus "@baseboard_fab2_lib.baseboard_fab2(sch_1):page123_i13:vss(440)" )
			)
			( pin "U7C1.B19"
				( objectStatus "@baseboard_fab2_lib.baseboard_fab2(sch_1):page123_i13:vss(441)" )
			)
			( pin "U7C1.B12"
				( objectStatus "@baseboard_fab2_lib.baseboard_fab2(sch_1):page123_i13:vss(442)" )
			)
			( pin "U7C1.A41"
				( objectStatus "@baseboard_fab2_lib.baseboard_fab2(sch_1):page123_i13:vss(443)" )
			)
			( pin "U7C1.A37"
				( objectStatus "@baseboard_fab2_lib.baseboard_fab2(sch_1):page123_i13:vss(444)" )
			)
			( pin "U7C1.A34"
				( objectStatus "@baseboard_fab2_lib.baseboard_fab2(sch_1):page123_i13:vss(445)" )
			)
			( pin "U7C1.A30"
				( objectStatus "@baseboard_fab2_lib.baseboard_fab2(sch_1):page123_i13:vss(446)" )
			)
			( pin "U7C1.A22"
				( objectStatus "@baseboard_fab2_lib.baseboard_fab2(sch_1):page123_i13:vss(447)" )
			)
			( pin "U7C1.A18"
				( objectStatus "@baseboard_fab2_lib.baseboard_fab2(sch_1):page123_i13:vss(448)" )
			)
			( pin "U7C1.Y70"
				( objectStatus "@baseboard_fab2_lib.baseboard_fab2(sch_1):page123_i13:vss(449)" )
			)
			( pin "U7C1.Y72"
				( objectStatus "@baseboard_fab2_lib.baseboard_fab2(sch_1):page123_i13:vss(450)" )
			)
			( pin "U7C1.AT37"
				( objectStatus "@baseboard_fab2_lib.baseboard_fab2(sch_1):page123_i13:vss(451)" )
			)
			( pin "U7C1.BB48"
				( objectStatus "@baseboard_fab2_lib.baseboard_fab2(sch_1):page123_i13:vss(452)" )
			)
			( pin "U7C1.CA70"
				( objectStatus "@baseboard_fab2_lib.baseboard_fab2(sch_1):page123_i13:vss(453)" )
			)
			( pin "U7C1.BW72"
				( objectStatus "@baseboard_fab2_lib.baseboard_fab2(sch_1):page123_i13:vss(454)" )
			)
			( pin "U7C1.BW70"
				( objectStatus "@baseboard_fab2_lib.baseboard_fab2(sch_1):page123_i13:vss(455)" )
			)
			( pin "U7C1.BU72"
				( objectStatus "@baseboard_fab2_lib.baseboard_fab2(sch_1):page123_i13:vss(456)" )
			)
			( pin "U7C1.BR72"
				( objectStatus "@baseboard_fab2_lib.baseboard_fab2(sch_1):page123_i13:vss(457)" )
			)
			( pin "U7C1.G72"
				( objectStatus "@baseboard_fab2_lib.baseboard_fab2(sch_1):page123_i13:vss(458)" )
			)
			( pin "U7C1.G1"
				( objectStatus "@baseboard_fab2_lib.baseboard_fab2(sch_1):page123_i13:vss(459)" )
			)
			( pin "U7C1.E72"
				( objectStatus "@baseboard_fab2_lib.baseboard_fab2(sch_1):page123_i13:vss(460)" )
			)
			( pin "U7C1.E1"
				( objectStatus "@baseboard_fab2_lib.baseboard_fab2(sch_1):page123_i13:vss(461)" )
			)
			( pin "U7C1.C72"
				( objectStatus "@baseboard_fab2_lib.baseboard_fab2(sch_1):page123_i13:vss(462)" )
			)
			( pin "U7C1.C3"
				( objectStatus "@baseboard_fab2_lib.baseboard_fab2(sch_1):page123_i13:vss(463)" )
			)
			( pin "U7C1.BR1"
				( objectStatus "@baseboard_fab2_lib.baseboard_fab2(sch_1):page123_i13:vss(464)" )
			)
			( pin "U7C1.BU1"
				( objectStatus "@baseboard_fab2_lib.baseboard_fab2(sch_1):page123_i13:vss(465)" )
			)
			( pin "U7C1.BW1"
				( objectStatus "@baseboard_fab2_lib.baseboard_fab2(sch_1):page123_i13:vss(466)" )
			)
			( pin "U7C1.CA3"
				( objectStatus "@baseboard_fab2_lib.baseboard_fab2(sch_1):page123_i13:vss(467)" )
			)
			( pin "U7C1.A70"
				( objectStatus "@baseboard_fab2_lib.baseboard_fab2(sch_1):page123_i13:vss(468)" )
			)
			( pin "U7C1.CA5"
				( objectStatus "@baseboard_fab2_lib.baseboard_fab2(sch_1):page123_i13:vss(469)" )
			)
			( pin "U7C1.CA7"
				( objectStatus "@baseboard_fab2_lib.baseboard_fab2(sch_1):page123_i13:vss(470)" )
			)
			( pin "U7C1.CA9"
				( objectStatus "@baseboard_fab2_lib.baseboard_fab2(sch_1):page123_i13:vss(471)" )
			)
			( pin "U7C1.CA65"
				( objectStatus "@baseboard_fab2_lib.baseboard_fab2(sch_1):page123_i13:vss(472)" )
			)
			( pin "U7C1.CA66"
				( objectStatus "@baseboard_fab2_lib.baseboard_fab2(sch_1):page123_i13:vss(473)" )
			)
			( pin "U7C1.CA68"
				( objectStatus "@baseboard_fab2_lib.baseboard_fab2(sch_1):page123_i13:vss(474)" )
			)
			( pin "U7C1.BN72"
				( objectStatus "@baseboard_fab2_lib.baseboard_fab2(sch_1):page123_i13:vss(475)" )
			)
			( pin "U7C1.BN1"
				( objectStatus "@baseboard_fab2_lib.baseboard_fab2(sch_1):page123_i13:vss(476)" )
			)
			( pin "U7C1.J72"
				( objectStatus "@baseboard_fab2_lib.baseboard_fab2(sch_1):page123_i13:vss(477)" )
			)
			( pin "U7C1.J1"
				( objectStatus "@baseboard_fab2_lib.baseboard_fab2(sch_1):page123_i13:vss(478)" )
			)
			( pin "U7C1.A68"
				( objectStatus "@baseboard_fab2_lib.baseboard_fab2(sch_1):page123_i13:vss(479)" )
			)
			( pin "U7C1.A66"
				( objectStatus "@baseboard_fab2_lib.baseboard_fab2(sch_1):page123_i13:vss(480)" )
			)
			( pin "U7C1.A65"
				( objectStatus "@baseboard_fab2_lib.baseboard_fab2(sch_1):page123_i13:vss(481)" )
			)
			( pin "U7C1.A9"
				( objectStatus "@baseboard_fab2_lib.baseboard_fab2(sch_1):page123_i13:vss(482)" )
			)
			( pin "U7C1.A7"
				( objectStatus "@baseboard_fab2_lib.baseboard_fab2(sch_1):page123_i13:vss(483)" )
			)
			( pin "U7C1.A5"
				( objectStatus "@baseboard_fab2_lib.baseboard_fab2(sch_1):page123_i13:vss(484)" )
			)
			( pin "U7C1.E3"
				( objectStatus "@baseboard_fab2_lib.baseboard_fab2(sch_1):page123_i13:vss(485)" )
			)
			( pin "U7C1.F3"
				( objectStatus "@baseboard_fab2_lib.baseboard_fab2(sch_1):page123_i13:vss(486)" )
			)
			( pin "U7C1.BR3"
				( objectStatus "@baseboard_fab2_lib.baseboard_fab2(sch_1):page123_i13:vss(487)" )
			)
			( pin "U7C1.BU3"
				( objectStatus "@baseboard_fab2_lib.baseboard_fab2(sch_1):page123_i13:vss(488)" )
			)
			( pin "U7C1.E70"
				( objectStatus "@baseboard_fab2_lib.baseboard_fab2(sch_1):page123_i13:vss(489)" )
			)
			( pin "U7C1.F70"
				( objectStatus "@baseboard_fab2_lib.baseboard_fab2(sch_1):page123_i13:vss(490)" )
			)
			( pin "U7C1.BR70"
				( objectStatus "@baseboard_fab2_lib.baseboard_fab2(sch_1):page123_i13:vss(491)" )
			)
			( pin "U7C1.BU70"
				( objectStatus "@baseboard_fab2_lib.baseboard_fab2(sch_1):page123_i13:vss(492)" )
			)
			( pin "U7C1.BT69"
				( objectStatus "@baseboard_fab2_lib.baseboard_fab2(sch_1):page123_i13:vss(493)" )
			)
			( pin "U7C1.BP69"
				( objectStatus "@baseboard_fab2_lib.baseboard_fab2(sch_1):page123_i13:vss(494)" )
			)
			( pin "U7C1.AE27"
				( objectStatus "@baseboard_fab2_lib.baseboard_fab2(sch_1):page123_i21:vccmphy_1p05(13)" )
			)
			( pin "U7C1.AU36"
				( objectStatus "@baseboard_fab2_lib.baseboard_fab2(sch_1):page123_i21:vccprim_avid(0)" )
			)
			( pin "U7C1.AU34"
				( objectStatus "@baseboard_fab2_lib.baseboard_fab2(sch_1):page123_i21:vccprim_avid(1)" )
			)
			( pin "U7C1.AU32"
				( objectStatus "@baseboard_fab2_lib.baseboard_fab2(sch_1):page123_i21:vccprim_avid(2)" )
			)
			( pin "U7C1.AT36"
				( objectStatus "@baseboard_fab2_lib.baseboard_fab2(sch_1):page123_i21:vccprim_avid(3)" )
			)
			( pin "U7C1.AT34"
				( objectStatus "@baseboard_fab2_lib.baseboard_fab2(sch_1):page123_i21:vccprim_avid(4)" )
			)
			( pin "U7C1.AT32"
				( objectStatus "@baseboard_fab2_lib.baseboard_fab2(sch_1):page123_i21:vccprim_avid(5)" )
			)
			( pin "U7C1.AP39"
				( objectStatus "@baseboard_fab2_lib.baseboard_fab2(sch_1):page123_i21:vccprim_avid(6)" )
			)
			( pin "U7C1.AP37"
				( objectStatus "@baseboard_fab2_lib.baseboard_fab2(sch_1):page123_i21:vccprim_avid(7)" )
			)
			( pin "U7C1.AP36"
				( objectStatus "@baseboard_fab2_lib.baseboard_fab2(sch_1):page123_i21:vccprim_avid(8)" )
			)
			( pin "U7C1.AP34"
				( objectStatus "@baseboard_fab2_lib.baseboard_fab2(sch_1):page123_i21:vccprim_avid(9)" )
			)
			( pin "U7C1.AP32"
				( objectStatus "@baseboard_fab2_lib.baseboard_fab2(sch_1):page123_i21:vccprim_avid(10)" )
			)
			( pin "U7C1.AM39"
				( objectStatus "@baseboard_fab2_lib.baseboard_fab2(sch_1):page123_i21:vccprim_avid(11)" )
			)
			( pin "U7C1.AM37"
				( objectStatus "@baseboard_fab2_lib.baseboard_fab2(sch_1):page123_i21:vccprim_avid(12)" )
			)
			( pin "U7C1.AM36"
				( objectStatus "@baseboard_fab2_lib.baseboard_fab2(sch_1):page123_i21:vccprim_avid(13)" )
			)
			( pin "U7C1.AM34"
				( objectStatus "@baseboard_fab2_lib.baseboard_fab2(sch_1):page123_i21:vccprim_avid(14)" )
			)
			( pin "U7C1.AM32"
				( objectStatus "@baseboard_fab2_lib.baseboard_fab2(sch_1):page123_i21:vccprim_avid(15)" )
			)
			( pin "U7C1.AK39"
				( objectStatus "@baseboard_fab2_lib.baseboard_fab2(sch_1):page123_i21:vccprim_avid(16)" )
			)
			( pin "U7C1.AK37"
				( objectStatus "@baseboard_fab2_lib.baseboard_fab2(sch_1):page123_i21:vccprim_avid(17)" )
			)
			( pin "U7C1.AK34"
				( objectStatus "@baseboard_fab2_lib.baseboard_fab2(sch_1):page123_i21:vccprim_avid(18)" )
			)
			( pin "U7C1.AG39"
				( objectStatus "@baseboard_fab2_lib.baseboard_fab2(sch_1):page123_i21:vccprim_avid(19)" )
			)
			( pin "U7C1.AG37"
				( objectStatus "@baseboard_fab2_lib.baseboard_fab2(sch_1):page123_i21:vccprim_avid(20)" )
			)
			( pin "U7C1.AG36"
				( objectStatus "@baseboard_fab2_lib.baseboard_fab2(sch_1):page123_i21:vccprim_avid(21)" )
			)
			( pin "U7C1.AG34"
				( objectStatus "@baseboard_fab2_lib.baseboard_fab2(sch_1):page123_i21:vccprim_avid(22)" )
			)
			( pin "U7C1.AG32"
				( objectStatus "@baseboard_fab2_lib.baseboard_fab2(sch_1):page123_i21:vccprim_avid(23)" )
			)
			( pin "U7C1.AE41"
				( objectStatus "@baseboard_fab2_lib.baseboard_fab2(sch_1):page123_i21:vccprim_avid(24)" )
			)
			( pin "U7C1.AE39"
				( objectStatus "@baseboard_fab2_lib.baseboard_fab2(sch_1):page123_i21:vccprim_avid(25)" )
			)
			( pin "U7C1.AE37"
				( objectStatus "@baseboard_fab2_lib.baseboard_fab2(sch_1):page123_i21:vccprim_avid(26)" )
			)
			( pin "U7C1.AE36"
				( objectStatus "@baseboard_fab2_lib.baseboard_fab2(sch_1):page123_i21:vccprim_avid(27)" )
			)
			( pin "U7C1.AE34"
				( objectStatus "@baseboard_fab2_lib.baseboard_fab2(sch_1):page123_i21:vccprim_avid(28)" )
			)
			( pin "U7C1.AE32"
				( objectStatus "@baseboard_fab2_lib.baseboard_fab2(sch_1):page123_i21:vccprim_avid(29)" )
			)
			( pin "U7C1.AE30"
				( objectStatus "@baseboard_fab2_lib.baseboard_fab2(sch_1):page123_i21:vccprim_avid(30)" )
			)
			( pin "U7C1.U27"
				( objectStatus "@baseboard_fab2_lib.baseboard_fab2(sch_1):page123_i21:vccprim_avid(31)" )
			)
			( pin "U7C1.AC41"
				( objectStatus "@baseboard_fab2_lib.baseboard_fab2(sch_1):page123_i21:vccprim_avid(32)" )
			)
			( pin "U7C1.AC39"
				( objectStatus "@baseboard_fab2_lib.baseboard_fab2(sch_1):page123_i21:vccprim_avid(33)" )
			)
			( pin "U7C1.AC37"
				( objectStatus "@baseboard_fab2_lib.baseboard_fab2(sch_1):page123_i21:vccprim_avid(34)" )
			)
			( pin "U7C1.AC36"
				( objectStatus "@baseboard_fab2_lib.baseboard_fab2(sch_1):page123_i21:vccprim_avid(35)" )
			)
			( pin "U7C1.AC34"
				( objectStatus "@baseboard_fab2_lib.baseboard_fab2(sch_1):page123_i21:vccprim_avid(36)" )
			)
			( pin "U7C1.AC32"
				( objectStatus "@baseboard_fab2_lib.baseboard_fab2(sch_1):page123_i21:vccprim_avid(37)" )
			)
			( pin "U7C1.AC30"
				( objectStatus "@baseboard_fab2_lib.baseboard_fab2(sch_1):page123_i21:vccprim_avid(38)" )
			)
			( pin "U7C1.AC29"
				( objectStatus "@baseboard_fab2_lib.baseboard_fab2(sch_1):page123_i21:vccprim_avid(39)" )
			)
			( pin "U7C1.AA41"
				( objectStatus "@baseboard_fab2_lib.baseboard_fab2(sch_1):page123_i21:vccprim_avid(40)" )
			)
			( pin "U7C1.AA39"
				( objectStatus "@baseboard_fab2_lib.baseboard_fab2(sch_1):page123_i21:vccprim_avid(41)" )
			)
			( pin "U7C1.AA37"
				( objectStatus "@baseboard_fab2_lib.baseboard_fab2(sch_1):page123_i21:vccprim_avid(42)" )
			)
			( pin "U7C1.AA36"
				( objectStatus "@baseboard_fab2_lib.baseboard_fab2(sch_1):page123_i21:vccprim_avid(43)" )
			)
			( pin "U7C1.AA34"
				( objectStatus "@baseboard_fab2_lib.baseboard_fab2(sch_1):page123_i21:vccprim_avid(44)" )
			)
			( pin "U7C1.AA32"
				( objectStatus "@baseboard_fab2_lib.baseboard_fab2(sch_1):page123_i21:vccprim_avid(45)" )
			)
			( pin "U7C1.AA30"
				( objectStatus "@baseboard_fab2_lib.baseboard_fab2(sch_1):page123_i21:vccprim_avid(46)" )
			)
			( pin "U7C1.AA29"
				( objectStatus "@baseboard_fab2_lib.baseboard_fab2(sch_1):page123_i21:vccprim_avid(47)" )
			)
			( pin "U7C1.Y41"
				( objectStatus "@baseboard_fab2_lib.baseboard_fab2(sch_1):page123_i21:vccprim_avid(48)" )
			)
			( pin "U7C1.Y39"
				( objectStatus "@baseboard_fab2_lib.baseboard_fab2(sch_1):page123_i21:vccprim_avid(49)" )
			)
			( pin "U7C1.Y37"
				( objectStatus "@baseboard_fab2_lib.baseboard_fab2(sch_1):page123_i21:vccprim_avid(50)" )
			)
			( pin "U7C1.Y36"
				( objectStatus "@baseboard_fab2_lib.baseboard_fab2(sch_1):page123_i21:vccprim_avid(51)" )
			)
			( pin "U7C1.Y34"
				( objectStatus "@baseboard_fab2_lib.baseboard_fab2(sch_1):page123_i21:vccprim_avid(52)" )
			)
			( pin "U7C1.Y32"
				( objectStatus "@baseboard_fab2_lib.baseboard_fab2(sch_1):page123_i21:vccprim_avid(53)" )
			)
			( pin "U7C1.Y30"
				( objectStatus "@baseboard_fab2_lib.baseboard_fab2(sch_1):page123_i21:vccprim_avid(54)" )
			)
			( pin "U7C1.Y29"
				( objectStatus "@baseboard_fab2_lib.baseboard_fab2(sch_1):page123_i21:vccprim_avid(55)" )
			)
			( pin "U7C1.V40"
				( objectStatus "@baseboard_fab2_lib.baseboard_fab2(sch_1):page123_i21:vccprim_avid(56)" )
			)
			( pin "U7C1.V33"
				( objectStatus "@baseboard_fab2_lib.baseboard_fab2(sch_1):page123_i21:vccprim_avid(57)" )
			)
			( pin "U7C1.V29"
				( objectStatus "@baseboard_fab2_lib.baseboard_fab2(sch_1):page123_i21:vccprim_avid(58)" )
			)
			( pin "U7C1.U38"
				( objectStatus "@baseboard_fab2_lib.baseboard_fab2(sch_1):page123_i21:vccprim_avid(59)" )
			)
			( pin "U7C1.U35"
				( objectStatus "@baseboard_fab2_lib.baseboard_fab2(sch_1):page123_i21:vccprim_avid(60)" )
			)
			( pin "U7C1.U31"
				( objectStatus "@baseboard_fab2_lib.baseboard_fab2(sch_1):page123_i21:vccprim_avid(61)" )
			)
			( pin "U7C1.AK32"
				( objectStatus "@baseboard_fab2_lib.baseboard_fab2(sch_1):page123_i21:vccprim_avid(62)" )
			)
			( pin "U7C1.V37"
				( objectStatus "@baseboard_fab2_lib.baseboard_fab2(sch_1):page123_i21:vccprim_avid_qat_sense" )
			)
			( pin "U7C1.AK36"
				( objectStatus "@baseboard_fab2_lib.baseboard_fab2(sch_1):page123_i21:vccprim_avid_sense" )
			)
			( pin "U7C1.CA52"
				( objectStatus "@baseboard_fab2_lib.baseboard_fab2(sch_1):page124_i15:vss(0)" )
			)
			( pin "U7C1.CA50"
				( objectStatus "@baseboard_fab2_lib.baseboard_fab2(sch_1):page124_i15:vss(1)" )
			)
			( pin "U7C1.CA26"
				( objectStatus "@baseboard_fab2_lib.baseboard_fab2(sch_1):page124_i15:vss(2)" )
			)
			( pin "U7C1.CA18"
				( objectStatus "@baseboard_fab2_lib.baseboard_fab2(sch_1):page124_i15:vss(3)" )
			)
			( pin "U7C1.CA15"
				( objectStatus "@baseboard_fab2_lib.baseboard_fab2(sch_1):page124_i15:vss(4)" )
			)
			( pin "U7C1.BY49"
				( objectStatus "@baseboard_fab2_lib.baseboard_fab2(sch_1):page124_i15:vss(5)" )
			)
			( pin "U7C1.BY40"
				( objectStatus "@baseboard_fab2_lib.baseboard_fab2(sch_1):page124_i15:vss(6)" )
			)
			( pin "U7C1.BW52"
				( objectStatus "@baseboard_fab2_lib.baseboard_fab2(sch_1):page124_i15:vss(7)" )
			)
			( pin "U7C1.BW26"
				( objectStatus "@baseboard_fab2_lib.baseboard_fab2(sch_1):page124_i15:vss(8)" )
			)
			( pin "U7C1.BW18"
				( objectStatus "@baseboard_fab2_lib.baseboard_fab2(sch_1):page124_i15:vss(9)" )
			)
			( pin "U7C1.BW15"
				( objectStatus "@baseboard_fab2_lib.baseboard_fab2(sch_1):page124_i15:vss(10)" )
			)
			( pin "U7C1.BV40"
				( objectStatus "@baseboard_fab2_lib.baseboard_fab2(sch_1):page124_i15:vss(11)" )
			)
			( pin "U7C1.BU9"
				( objectStatus "@baseboard_fab2_lib.baseboard_fab2(sch_1):page124_i15:vss(12)" )
			)
			( pin "U7C1.BU63"
				( objectStatus "@baseboard_fab2_lib.baseboard_fab2(sch_1):page124_i15:vss(13)" )
			)
			( pin "U7C1.BU61"
				( objectStatus "@baseboard_fab2_lib.baseboard_fab2(sch_1):page124_i15:vss(14)" )
			)
			( pin "U7C1.BU59"
				( objectStatus "@baseboard_fab2_lib.baseboard_fab2(sch_1):page124_i15:vss(15)" )
			)
			( pin "U7C1.BU57"
				( objectStatus "@baseboard_fab2_lib.baseboard_fab2(sch_1):page124_i15:vss(16)" )
			)
			( pin "U7C1.BU54"
				( objectStatus "@baseboard_fab2_lib.baseboard_fab2(sch_1):page124_i15:vss(17)" )
			)
			( pin "U7C1.BU52"
				( objectStatus "@baseboard_fab2_lib.baseboard_fab2(sch_1):page124_i15:vss(18)" )
			)
			( pin "U7C1.BU50"
				( objectStatus "@baseboard_fab2_lib.baseboard_fab2(sch_1):page124_i15:vss(19)" )
			)
			( pin "U7C1.BU48"
				( objectStatus "@baseboard_fab2_lib.baseboard_fab2(sch_1):page124_i15:vss(20)" )
			)
			( pin "U7C1.BU45"
				( objectStatus "@baseboard_fab2_lib.baseboard_fab2(sch_1):page124_i15:vss(21)" )
			)
			( pin "U7C1.BU43"
				( objectStatus "@baseboard_fab2_lib.baseboard_fab2(sch_1):page124_i15:vss(22)" )
			)
			( pin "U7C1.BU41"
				( objectStatus "@baseboard_fab2_lib.baseboard_fab2(sch_1):page124_i15:vss(23)" )
			)
			( pin "U7C1.BU39"
				( objectStatus "@baseboard_fab2_lib.baseboard_fab2(sch_1):page124_i15:vss(24)" )
			)
			( pin "U7C1.BU37"
				( objectStatus "@baseboard_fab2_lib.baseboard_fab2(sch_1):page124_i15:vss(25)" )
			)
			( pin "U7C1.BU34"
				( objectStatus "@baseboard_fab2_lib.baseboard_fab2(sch_1):page124_i15:vss(26)" )
			)
			( pin "U7C1.BU32"
				( objectStatus "@baseboard_fab2_lib.baseboard_fab2(sch_1):page124_i15:vss(27)" )
			)
			( pin "U7C1.BU30"
				( objectStatus "@baseboard_fab2_lib.baseboard_fab2(sch_1):page124_i15:vss(28)" )
			)
			( pin "U7C1.BU28"
				( objectStatus "@baseboard_fab2_lib.baseboard_fab2(sch_1):page124_i15:vss(29)" )
			)
			( pin "U7C1.BU26"
				( objectStatus "@baseboard_fab2_lib.baseboard_fab2(sch_1):page124_i15:vss(30)" )
			)
			( pin "U7C1.BU24"
				( objectStatus "@baseboard_fab2_lib.baseboard_fab2(sch_1):page124_i15:vss(31)" )
			)
			( pin "U7C1.BU22"
				( objectStatus "@baseboard_fab2_lib.baseboard_fab2(sch_1):page124_i15:vss(32)" )
			)
			( pin "U7C1.BU20"
				( objectStatus "@baseboard_fab2_lib.baseboard_fab2(sch_1):page124_i15:vss(33)" )
			)
			( pin "U7C1.BU18"
				( objectStatus "@baseboard_fab2_lib.baseboard_fab2(sch_1):page124_i15:vss(34)" )
			)
			( pin "U7C1.BU15"
				( objectStatus "@baseboard_fab2_lib.baseboard_fab2(sch_1):page124_i15:vss(35)" )
			)
			( pin "U7C1.BV49"
				( objectStatus "@baseboard_fab2_lib.baseboard_fab2(sch_1):page124_i15:vss(36)" )
			)
			( pin "U7C1.BU11"
				( objectStatus "@baseboard_fab2_lib.baseboard_fab2(sch_1):page124_i15:vss(37)" )
			)
			( pin "U7C1.BU13"
				( objectStatus "@baseboard_fab2_lib.baseboard_fab2(sch_1):page124_i15:vss(38)" )
			)
			( pin "U7C1.BT66"
				( objectStatus "@baseboard_fab2_lib.baseboard_fab2(sch_1):page124_i15:vss(39)" )
			)
			( pin "U7C1.BR6"
				( objectStatus "@baseboard_fab2_lib.baseboard_fab2(sch_1):page124_i15:vss(40)" )
			)
			( pin "U7C1.BR58"
				( objectStatus "@baseboard_fab2_lib.baseboard_fab2(sch_1):page124_i15:vss(41)" )
			)
			( pin "U7C1.BR54"
				( objectStatus "@baseboard_fab2_lib.baseboard_fab2(sch_1):page124_i15:vss(42)" )
			)
			( pin "U7C1.BT8"
				( objectStatus "@baseboard_fab2_lib.baseboard_fab2(sch_1):page124_i15:vss(43)" )
			)
			( pin "U7C1.BR50"
				( objectStatus "@baseboard_fab2_lib.baseboard_fab2(sch_1):page124_i15:vss(44)" )
			)
			( pin "U7C1.BR20"
				( objectStatus "@baseboard_fab2_lib.baseboard_fab2(sch_1):page124_i15:vss(45)" )
			)
			( pin "U7C1.BN66"
				( objectStatus "@baseboard_fab2_lib.baseboard_fab2(sch_1):page124_i15:vss(46)" )
			)
			( pin "U7C1.BN52"
				( objectStatus "@baseboard_fab2_lib.baseboard_fab2(sch_1):page124_i15:vss(47)" )
			)
			( pin "U7C1.BN5"
				( objectStatus "@baseboard_fab2_lib.baseboard_fab2(sch_1):page124_i15:vss(48)" )
			)
			( pin "U7C1.BN59"
				( objectStatus "@baseboard_fab2_lib.baseboard_fab2(sch_1):page124_i15:vss(49)" )
			)
			( pin "U7C1.BN22"
				( objectStatus "@baseboard_fab2_lib.baseboard_fab2(sch_1):page124_i15:vss(50)" )
			)
			( pin "U7C1.BM9"
				( objectStatus "@baseboard_fab2_lib.baseboard_fab2(sch_1):page124_i15:vss(51)" )
			)
			( pin "U7C1.BM71"
				( objectStatus "@baseboard_fab2_lib.baseboard_fab2(sch_1):page124_i15:vss(52)" )
			)
			( pin "U7C1.BM69"
				( objectStatus "@baseboard_fab2_lib.baseboard_fab2(sch_1):page124_i15:vss(53)" )
			)
			( pin "U7C1.BM58"
				( objectStatus "@baseboard_fab2_lib.baseboard_fab2(sch_1):page124_i15:vss(54)" )
			)
			( pin "U7C1.BM50"
				( objectStatus "@baseboard_fab2_lib.baseboard_fab2(sch_1):page124_i15:vss(55)" )
			)
			( pin "U7C1.BM46"
				( objectStatus "@baseboard_fab2_lib.baseboard_fab2(sch_1):page124_i15:vss(56)" )
			)
			( pin "U7C1.BN37"
				( objectStatus "@baseboard_fab2_lib.baseboard_fab2(sch_1):page124_i15:vss(57)" )
			)
			( pin "U7C1.BM17"
				( objectStatus "@baseboard_fab2_lib.baseboard_fab2(sch_1):page124_i15:vss(58)" )
			)
			( pin "U7C1.BM13"
				( objectStatus "@baseboard_fab2_lib.baseboard_fab2(sch_1):page124_i15:vss(59)" )
			)
			( pin "U7C1.BL72"
				( objectStatus "@baseboard_fab2_lib.baseboard_fab2(sch_1):page124_i15:vss(60)" )
			)
			( pin "U7C1.BL70"
				( objectStatus "@baseboard_fab2_lib.baseboard_fab2(sch_1):page124_i15:vss(61)" )
			)
			( pin "U7C1.BL63"
				( objectStatus "@baseboard_fab2_lib.baseboard_fab2(sch_1):page124_i15:vss(62)" )
			)
			( pin "U7C1.BL5"
				( objectStatus "@baseboard_fab2_lib.baseboard_fab2(sch_1):page124_i15:vss(63)" )
			)
			( pin "U7C1.BL37"
				( objectStatus "@baseboard_fab2_lib.baseboard_fab2(sch_1):page124_i15:vss(64)" )
			)
			( pin "U7C1.BL68"
				( objectStatus "@baseboard_fab2_lib.baseboard_fab2(sch_1):page124_i15:vss(65)" )
			)
			( pin "U7C1.BL40"
				( objectStatus "@baseboard_fab2_lib.baseboard_fab2(sch_1):page124_i15:vss(66)" )
			)
			( pin "U7C1.BL22"
				( objectStatus "@baseboard_fab2_lib.baseboard_fab2(sch_1):page124_i15:vss(67)" )
			)
			( pin "U7C1.BK50"
				( objectStatus "@baseboard_fab2_lib.baseboard_fab2(sch_1):page124_i15:vss(68)" )
			)
			( pin "U7C1.BK42"
				( objectStatus "@baseboard_fab2_lib.baseboard_fab2(sch_1):page124_i15:vss(69)" )
			)
			( pin "U7C1.BK38"
				( objectStatus "@baseboard_fab2_lib.baseboard_fab2(sch_1):page124_i15:vss(70)" )
			)
			( pin "U7C1.BK35"
				( objectStatus "@baseboard_fab2_lib.baseboard_fab2(sch_1):page124_i15:vss(71)" )
			)
			( pin "U7C1.BK31"
				( objectStatus "@baseboard_fab2_lib.baseboard_fab2(sch_1):page124_i15:vss(72)" )
			)
			( pin "U7C1.BK27"
				( objectStatus "@baseboard_fab2_lib.baseboard_fab2(sch_1):page124_i15:vss(73)" )
			)
			( pin "U7C1.BK24"
				( objectStatus "@baseboard_fab2_lib.baseboard_fab2(sch_1):page124_i15:vss(74)" )
			)
			( pin "U7C1.BJ68"
				( objectStatus "@baseboard_fab2_lib.baseboard_fab2(sch_1):page124_i16:vss(75)" )
			)
			( pin "U7C1.BJ52"
				( objectStatus "@baseboard_fab2_lib.baseboard_fab2(sch_1):page124_i16:vss(76)" )
			)
			( pin "U7C1.BJ33"
				( objectStatus "@baseboard_fab2_lib.baseboard_fab2(sch_1):page124_i16:vss(77)" )
			)
			( pin "U7C1.BJ3"
				( objectStatus "@baseboard_fab2_lib.baseboard_fab2(sch_1):page124_i16:vss(78)" )
			)
			( pin "U7C1.BJ26"
				( objectStatus "@baseboard_fab2_lib.baseboard_fab2(sch_1):page124_i16:vss(79)" )
			)
			( pin "U7C1.BJ18"
				( objectStatus "@baseboard_fab2_lib.baseboard_fab2(sch_1):page124_i16:vss(80)" )
			)
			( pin "U7C1.BJ15"
				( objectStatus "@baseboard_fab2_lib.baseboard_fab2(sch_1):page124_i16:vss(81)" )
			)
			( pin "U7C1.BJ7"
				( objectStatus "@baseboard_fab2_lib.baseboard_fab2(sch_1):page124_i16:vss(82)" )
			)
			( pin "U7C1.BJ5"
				( objectStatus "@baseboard_fab2_lib.baseboard_fab2(sch_1):page124_i16:vss(83)" )
			)
			( pin "U7C1.BJ11"
				( objectStatus "@baseboard_fab2_lib.baseboard_fab2(sch_1):page124_i16:vss(84)" )
			)
			( pin "U7C1.BJ1"
				( objectStatus "@baseboard_fab2_lib.baseboard_fab2(sch_1):page124_i16:vss(85)" )
			)
			( pin "U7C1.BH54"
				( objectStatus "@baseboard_fab2_lib.baseboard_fab2(sch_1):page124_i16:vss(86)" )
			)
			( pin "U7C1.BH46"
				( objectStatus "@baseboard_fab2_lib.baseboard_fab2(sch_1):page124_i16:vss(87)" )
			)
			( pin "U7C1.BH42"
				( objectStatus "@baseboard_fab2_lib.baseboard_fab2(sch_1):page124_i16:vss(88)" )
			)
			( pin "U7C1.BH38"
				( objectStatus "@baseboard_fab2_lib.baseboard_fab2(sch_1):page124_i16:vss(89)" )
			)
			( pin "U7C1.BH27"
				( objectStatus "@baseboard_fab2_lib.baseboard_fab2(sch_1):page124_i16:vss(90)" )
			)
			( pin "U7C1.BG63"
				( objectStatus "@baseboard_fab2_lib.baseboard_fab2(sch_1):page124_i16:vss(91)" )
			)
			( pin "U7C1.BG59"
				( objectStatus "@baseboard_fab2_lib.baseboard_fab2(sch_1):page124_i16:vss(92)" )
			)
			( pin "U7C1.BG48"
				( objectStatus "@baseboard_fab2_lib.baseboard_fab2(sch_1):page124_i16:vss(93)" )
			)
			( pin "U7C1.BG33"
				( objectStatus "@baseboard_fab2_lib.baseboard_fab2(sch_1):page124_i16:vss(94)" )
			)
			( pin "U7C1.BF9"
				( objectStatus "@baseboard_fab2_lib.baseboard_fab2(sch_1):page124_i16:vss(95)" )
			)
			( pin "U7C1.BF68"
				( objectStatus "@baseboard_fab2_lib.baseboard_fab2(sch_1):page124_i16:vss(96)" )
			)
			( pin "U7C1.BF65"
				( objectStatus "@baseboard_fab2_lib.baseboard_fab2(sch_1):page124_i16:vss(97)" )
			)
			( pin "U7C1.BF61"
				( objectStatus "@baseboard_fab2_lib.baseboard_fab2(sch_1):page124_i16:vss(98)" )
			)
			( pin "U7C1.BF58"
				( objectStatus "@baseboard_fab2_lib.baseboard_fab2(sch_1):page124_i16:vss(99)" )
			)
			( pin "U7C1.BF50"
				( objectStatus "@baseboard_fab2_lib.baseboard_fab2(sch_1):page124_i16:vss(100)" )
			)
			( pin "U7C1.BF5"
				( objectStatus "@baseboard_fab2_lib.baseboard_fab2(sch_1):page124_i16:vss(101)" )
			)
			( pin "U7C1.BF42"
				( objectStatus "@baseboard_fab2_lib.baseboard_fab2(sch_1):page124_i16:vss(102)" )
			)
			( pin "U7C1.BF38"
				( objectStatus "@baseboard_fab2_lib.baseboard_fab2(sch_1):page124_i16:vss(103)" )
			)
			( pin "U7C1.BF27"
				( objectStatus "@baseboard_fab2_lib.baseboard_fab2(sch_1):page124_i16:vss(104)" )
			)
			( pin "U7C1.BF24"
				( objectStatus "@baseboard_fab2_lib.baseboard_fab2(sch_1):page124_i16:vss(105)" )
			)
			( pin "U7C1.BF20"
				( objectStatus "@baseboard_fab2_lib.baseboard_fab2(sch_1):page124_i16:vss(106)" )
			)
			( pin "U7C1.BG44"
				( objectStatus "@baseboard_fab2_lib.baseboard_fab2(sch_1):page124_i16:vss(107)" )
			)
			( pin "U7C1.BF54"
				( objectStatus "@baseboard_fab2_lib.baseboard_fab2(sch_1):page124_i16:vss(108)" )
			)
			( pin "U7C1.BF17"
				( objectStatus "@baseboard_fab2_lib.baseboard_fab2(sch_1):page124_i16:vss(109)" )
			)
			( pin "U7C1.BF13"
				( objectStatus "@baseboard_fab2_lib.baseboard_fab2(sch_1):page124_i16:vss(110)" )
			)
			( pin "U7C1.BE66"
				( objectStatus "@baseboard_fab2_lib.baseboard_fab2(sch_1):page124_i16:vss(111)" )
			)
			( pin "U7C1.BE63"
				( objectStatus "@baseboard_fab2_lib.baseboard_fab2(sch_1):page124_i16:vss(112)" )
			)
			( pin "U7C1.BE59"
				( objectStatus "@baseboard_fab2_lib.baseboard_fab2(sch_1):page124_i16:vss(113)" )
			)
			( pin "U7C1.BE56"
				( objectStatus "@baseboard_fab2_lib.baseboard_fab2(sch_1):page124_i16:vss(114)" )
			)
			( pin "U7C1.BE37"
				( objectStatus "@baseboard_fab2_lib.baseboard_fab2(sch_1):page124_i16:vss(115)" )
			)
			( pin "U7C1.BE33"
				( objectStatus "@baseboard_fab2_lib.baseboard_fab2(sch_1):page124_i16:vss(116)" )
			)
			( pin "U7C1.BE29"
				( objectStatus "@baseboard_fab2_lib.baseboard_fab2(sch_1):page124_i16:vss(117)" )
			)
			( pin "U7C1.BD68"
				( objectStatus "@baseboard_fab2_lib.baseboard_fab2(sch_1):page124_i16:vss(118)" )
			)
			( pin "U7C1.BD54"
				( objectStatus "@baseboard_fab2_lib.baseboard_fab2(sch_1):page124_i16:vss(119)" )
			)
			( pin "U7C1.BD50"
				( objectStatus "@baseboard_fab2_lib.baseboard_fab2(sch_1):page124_i16:vss(120)" )
			)
			( pin "U7C1.BD5"
				( objectStatus "@baseboard_fab2_lib.baseboard_fab2(sch_1):page124_i16:vss(121)" )
			)
			( pin "U7C1.BD35"
				( objectStatus "@baseboard_fab2_lib.baseboard_fab2(sch_1):page124_i16:vss(122)" )
			)
			( pin "U7C1.BD31"
				( objectStatus "@baseboard_fab2_lib.baseboard_fab2(sch_1):page124_i16:vss(123)" )
			)
			( pin "U7C1.BD27"
				( objectStatus "@baseboard_fab2_lib.baseboard_fab2(sch_1):page124_i16:vss(124)" )
			)
			( pin "U7C1.BD24"
				( objectStatus "@baseboard_fab2_lib.baseboard_fab2(sch_1):page124_i16:vss(125)" )
			)
			( pin "U7C1.BC71"
				( objectStatus "@baseboard_fab2_lib.baseboard_fab2(sch_1):page124_i16:vss(126)" )
			)
			( pin "U7C1.BC69"
				( objectStatus "@baseboard_fab2_lib.baseboard_fab2(sch_1):page124_i16:vss(127)" )
			)
			( pin "U7C1.BB72"
				( objectStatus "@baseboard_fab2_lib.baseboard_fab2(sch_1):page124_i16:vss(128)" )
			)
			( pin "U7C1.BB70"
				( objectStatus "@baseboard_fab2_lib.baseboard_fab2(sch_1):page124_i16:vss(129)" )
			)
			( pin "U7C1.BB68"
				( objectStatus "@baseboard_fab2_lib.baseboard_fab2(sch_1):page124_i16:vss(130)" )
			)
			( pin "U7C1.BB66"
				( objectStatus "@baseboard_fab2_lib.baseboard_fab2(sch_1):page124_i16:vss(131)" )
			)
			( pin "U7C1.BB59"
				( objectStatus "@baseboard_fab2_lib.baseboard_fab2(sch_1):page124_i16:vss(132)" )
			)
			( pin "U7C1.BB44"
				( objectStatus "@baseboard_fab2_lib.baseboard_fab2(sch_1):page124_i16:vss(133)" )
			)
			( pin "U7C1.BB22"
				( objectStatus "@baseboard_fab2_lib.baseboard_fab2(sch_1):page124_i16:vss(134)" )
			)
			( pin "U7C1.BB18"
				( objectStatus "@baseboard_fab2_lib.baseboard_fab2(sch_1):page124_i16:vss(135)" )
			)
			( pin "U7C1.BB15"
				( objectStatus "@baseboard_fab2_lib.baseboard_fab2(sch_1):page124_i16:vss(136)" )
			)
			( pin "U7C1.BB11"
				( objectStatus "@baseboard_fab2_lib.baseboard_fab2(sch_1):page124_i16:vss(137)" )
			)
			( pin "U7C1.BB7"
				( objectStatus "@baseboard_fab2_lib.baseboard_fab2(sch_1):page124_i16:vss(138)" )
			)
			( pin "U7C1.BB5"
				( objectStatus "@baseboard_fab2_lib.baseboard_fab2(sch_1):page124_i16:vss(139)" )
			)
			( pin "U7C1.BA58"
				( objectStatus "@baseboard_fab2_lib.baseboard_fab2(sch_1):page124_i16:vss(140)" )
			)
			( pin "U7C1.BA54"
				( objectStatus "@baseboard_fab2_lib.baseboard_fab2(sch_1):page124_i16:vss(141)" )
			)
			( pin "U7C1.BA50"
				( objectStatus "@baseboard_fab2_lib.baseboard_fab2(sch_1):page124_i16:vss(142)" )
			)
			( pin "U7C1.AY68"
				( objectStatus "@baseboard_fab2_lib.baseboard_fab2(sch_1):page124_i16:vss(143)" )
			)
			( pin "U7C1.AY63"
				( objectStatus "@baseboard_fab2_lib.baseboard_fab2(sch_1):page124_i16:vss(144)" )
			)
			( pin "U7C1.AY56"
				( objectStatus "@baseboard_fab2_lib.baseboard_fab2(sch_1):page124_i16:vss(145)" )
			)
			( pin "U7C1.AY22"
				( objectStatus "@baseboard_fab2_lib.baseboard_fab2(sch_1):page124_i16:vss(146)" )
			)
			( pin "U7C1.AY5"
				( objectStatus "@baseboard_fab2_lib.baseboard_fab2(sch_1):page124_i16:vss(147)" )
			)
			( pin "U7C1.AW61"
				( objectStatus "@baseboard_fab2_lib.baseboard_fab2(sch_1):page124_i16:vss(148)" )
			)
			( pin "U7C1.AW58"
				( objectStatus "@baseboard_fab2_lib.baseboard_fab2(sch_1):page124_i16:vss(149)" )
			)
			( pin "U7C1.AW50"
				( objectStatus "@baseboard_fab2_lib.baseboard_fab2(sch_1):page124_i16:vss(150)" )
			)
			( pin "U7C1.AW46"
				( objectStatus "@baseboard_fab2_lib.baseboard_fab2(sch_1):page124_i16:vss(151)" )
			)
			( pin "U7C1.AW41"
				( objectStatus "@baseboard_fab2_lib.baseboard_fab2(sch_1):page124_i16:vss(152)" )
			)
			( pin "U7C1.AW39"
				( objectStatus "@baseboard_fab2_lib.baseboard_fab2(sch_1):page124_i16:vss(153)" )
			)
			( pin "U7C1.AW37"
				( objectStatus "@baseboard_fab2_lib.baseboard_fab2(sch_1):page124_i16:vss(154)" )
			)
			( pin "U7C1.AW36"
				( objectStatus "@baseboard_fab2_lib.baseboard_fab2(sch_1):page124_i16:vss(155)" )
			)
			( pin "U7C1.AW34"
				( objectStatus "@baseboard_fab2_lib.baseboard_fab2(sch_1):page124_i16:vss(156)" )
			)
			( pin "U7C1.AW32"
				( objectStatus "@baseboard_fab2_lib.baseboard_fab2(sch_1):page124_i16:vss(157)" )
			)
			( pin "U7C1.AW30"
				( objectStatus "@baseboard_fab2_lib.baseboard_fab2(sch_1):page124_i16:vss(158)" )
			)
			( pin "U7C1.AW26"
				( objectStatus "@baseboard_fab2_lib.baseboard_fab2(sch_1):page124_i16:vss(159)" )
			)
			( pin "U7C1.AW17"
				( objectStatus "@baseboard_fab2_lib.baseboard_fab2(sch_1):page124_i16:vss(160)" )
			)
			( pin "U7C1.AW13"
				( objectStatus "@baseboard_fab2_lib.baseboard_fab2(sch_1):page124_i16:vss(161)" )
			)
			( pin "U7C1.AW9"
				( objectStatus "@baseboard_fab2_lib.baseboard_fab2(sch_1):page124_i16:vss(162)" )
			)
			( pin "U7C1.AV68"
				( objectStatus "@baseboard_fab2_lib.baseboard_fab2(sch_1):page124_i16:vss(163)" )
			)
			( pin "U7C1.AV59"
				( objectStatus "@baseboard_fab2_lib.baseboard_fab2(sch_1):page124_i16:vss(164)" )
			)
			( pin "U7C1.AV22"
				( objectStatus "@baseboard_fab2_lib.baseboard_fab2(sch_1):page124_i16:vss(165)" )
			)
			( pin "U7C1.AV5"
				( objectStatus "@baseboard_fab2_lib.baseboard_fab2(sch_1):page124_i16:vss(166)" )
			)
			( pin "U7C1.AU61"
				( objectStatus "@baseboard_fab2_lib.baseboard_fab2(sch_1):page124_i16:vss(167)" )
			)
			( pin "U7C1.AU54"
				( objectStatus "@baseboard_fab2_lib.baseboard_fab2(sch_1):page124_i16:vss(168)" )
			)
			( pin "U7C1.AU50"
				( objectStatus "@baseboard_fab2_lib.baseboard_fab2(sch_1):page124_i16:vss(169)" )
			)
			( pin "U7C1.AU46"
				( objectStatus "@baseboard_fab2_lib.baseboard_fab2(sch_1):page124_i16:vss(170)" )
			)
			( pin "U7C1.AU41"
				( objectStatus "@baseboard_fab2_lib.baseboard_fab2(sch_1):page124_i16:vss(171)" )
			)
			( pin "U7C1.AE22"
				( objectStatus "@baseboard_fab2_lib.baseboard_fab2(sch_1):page124_i16:vss(172)" )
			)
			( pin "U7C1.AU30"
				( objectStatus "@baseboard_fab2_lib.baseboard_fab2(sch_1):page124_i16:vss(173)" )
			)
			( pin "U7C1.AU26"
				( objectStatus "@baseboard_fab2_lib.baseboard_fab2(sch_1):page124_i16:vss(174)" )
			)
			( pin "U7C1.AT59"
				( objectStatus "@baseboard_fab2_lib.baseboard_fab2(sch_1):page124_i16:vss(175)" )
			)
			( pin "U7C1.AT46"
				( objectStatus "@baseboard_fab2_lib.baseboard_fab2(sch_1):page124_i16:vss(176)" )
			)
			( pin "U7C1.AT41"
				( objectStatus "@baseboard_fab2_lib.baseboard_fab2(sch_1):page124_i16:vss(177)" )
			)
			( pin "U7C1.AT30"
				( objectStatus "@baseboard_fab2_lib.baseboard_fab2(sch_1):page124_i16:vss(178)" )
			)
			( pin "U7C1.AT26"
				( objectStatus "@baseboard_fab2_lib.baseboard_fab2(sch_1):page124_i16:vss(179)" )
			)
			( pin "U7C1.AT22"
				( objectStatus "@baseboard_fab2_lib.baseboard_fab2(sch_1):page124_i16:vss(180)" )
			)
			( pin "U7C1.AT18"
				( objectStatus "@baseboard_fab2_lib.baseboard_fab2(sch_1):page124_i16:vss(181)" )
			)
			( pin "U7C1.AT15"
				( objectStatus "@baseboard_fab2_lib.baseboard_fab2(sch_1):page124_i16:vss(182)" )
			)
			( pin "U7C1.AT11"
				( objectStatus "@baseboard_fab2_lib.baseboard_fab2(sch_1):page124_i16:vss(183)" )
			)
			( pin "U7C1.AT7"
				( objectStatus "@baseboard_fab2_lib.baseboard_fab2(sch_1):page124_i16:vss(184)" )
			)
			( pin "U7C1.AR72"
				( objectStatus "@baseboard_fab2_lib.baseboard_fab2(sch_1):page124_i16:vss(185)" )
			)
			( pin "U7C1.AR70"
				( objectStatus "@baseboard_fab2_lib.baseboard_fab2(sch_1):page124_i16:vss(186)" )
			)
			( pin "U7C1.AR68"
				( objectStatus "@baseboard_fab2_lib.baseboard_fab2(sch_1):page124_i16:vss(187)" )
			)
			( pin "U7C1.AR65"
				( objectStatus "@baseboard_fab2_lib.baseboard_fab2(sch_1):page124_i16:vss(188)" )
			)
			( pin "U7C1.AR58"
				( objectStatus "@baseboard_fab2_lib.baseboard_fab2(sch_1):page124_i16:vss(189)" )
			)
			( pin "U7C1.AR50"
				( objectStatus "@baseboard_fab2_lib.baseboard_fab2(sch_1):page124_i16:vss(190)" )
			)
			( pin "U7C1.AR5"
				( objectStatus "@baseboard_fab2_lib.baseboard_fab2(sch_1):page124_i16:vss(191)" )
			)
			( pin "U7C1.AP66"
				( objectStatus "@baseboard_fab2_lib.baseboard_fab2(sch_1):page124_i16:vss(192)" )
			)
			( pin "U7C1.AP52"
				( objectStatus "@baseboard_fab2_lib.baseboard_fab2(sch_1):page124_i16:vss(193)" )
			)
			( pin "U7C1.AP46"
				( objectStatus "@baseboard_fab2_lib.baseboard_fab2(sch_1):page124_i16:vss(194)" )
			)
			( pin "U7C1.AP41"
				( objectStatus "@baseboard_fab2_lib.baseboard_fab2(sch_1):page124_i16:vss(195)" )
			)
			( pin "U7C1.AP4"
				( objectStatus "@baseboard_fab2_lib.baseboard_fab2(sch_1):page124_i16:vss(196)" )
			)
			( pin "U7C1.AP30"
				( objectStatus "@baseboard_fab2_lib.baseboard_fab2(sch_1):page124_i16:vss(197)" )
			)
			( pin "U7C1.AP26"
				( objectStatus "@baseboard_fab2_lib.baseboard_fab2(sch_1):page124_i16:vss(198)" )
			)
			( pin "U7C1.AP2"
				( objectStatus "@baseboard_fab2_lib.baseboard_fab2(sch_1):page124_i16:vss(199)" )
			)
			( pin "U7C1.AN9"
				( objectStatus "@baseboard_fab2_lib.baseboard_fab2(sch_1):page124_i16:vss(200)" )
			)
			( pin "U7C1.AN58"
				( objectStatus "@baseboard_fab2_lib.baseboard_fab2(sch_1):page124_i16:vss(201)" )
			)
			( pin "U7C1.AN5"
				( objectStatus "@baseboard_fab2_lib.baseboard_fab2(sch_1):page124_i16:vss(202)" )
			)
			( pin "U7C1.AN20"
				( objectStatus "@baseboard_fab2_lib.baseboard_fab2(sch_1):page124_i16:vss(203)" )
			)
			( pin "U7C1.AP22"
				( objectStatus "@baseboard_fab2_lib.baseboard_fab2(sch_1):page124_i16:vss(204)" )
			)
			( pin "U7C1.AN68"
				( objectStatus "@baseboard_fab2_lib.baseboard_fab2(sch_1):page124_i16:vss(205)" )
			)
			( pin "U7C1.AN17"
				( objectStatus "@baseboard_fab2_lib.baseboard_fab2(sch_1):page124_i16:vss(206)" )
			)
			( pin "U7C1.AN13"
				( objectStatus "@baseboard_fab2_lib.baseboard_fab2(sch_1):page124_i16:vss(207)" )
			)
			( pin "U7C1.AM46"
				( objectStatus "@baseboard_fab2_lib.baseboard_fab2(sch_1):page124_i16:vss(208)" )
			)
			( pin "U7C1.AM41"
				( objectStatus "@baseboard_fab2_lib.baseboard_fab2(sch_1):page124_i16:vss(209)" )
			)
			( pin "U7C1.AM30"
				( objectStatus "@baseboard_fab2_lib.baseboard_fab2(sch_1):page124_i16:vss(210)" )
			)
			( pin "U7C1.AM26"
				( objectStatus "@baseboard_fab2_lib.baseboard_fab2(sch_1):page124_i16:vss(211)" )
			)
			( pin "U7C1.AL72"
				( objectStatus "@baseboard_fab2_lib.baseboard_fab2(sch_1):page124_i16:vss(212)" )
			)
			( pin "U7C1.AL70"
				( objectStatus "@baseboard_fab2_lib.baseboard_fab2(sch_1):page124_i16:vss(213)" )
			)
			( pin "U7C1.AL68"
				( objectStatus "@baseboard_fab2_lib.baseboard_fab2(sch_1):page124_i16:vss(214)" )
			)
			( pin "U7C1.AL59"
				( objectStatus "@baseboard_fab2_lib.baseboard_fab2(sch_1):page124_i17:vss(215)" )
			)
			( pin "U7C1.AL52"
				( objectStatus "@baseboard_fab2_lib.baseboard_fab2(sch_1):page124_i17:vss(216)" )
			)
			( pin "U7C1.AL5"
				( objectStatus "@baseboard_fab2_lib.baseboard_fab2(sch_1):page124_i17:vss(217)" )
			)
			( pin "U7C1.AL22"
				( objectStatus "@baseboard_fab2_lib.baseboard_fab2(sch_1):page124_i17:vss(218)" )
			)
			( pin "U7C1.AK71"
				( objectStatus "@baseboard_fab2_lib.baseboard_fab2(sch_1):page124_i17:vss(219)" )
			)
			( pin "U7C1.AK69"
				( objectStatus "@baseboard_fab2_lib.baseboard_fab2(sch_1):page124_i17:vss(220)" )
			)
			( pin "U7C1.AK61"
				( objectStatus "@baseboard_fab2_lib.baseboard_fab2(sch_1):page124_i17:vss(221)" )
			)
			( pin "U7C1.AK58"
				( objectStatus "@baseboard_fab2_lib.baseboard_fab2(sch_1):page124_i17:vss(222)" )
			)
			( pin "U7C1.AK48"
				( objectStatus "@baseboard_fab2_lib.baseboard_fab2(sch_1):page124_i17:vss(223)" )
			)
			( pin "U7C1.AK46"
				( objectStatus "@baseboard_fab2_lib.baseboard_fab2(sch_1):page124_i17:vss(224)" )
			)
			( pin "U7C1.AK41"
				( objectStatus "@baseboard_fab2_lib.baseboard_fab2(sch_1):page124_i17:vss(225)" )
			)
			( pin "U7C1.AK26"
				( objectStatus "@baseboard_fab2_lib.baseboard_fab2(sch_1):page124_i17:vss(226)" )
			)
			( pin "U7C1.AJ7"
				( objectStatus "@baseboard_fab2_lib.baseboard_fab2(sch_1):page124_i17:vss(227)" )
			)
			( pin "U7C1.AJ68"
				( objectStatus "@baseboard_fab2_lib.baseboard_fab2(sch_1):page124_i17:vss(228)" )
			)
			( pin "U7C1.AJ66"
				( objectStatus "@baseboard_fab2_lib.baseboard_fab2(sch_1):page124_i17:vss(229)" )
			)
			( pin "U7C1.AJ59"
				( objectStatus "@baseboard_fab2_lib.baseboard_fab2(sch_1):page124_i17:vss(230)" )
			)
			( pin "U7C1.AJ52"
				( objectStatus "@baseboard_fab2_lib.baseboard_fab2(sch_1):page124_i17:vss(231)" )
			)
			( pin "U7C1.AJ5"
				( objectStatus "@baseboard_fab2_lib.baseboard_fab2(sch_1):page124_i17:vss(232)" )
			)
			( pin "U7C1.AJ41"
				( objectStatus "@baseboard_fab2_lib.baseboard_fab2(sch_1):page124_i17:vss(233)" )
			)
			( pin "U7C1.AJ39"
				( objectStatus "@baseboard_fab2_lib.baseboard_fab2(sch_1):page124_i17:vss(234)" )
			)
			( pin "U7C1.AJ37"
				( objectStatus "@baseboard_fab2_lib.baseboard_fab2(sch_1):page124_i17:vss(235)" )
			)
			( pin "U7C1.AJ36"
				( objectStatus "@baseboard_fab2_lib.baseboard_fab2(sch_1):page124_i17:vss(236)" )
			)
			( pin "U7C1.AJ34"
				( objectStatus "@baseboard_fab2_lib.baseboard_fab2(sch_1):page124_i17:vss(237)" )
			)
			( pin "U7C1.AJ30"
				( objectStatus "@baseboard_fab2_lib.baseboard_fab2(sch_1):page124_i17:vss(238)" )
			)
			( pin "U7C1.AJ26"
				( objectStatus "@baseboard_fab2_lib.baseboard_fab2(sch_1):page124_i17:vss(239)" )
			)
			( pin "U7C1.AJ22"
				( objectStatus "@baseboard_fab2_lib.baseboard_fab2(sch_1):page124_i17:vss(240)" )
			)
			( pin "U7C1.AJ18"
				( objectStatus "@baseboard_fab2_lib.baseboard_fab2(sch_1):page124_i17:vss(241)" )
			)
			( pin "U7C1.AJ15"
				( objectStatus "@baseboard_fab2_lib.baseboard_fab2(sch_1):page124_i17:vss(242)" )
			)
			( pin "U7C1.AK30"
				( objectStatus "@baseboard_fab2_lib.baseboard_fab2(sch_1):page124_i17:vss(243)" )
			)
			( pin "U7C1.AJ56"
				( objectStatus "@baseboard_fab2_lib.baseboard_fab2(sch_1):page124_i17:vss(244)" )
			)
			( pin "U7C1.AJ32"
				( objectStatus "@baseboard_fab2_lib.baseboard_fab2(sch_1):page124_i17:vss(245)" )
			)
			( pin "U7C1.AJ11"
				( objectStatus "@baseboard_fab2_lib.baseboard_fab2(sch_1):page124_i17:vss(246)" )
			)
			( pin "U7C1.AH20"
				( objectStatus "@baseboard_fab2_lib.baseboard_fab2(sch_1):page124_i17:vss(247)" )
			)
			( pin "U7C1.AG66"
				( objectStatus "@baseboard_fab2_lib.baseboard_fab2(sch_1):page124_i17:vss(248)" )
			)
			( pin "U7C1.AG59"
				( objectStatus "@baseboard_fab2_lib.baseboard_fab2(sch_1):page124_i17:vss(249)" )
			)
			( pin "U7C1.AG56"
				( objectStatus "@baseboard_fab2_lib.baseboard_fab2(sch_1):page124_i17:vss(250)" )
			)
			( pin "U7C1.AG52"
				( objectStatus "@baseboard_fab2_lib.baseboard_fab2(sch_1):page124_i17:vss(251)" )
			)
			( pin "U7C1.AG43"
				( objectStatus "@baseboard_fab2_lib.baseboard_fab2(sch_1):page124_i17:vss(252)" )
			)
			( pin "U7C1.AG41"
				( objectStatus "@baseboard_fab2_lib.baseboard_fab2(sch_1):page124_i17:vss(253)" )
			)
			( pin "U7C1.AG30"
				( objectStatus "@baseboard_fab2_lib.baseboard_fab2(sch_1):page124_i17:vss(254)" )
			)
			( pin "U7C1.AG26"
				( objectStatus "@baseboard_fab2_lib.baseboard_fab2(sch_1):page124_i17:vss(255)" )
			)
			( pin "U7C1.AF68"
				( objectStatus "@baseboard_fab2_lib.baseboard_fab2(sch_1):page124_i17:vss(256)" )
			)
			( pin "U7C1.AF3"
				( objectStatus "@baseboard_fab2_lib.baseboard_fab2(sch_1):page124_i17:vss(257)" )
			)
			( pin "U7C1.AF24"
				( objectStatus "@baseboard_fab2_lib.baseboard_fab2(sch_1):page124_i17:vss(258)" )
			)
			( pin "U7C1.AF17"
				( objectStatus "@baseboard_fab2_lib.baseboard_fab2(sch_1):page124_i17:vss(259)" )
			)
			( pin "U7C1.AF9"
				( objectStatus "@baseboard_fab2_lib.baseboard_fab2(sch_1):page124_i17:vss(260)" )
			)
			( pin "U7C1.AF5"
				( objectStatus "@baseboard_fab2_lib.baseboard_fab2(sch_1):page124_i17:vss(261)" )
			)
			( pin "U7C1.AF13"
				( objectStatus "@baseboard_fab2_lib.baseboard_fab2(sch_1):page124_i17:vss(262)" )
			)
			( pin "U7C1.AF1"
				( objectStatus "@baseboard_fab2_lib.baseboard_fab2(sch_1):page124_i17:vss(263)" )
			)
			( pin "U7C1.AE66"
				( objectStatus "@baseboard_fab2_lib.baseboard_fab2(sch_1):page124_i17:vss(264)" )
			)
			( pin "U7C1.AE63"
				( objectStatus "@baseboard_fab2_lib.baseboard_fab2(sch_1):page124_i17:vss(265)" )
			)
			( pin "U7C1.AE59"
				( objectStatus "@baseboard_fab2_lib.baseboard_fab2(sch_1):page124_i17:vss(266)" )
			)
			( pin "U7C1.AE56"
				( objectStatus "@baseboard_fab2_lib.baseboard_fab2(sch_1):page124_i17:vss(267)" )
			)
			( pin "U7C1.AE52"
				( objectStatus "@baseboard_fab2_lib.baseboard_fab2(sch_1):page124_i17:vss(268)" )
			)
			( pin "U7C1.AE48"
				( objectStatus "@baseboard_fab2_lib.baseboard_fab2(sch_1):page124_i17:vss(269)" )
			)
			( pin "U7C1.J18"
				( objectStatus "@baseboard_fab2_lib.baseboard_fab2(sch_1):page124_i17:vss(270)" )
			)
			( pin "U7C1.AE29"
				( objectStatus "@baseboard_fab2_lib.baseboard_fab2(sch_1):page124_i17:vss(271)" )
			)
			( pin "U7C1.AD68"
				( objectStatus "@baseboard_fab2_lib.baseboard_fab2(sch_1):page124_i17:vss(272)" )
			)
			( pin "U7C1.AD65"
				( objectStatus "@baseboard_fab2_lib.baseboard_fab2(sch_1):page124_i17:vss(273)" )
			)
			( pin "U7C1.AD5"
				( objectStatus "@baseboard_fab2_lib.baseboard_fab2(sch_1):page124_i17:vss(274)" )
			)
			( pin "U7C1.AC7"
				( objectStatus "@baseboard_fab2_lib.baseboard_fab2(sch_1):page124_i17:vss(275)" )
			)
			( pin "U7C1.AC66"
				( objectStatus "@baseboard_fab2_lib.baseboard_fab2(sch_1):page124_i17:vss(276)" )
			)
			( pin "U7C1.AC63"
				( objectStatus "@baseboard_fab2_lib.baseboard_fab2(sch_1):page124_i17:vss(277)" )
			)
			( pin "U7C1.AC59"
				( objectStatus "@baseboard_fab2_lib.baseboard_fab2(sch_1):page124_i17:vss(278)" )
			)
			( pin "U7C1.AC52"
				( objectStatus "@baseboard_fab2_lib.baseboard_fab2(sch_1):page124_i17:vss(279)" )
			)
			( pin "U7C1.AC48"
				( objectStatus "@baseboard_fab2_lib.baseboard_fab2(sch_1):page124_i17:vss(280)" )
			)
			( pin "U7C1.AC46"
				( objectStatus "@baseboard_fab2_lib.baseboard_fab2(sch_1):page124_i17:vss(281)" )
			)
			( pin "U7C1.AC43"
				( objectStatus "@baseboard_fab2_lib.baseboard_fab2(sch_1):page124_i17:vss(282)" )
			)
			( pin "U7C1.AC27"
				( objectStatus "@baseboard_fab2_lib.baseboard_fab2(sch_1):page124_i17:vss(283)" )
			)
			( pin "U7C1.AD58"
				( objectStatus "@baseboard_fab2_lib.baseboard_fab2(sch_1):page124_i17:vss(284)" )
			)
			( pin "U7C1.AC45"
				( objectStatus "@baseboard_fab2_lib.baseboard_fab2(sch_1):page124_i17:vss(285)" )
			)
			( pin "U7C1.AC22"
				( objectStatus "@baseboard_fab2_lib.baseboard_fab2(sch_1):page124_i17:vss(286)" )
			)
			( pin "U7C1.AC18"
				( objectStatus "@baseboard_fab2_lib.baseboard_fab2(sch_1):page124_i17:vss(287)" )
			)
			( pin "U7C1.AC15"
				( objectStatus "@baseboard_fab2_lib.baseboard_fab2(sch_1):page124_i17:vss(288)" )
			)
			( pin "U7C1.AC11"
				( objectStatus "@baseboard_fab2_lib.baseboard_fab2(sch_1):page124_i17:vss(289)" )
			)
			( pin "U7C1.AB72"
				( objectStatus "@baseboard_fab2_lib.baseboard_fab2(sch_1):page124_i17:vss(290)" )
			)
			( pin "U7C1.AB70"
				( objectStatus "@baseboard_fab2_lib.baseboard_fab2(sch_1):page124_i17:vss(291)" )
			)
			( pin "U7C1.AB68"
				( objectStatus "@baseboard_fab2_lib.baseboard_fab2(sch_1):page124_i17:vss(292)" )
			)
			( pin "U7C1.AB5"
				( objectStatus "@baseboard_fab2_lib.baseboard_fab2(sch_1):page124_i17:vss(293)" )
			)
			( pin "U7C1.AA48"
				( objectStatus "@baseboard_fab2_lib.baseboard_fab2(sch_1):page124_i17:vss(294)" )
			)
			( pin "U7C1.AA43"
				( objectStatus "@baseboard_fab2_lib.baseboard_fab2(sch_1):page124_i17:vss(295)" )
			)
			( pin "U7C1.AA27"
				( objectStatus "@baseboard_fab2_lib.baseboard_fab2(sch_1):page124_i17:vss(296)" )
			)
			( pin "U7C1.AA26"
				( objectStatus "@baseboard_fab2_lib.baseboard_fab2(sch_1):page124_i17:vss(297)" )
			)
			( pin "U7C1.Y68"
				( objectStatus "@baseboard_fab2_lib.baseboard_fab2(sch_1):page124_i17:vss(298)" )
			)
			( pin "U7C1.Y63"
				( objectStatus "@baseboard_fab2_lib.baseboard_fab2(sch_1):page124_i17:vss(299)" )
			)
			( pin "U7C1.Y59"
				( objectStatus "@baseboard_fab2_lib.baseboard_fab2(sch_1):page124_i17:vss(300)" )
			)
			( pin "U7C1.Y52"
				( objectStatus "@baseboard_fab2_lib.baseboard_fab2(sch_1):page124_i17:vss(301)" )
			)
			( pin "U7C1.Y5"
				( objectStatus "@baseboard_fab2_lib.baseboard_fab2(sch_1):page124_i17:vss(302)" )
			)
			( pin "U7C1.Y48"
				( objectStatus "@baseboard_fab2_lib.baseboard_fab2(sch_1):page124_i17:vss(303)" )
			)
			( pin "U7C1.Y27"
				( objectStatus "@baseboard_fab2_lib.baseboard_fab2(sch_1):page124_i17:vss(304)" )
			)
			( pin "U7C1.Y22"
				( objectStatus "@baseboard_fab2_lib.baseboard_fab2(sch_1):page124_i17:vss(305)" )
			)
			( pin "U7C1.W9"
				( objectStatus "@baseboard_fab2_lib.baseboard_fab2(sch_1):page124_i17:vss(306)" )
			)
			( pin "U7C1.W61"
				( objectStatus "@baseboard_fab2_lib.baseboard_fab2(sch_1):page124_i17:vss(307)" )
			)
			( pin "U7C1.Y43"
				( objectStatus "@baseboard_fab2_lib.baseboard_fab2(sch_1):page124_i17:vss(308)" )
			)
			( pin "U7C1.AA50"
				( objectStatus "@baseboard_fab2_lib.baseboard_fab2(sch_1):page124_i17:vss(309)" )
			)
			( pin "U7C1.W24"
				( objectStatus "@baseboard_fab2_lib.baseboard_fab2(sch_1):page124_i17:vss(310)" )
			)
			( pin "U7C1.W20"
				( objectStatus "@baseboard_fab2_lib.baseboard_fab2(sch_1):page124_i17:vss(311)" )
			)
			( pin "U7C1.W17"
				( objectStatus "@baseboard_fab2_lib.baseboard_fab2(sch_1):page124_i17:vss(312)" )
			)
			( pin "U7C1.W13"
				( objectStatus "@baseboard_fab2_lib.baseboard_fab2(sch_1):page124_i17:vss(313)" )
			)
			( pin "U7C1.V68"
				( objectStatus "@baseboard_fab2_lib.baseboard_fab2(sch_1):page124_i17:vss(314)" )
			)
			( pin "U7C1.V66"
				( objectStatus "@baseboard_fab2_lib.baseboard_fab2(sch_1):page124_i17:vss(315)" )
			)
			( pin "U7C1.W58"
				( objectStatus "@baseboard_fab2_lib.baseboard_fab2(sch_1):page124_i17:vss(316)" )
			)
			( pin "U7C1.V52"
				( objectStatus "@baseboard_fab2_lib.baseboard_fab2(sch_1):page124_i17:vss(317)" )
			)
			( pin "U7C1.V5"
				( objectStatus "@baseboard_fab2_lib.baseboard_fab2(sch_1):page124_i17:vss(318)" )
			)
			( pin "U7C1.V48"
				( objectStatus "@baseboard_fab2_lib.baseboard_fab2(sch_1):page124_i17:vss(319)" )
			)
			( pin "U7C1.V26"
				( objectStatus "@baseboard_fab2_lib.baseboard_fab2(sch_1):page124_i17:vss(320)" )
			)
			( pin "U7C1.U58"
				( objectStatus "@baseboard_fab2_lib.baseboard_fab2(sch_1):page124_i17:vss(321)" )
			)
			( pin "U7C1.AG46"
				( objectStatus "@baseboard_fab2_lib.baseboard_fab2(sch_1):page124_i17:vss(322)" )
			)
			( pin "U7C1.AF50"
				( objectStatus "@baseboard_fab2_lib.baseboard_fab2(sch_1):page124_i17:vss(323)" )
			)
			( pin "U7C1.T7"
				( objectStatus "@baseboard_fab2_lib.baseboard_fab2(sch_1):page124_i17:vss(324)" )
			)
			( pin "U7C1.T66"
				( objectStatus "@baseboard_fab2_lib.baseboard_fab2(sch_1):page124_i17:vss(325)" )
			)
			( pin "U7C1.T52"
				( objectStatus "@baseboard_fab2_lib.baseboard_fab2(sch_1):page124_i17:vss(326)" )
			)
			( pin "U7C1.T48"
				( objectStatus "@baseboard_fab2_lib.baseboard_fab2(sch_1):page124_i17:vss(327)" )
			)
			( pin "U7C1.AJ45"
				( objectStatus "@baseboard_fab2_lib.baseboard_fab2(sch_1):page124_i17:vss(328)" )
			)
			( pin "U7C1.T40"
				( objectStatus "@baseboard_fab2_lib.baseboard_fab2(sch_1):page124_i17:vss(329)" )
			)
			( pin "U7C1.T37"
				( objectStatus "@baseboard_fab2_lib.baseboard_fab2(sch_1):page124_i17:vss(330)" )
			)
			( pin "U7C1.T33"
				( objectStatus "@baseboard_fab2_lib.baseboard_fab2(sch_1):page124_i17:vss(331)" )
			)
			( pin "U7C1.T29"
				( objectStatus "@baseboard_fab2_lib.baseboard_fab2(sch_1):page124_i17:vss(332)" )
			)
			( pin "U7C1.T26"
				( objectStatus "@baseboard_fab2_lib.baseboard_fab2(sch_1):page124_i17:vss(333)" )
			)
			( pin "U7C1.T22"
				( objectStatus "@baseboard_fab2_lib.baseboard_fab2(sch_1):page124_i17:vss(334)" )
			)
			( pin "U7C1.T18"
				( objectStatus "@baseboard_fab2_lib.baseboard_fab2(sch_1):page124_i17:vss(335)" )
			)
			( pin "U7C1.T15"
				( objectStatus "@baseboard_fab2_lib.baseboard_fab2(sch_1):page124_i17:vss(336)" )
			)
			( pin "U7C1.T11"
				( objectStatus "@baseboard_fab2_lib.baseboard_fab2(sch_1):page124_i17:vss(337)" )
			)
			( pin "U7C1.R68"
				( objectStatus "@baseboard_fab2_lib.baseboard_fab2(sch_1):page124_i17:vss(338)" )
			)
			( pin "U7C1.R58"
				( objectStatus "@baseboard_fab2_lib.baseboard_fab2(sch_1):page124_i17:vss(339)" )
			)
			( pin "U7C1.T56"
				( objectStatus "@baseboard_fab2_lib.baseboard_fab2(sch_1):page124_i17:vss(340)" )
			)
			( pin "U7C1.R54"
				( objectStatus "@baseboard_fab2_lib.baseboard_fab2(sch_1):page124_i17:vss(341)" )
			)
			( pin "U7C1.R50"
				( objectStatus "@baseboard_fab2_lib.baseboard_fab2(sch_1):page124_i17:vss(342)" )
			)
			( pin "U7C1.R5"
				( objectStatus "@baseboard_fab2_lib.baseboard_fab2(sch_1):page124_i17:vss(343)" )
			)
			( pin "U7C1.U42"
				( objectStatus "@baseboard_fab2_lib.baseboard_fab2(sch_1):page124_i17:vss(344)" )
			)
			( pin "U7C1.R27"
				( objectStatus "@baseboard_fab2_lib.baseboard_fab2(sch_1):page124_i17:vss(345)" )
			)
			( pin "U7C1.P63"
				( objectStatus "@baseboard_fab2_lib.baseboard_fab2(sch_1):page124_i17:vss(346)" )
			)
			( pin "U7C1.AE43"
				( objectStatus "@baseboard_fab2_lib.baseboard_fab2(sch_1):page124_i17:vss(347)" )
			)
			( pin "U7C1.N9"
				( objectStatus "@baseboard_fab2_lib.baseboard_fab2(sch_1):page124_i17:vss(348)" )
			)
			( pin "U7C1.N68"
				( objectStatus "@baseboard_fab2_lib.baseboard_fab2(sch_1):page124_i17:vss(349)" )
			)
			( pin "U7C1.R38"
				( objectStatus "@baseboard_fab2_lib.baseboard_fab2(sch_1):page124_i17:vss(350)" )
			)
			( pin "U7C1.N5"
				( objectStatus "@baseboard_fab2_lib.baseboard_fab2(sch_1):page124_i17:vss(351)" )
			)
			( pin "U7C1.N46"
				( objectStatus "@baseboard_fab2_lib.baseboard_fab2(sch_1):page124_i17:vss(352)" )
			)
			( pin "U7C1.N38"
				( objectStatus "@baseboard_fab2_lib.baseboard_fab2(sch_1):page124_i17:vss(353)" )
			)
			( pin "U7C1.N35"
				( objectStatus "@baseboard_fab2_lib.baseboard_fab2(sch_1):page124_i17:vss(354)" )
			)
			( pin "R2R11.1"
				( objectStatus "@baseboard_fab2_lib.baseboard_fab2(sch_1):page125_i11:a" )
			)
			( pin "R2R11.2"
				( objectStatus "@baseboard_fab2_lib.baseboard_fab2(sch_1):page125_i11:b" )
			)
			( pin "R2T1.1"
				( objectStatus "@baseboard_fab2_lib.baseboard_fab2(sch_1):page125_i15:a" )
			)
			( pin "R2T1.2"
				( objectStatus "@baseboard_fab2_lib.baseboard_fab2(sch_1):page125_i15:b" )
			)
			( pin "R8E6.1"
				( objectStatus "@baseboard_fab2_lib.baseboard_fab2(sch_1):page125_i21:a" )
			)
			( pin "R8E6.2"
				( objectStatus "@baseboard_fab2_lib.baseboard_fab2(sch_1):page125_i21:b" )
			)
			( pin "R8E4.1"
				( objectStatus "@baseboard_fab2_lib.baseboard_fab2(sch_1):page125_i24:a" )
			)
			( pin "R8E4.2"
				( objectStatus "@baseboard_fab2_lib.baseboard_fab2(sch_1):page125_i24:b" )
			)
			( pin "R8C18.1"
				( objectStatus "@baseboard_fab2_lib.baseboard_fab2(sch_1):page125_i40:a" )
			)
			( pin "R8C18.2"
				( objectStatus "@baseboard_fab2_lib.baseboard_fab2(sch_1):page125_i40:b" )
			)
			( pin "R8C17.1"
				( objectStatus "@baseboard_fab2_lib.baseboard_fab2(sch_1):page125_i41:a" )
			)
			( pin "R8C17.2"
				( objectStatus "@baseboard_fab2_lib.baseboard_fab2(sch_1):page125_i41:b" )
			)
			( pin "R8D5.1"
				( objectStatus "@baseboard_fab2_lib.baseboard_fab2(sch_1):page125_i50:a" )
			)
			( pin "R8D5.2"
				( objectStatus "@baseboard_fab2_lib.baseboard_fab2(sch_1):page125_i50:b" )
			)
			( pin "R8D13.1"
				( objectStatus "@baseboard_fab2_lib.baseboard_fab2(sch_1):page125_i52:a" )
			)
			( pin "R8D13.2"
				( objectStatus "@baseboard_fab2_lib.baseboard_fab2(sch_1):page125_i52:b" )
			)
			( pin "R7D13.1"
				( objectStatus "@baseboard_fab2_lib.baseboard_fab2(sch_1):page125_i60:a" )
			)
			( pin "R7D13.2"
				( objectStatus "@baseboard_fab2_lib.baseboard_fab2(sch_1):page125_i60:b" )
			)
			( pin "R7D1.1"
				( objectStatus "@baseboard_fab2_lib.baseboard_fab2(sch_1):page125_i70:a" )
			)
			( pin "R7D1.2"
				( objectStatus "@baseboard_fab2_lib.baseboard_fab2(sch_1):page125_i70:b" )
			)
			( pin "R8D16.1"
				( objectStatus "@baseboard_fab2_lib.baseboard_fab2(sch_1):page125_i71:a" )
			)
			( pin "R8D16.2"
				( objectStatus "@baseboard_fab2_lib.baseboard_fab2(sch_1):page125_i71:b" )
			)
			( pin "R3N2.1"
				( objectStatus "@baseboard_fab2_lib.baseboard_fab2(sch_1):page125_i72:a" )
			)
			( pin "R3N2.2"
				( objectStatus "@baseboard_fab2_lib.baseboard_fab2(sch_1):page125_i72:b" )
			)
			( pin "R2U30.1"
				( objectStatus "@baseboard_fab2_lib.baseboard_fab2(sch_1):page125_i76:a" )
			)
			( pin "R2U30.2"
				( objectStatus "@baseboard_fab2_lib.baseboard_fab2(sch_1):page125_i76:b" )
			)
			( pin "R3N17.1"
				( objectStatus "@baseboard_fab2_lib.baseboard_fab2(sch_1):page125_i78:a" )
			)
			( pin "R3N17.2"
				( objectStatus "@baseboard_fab2_lib.baseboard_fab2(sch_1):page125_i78:b" )
			)
			( pin "R2N14.1"
				( objectStatus "@baseboard_fab2_lib.baseboard_fab2(sch_1):page125_i83:a" )
			)
			( pin "R2N14.2"
				( objectStatus "@baseboard_fab2_lib.baseboard_fab2(sch_1):page125_i83:b" )
			)
			( pin "R7D19.1"
				( objectStatus "@baseboard_fab2_lib.baseboard_fab2(sch_1):page126_i6:a" )
			)
			( pin "R7D19.2"
				( objectStatus "@baseboard_fab2_lib.baseboard_fab2(sch_1):page126_i6:b" )
			)
			( pin "R2N10.1"
				( objectStatus "@baseboard_fab2_lib.baseboard_fab2(sch_1):page126_i10:a" )
			)
			( pin "R2N10.2"
				( objectStatus "@baseboard_fab2_lib.baseboard_fab2(sch_1):page126_i10:b" )
			)
			( pin "R1D35.1"
				( objectStatus "@baseboard_fab2_lib.baseboard_fab2(sch_1):page126_i12:a" )
			)
			( pin "R1D35.2"
				( objectStatus "@baseboard_fab2_lib.baseboard_fab2(sch_1):page126_i12:b" )
			)
			( pin "Q8E2.3"
				( objectStatus "@baseboard_fab2_lib.baseboard_fab2(sch_1):page126_i13:drn" )
			)
			( pin "Q8E2.1"
				( objectStatus "@baseboard_fab2_lib.baseboard_fab2(sch_1):page126_i13:gate" )
			)
			( pin "Q8E2.2"
				( objectStatus "@baseboard_fab2_lib.baseboard_fab2(sch_1):page126_i13:src" )
			)
			( pin "R8C9.1"
				( objectStatus "@baseboard_fab2_lib.baseboard_fab2(sch_1):page126_i20:a" )
			)
			( pin "R8C9.2"
				( objectStatus "@baseboard_fab2_lib.baseboard_fab2(sch_1):page126_i20:b" )
			)
			( pin "R3P62.1"
				( objectStatus "@baseboard_fab2_lib.baseboard_fab2(sch_1):page126_i22:a" )
			)
			( pin "R3P62.2"
				( objectStatus "@baseboard_fab2_lib.baseboard_fab2(sch_1):page126_i22:b" )
			)
			( pin "R3P64.1"
				( objectStatus "@baseboard_fab2_lib.baseboard_fab2(sch_1):page126_i23:a" )
			)
			( pin "R3P64.2"
				( objectStatus "@baseboard_fab2_lib.baseboard_fab2(sch_1):page126_i23:b" )
			)
			( pin "FB3M1.1"
				( objectStatus "@baseboard_fab2_lib.baseboard_fab2(sch_1):page127_i8:a" )
			)
			( pin "FB3M1.2"
				( objectStatus "@baseboard_fab2_lib.baseboard_fab2(sch_1):page127_i8:b" )
			)
			( pin "C3M21.1"
				( objectStatus "@baseboard_fab2_lib.baseboard_fab2(sch_1):page127_i9:a" )
			)
			( pin "C3M21.2"
				( objectStatus "@baseboard_fab2_lib.baseboard_fab2(sch_1):page127_i9:b" )
			)
			( pin "FB3M2.1"
				( objectStatus "@baseboard_fab2_lib.baseboard_fab2(sch_1):page127_i17:a" )
			)
			( pin "FB3M2.2"
				( objectStatus "@baseboard_fab2_lib.baseboard_fab2(sch_1):page127_i17:b" )
			)
			( pin "C3M22.1"
				( objectStatus "@baseboard_fab2_lib.baseboard_fab2(sch_1):page127_i18:a" )
			)
			( pin "C3M22.2"
				( objectStatus "@baseboard_fab2_lib.baseboard_fab2(sch_1):page127_i18:b" )
			)
			( pin "FB3M3.1"
				( objectStatus "@baseboard_fab2_lib.baseboard_fab2(sch_1):page127_i26:a" )
			)
			( pin "FB3M3.2"
				( objectStatus "@baseboard_fab2_lib.baseboard_fab2(sch_1):page127_i26:b" )
			)
			( pin "C3M30.1"
				( objectStatus "@baseboard_fab2_lib.baseboard_fab2(sch_1):page127_i27:a" )
			)
			( pin "C3M30.2"
				( objectStatus "@baseboard_fab2_lib.baseboard_fab2(sch_1):page127_i27:b" )
			)
			( pin "C2M5.1"
				( objectStatus "@baseboard_fab2_lib.baseboard_fab2(sch_1):page127_i43:a" )
			)
			( pin "C2M5.2"
				( objectStatus "@baseboard_fab2_lib.baseboard_fab2(sch_1):page127_i43:b" )
			)
			( pin "C2M7.1"
				( objectStatus "@baseboard_fab2_lib.baseboard_fab2(sch_1):page127_i44:a" )
			)
			( pin "C2M7.2"
				( objectStatus "@baseboard_fab2_lib.baseboard_fab2(sch_1):page127_i44:b" )
			)
			( pin "FB2M1.1"
				( objectStatus "@baseboard_fab2_lib.baseboard_fab2(sch_1):page127_i46:a" )
			)
			( pin "FB2M1.2"
				( objectStatus "@baseboard_fab2_lib.baseboard_fab2(sch_1):page127_i46:b" )
			)
			( pin "C2M10.1"
				( objectStatus "@baseboard_fab2_lib.baseboard_fab2(sch_1):page127_i49:a" )
			)
			( pin "C2M10.2"
				( objectStatus "@baseboard_fab2_lib.baseboard_fab2(sch_1):page127_i49:b" )
			)
			( pin "C2M9.1"
				( objectStatus "@baseboard_fab2_lib.baseboard_fab2(sch_1):page127_i50:a" )
			)
			( pin "C2M9.2"
				( objectStatus "@baseboard_fab2_lib.baseboard_fab2(sch_1):page127_i50:b" )
			)
			( pin "FB3M4.1"
				( objectStatus "@baseboard_fab2_lib.baseboard_fab2(sch_1):page127_i56:a" )
			)
			( pin "FB3M4.2"
				( objectStatus "@baseboard_fab2_lib.baseboard_fab2(sch_1):page127_i56:b" )
			)
			( pin "C3M31.1"
				( objectStatus "@baseboard_fab2_lib.baseboard_fab2(sch_1):page127_i57:a" )
			)
			( pin "C3M31.2"
				( objectStatus "@baseboard_fab2_lib.baseboard_fab2(sch_1):page127_i57:b" )
			)
			( pin "C2N6.1"
				( objectStatus "@baseboard_fab2_lib.baseboard_fab2(sch_1):page127_i64:a" )
			)
			( pin "C2N6.2"
				( objectStatus "@baseboard_fab2_lib.baseboard_fab2(sch_1):page127_i64:b" )
			)
			( pin "C2N5.1"
				( objectStatus "@baseboard_fab2_lib.baseboard_fab2(sch_1):page127_i65:a" )
			)
			( pin "C2N5.2"
				( objectStatus "@baseboard_fab2_lib.baseboard_fab2(sch_1):page127_i65:b" )
			)
			( pin "FB2M2.1"
				( objectStatus "@baseboard_fab2_lib.baseboard_fab2(sch_1):page127_i69:a" )
			)
			( pin "FB2M2.2"
				( objectStatus "@baseboard_fab2_lib.baseboard_fab2(sch_1):page127_i69:b" )
			)
			( pin "L2M1.1"
				( objectStatus "@baseboard_fab2_lib.baseboard_fab2(sch_1):page127_i71:ina" )
			)
			( pin "L2M1.2"
				( objectStatus "@baseboard_fab2_lib.baseboard_fab2(sch_1):page127_i71:inb" )
			)
			( pin "C2M8.1"
				( objectStatus "@baseboard_fab2_lib.baseboard_fab2(sch_1):page127_i74:a" )
			)
			( pin "C2M8.2"
				( objectStatus "@baseboard_fab2_lib.baseboard_fab2(sch_1):page127_i74:b" )
			)
			( pin "C2M6.1"
				( objectStatus "@baseboard_fab2_lib.baseboard_fab2(sch_1):page127_i76:a" )
			)
			( pin "C2M6.2"
				( objectStatus "@baseboard_fab2_lib.baseboard_fab2(sch_1):page127_i76:b" )
			)
			( pin "C2M25.1"
				( objectStatus "@baseboard_fab2_lib.baseboard_fab2(sch_1):page127_i78:a" )
			)
			( pin "C2M25.2"
				( objectStatus "@baseboard_fab2_lib.baseboard_fab2(sch_1):page127_i78:b" )
			)
			( pin "C3M29.1"
				( objectStatus "@baseboard_fab2_lib.baseboard_fab2(sch_1):page127_i80:a" )
			)
			( pin "C3M29.2"
				( objectStatus "@baseboard_fab2_lib.baseboard_fab2(sch_1):page127_i80:b" )
			)
			( pin "C3M24.1"
				( objectStatus "@baseboard_fab2_lib.baseboard_fab2(sch_1):page127_i81:a" )
			)
			( pin "C3M24.2"
				( objectStatus "@baseboard_fab2_lib.baseboard_fab2(sch_1):page127_i81:b" )
			)
			( pin "C3M23.1"
				( objectStatus "@baseboard_fab2_lib.baseboard_fab2(sch_1):page127_i82:a" )
			)
			( pin "C3M23.2"
				( objectStatus "@baseboard_fab2_lib.baseboard_fab2(sch_1):page127_i82:b" )
			)
			( pin "C3M27.1"
				( objectStatus "@baseboard_fab2_lib.baseboard_fab2(sch_1):page127_i83:a" )
			)
			( pin "C3M27.2"
				( objectStatus "@baseboard_fab2_lib.baseboard_fab2(sch_1):page127_i83:b" )
			)
			( pin "C3M20.1"
				( objectStatus "@baseboard_fab2_lib.baseboard_fab2(sch_1):page127_i84:a" )
			)
			( pin "C3M20.2"
				( objectStatus "@baseboard_fab2_lib.baseboard_fab2(sch_1):page127_i84:b" )
			)
			( pin "C3M18.1"
				( objectStatus "@baseboard_fab2_lib.baseboard_fab2(sch_1):page127_i85:a" )
			)
			( pin "C3M18.2"
				( objectStatus "@baseboard_fab2_lib.baseboard_fab2(sch_1):page127_i85:b" )
			)
			( pin "C3M17.1"
				( objectStatus "@baseboard_fab2_lib.baseboard_fab2(sch_1):page127_i86:a" )
			)
			( pin "C3M17.2"
				( objectStatus "@baseboard_fab2_lib.baseboard_fab2(sch_1):page127_i86:b" )
			)
			( pin "C3M19.1"
				( objectStatus "@baseboard_fab2_lib.baseboard_fab2(sch_1):page127_i87:a" )
			)
			( pin "C3M19.2"
				( objectStatus "@baseboard_fab2_lib.baseboard_fab2(sch_1):page127_i87:b" )
			)
			( pin "C7B25.1"
				( objectStatus "@baseboard_fab2_lib.baseboard_fab2(sch_1):page129_i35:a" )
			)
			( pin "C7B25.2"
				( objectStatus "@baseboard_fab2_lib.baseboard_fab2(sch_1):page129_i35:b" )
			)
			( pin "C7B27.1"
				( objectStatus "@baseboard_fab2_lib.baseboard_fab2(sch_1):page129_i69:a" )
			)
			( pin "C7B27.2"
				( objectStatus "@baseboard_fab2_lib.baseboard_fab2(sch_1):page129_i69:b" )
			)
			( pin "C7B28.1"
				( objectStatus "@baseboard_fab2_lib.baseboard_fab2(sch_1):page129_i70:a" )
			)
			( pin "C7B28.2"
				( objectStatus "@baseboard_fab2_lib.baseboard_fab2(sch_1):page129_i70:b" )
			)
			( pin "C7C2.1"
				( objectStatus "@baseboard_fab2_lib.baseboard_fab2(sch_1):page129_i71:a" )
			)
			( pin "C7C2.2"
				( objectStatus "@baseboard_fab2_lib.baseboard_fab2(sch_1):page129_i71:b" )
			)
			( pin "C3M40.1"
				( objectStatus "@baseboard_fab2_lib.baseboard_fab2(sch_1):page129_i72:a" )
			)
			( pin "C3M40.2"
				( objectStatus "@baseboard_fab2_lib.baseboard_fab2(sch_1):page129_i72:b" )
			)
			( pin "C3M37.1"
				( objectStatus "@baseboard_fab2_lib.baseboard_fab2(sch_1):page129_i73:a" )
			)
			( pin "C3M37.2"
				( objectStatus "@baseboard_fab2_lib.baseboard_fab2(sch_1):page129_i73:b" )
			)
			( pin "C3N9.1"
				( objectStatus "@baseboard_fab2_lib.baseboard_fab2(sch_1):page129_i74:a" )
			)
			( pin "C3N9.2"
				( objectStatus "@baseboard_fab2_lib.baseboard_fab2(sch_1):page129_i74:b" )
			)
			( pin "C3N8.1"
				( objectStatus "@baseboard_fab2_lib.baseboard_fab2(sch_1):page129_i75:a" )
			)
			( pin "C3N8.2"
				( objectStatus "@baseboard_fab2_lib.baseboard_fab2(sch_1):page129_i75:b" )
			)
			( pin "C7C3.1"
				( objectStatus "@baseboard_fab2_lib.baseboard_fab2(sch_1):page129_i76:a" )
			)
			( pin "C7C3.2"
				( objectStatus "@baseboard_fab2_lib.baseboard_fab2(sch_1):page129_i76:b" )
			)
			( pin "C7C1.1"
				( objectStatus "@baseboard_fab2_lib.baseboard_fab2(sch_1):page129_i77:a" )
			)
			( pin "C7C1.2"
				( objectStatus "@baseboard_fab2_lib.baseboard_fab2(sch_1):page129_i77:b" )
			)
			( pin "C7B29.1"
				( objectStatus "@baseboard_fab2_lib.baseboard_fab2(sch_1):page129_i78:a" )
			)
			( pin "C7B29.2"
				( objectStatus "@baseboard_fab2_lib.baseboard_fab2(sch_1):page129_i78:b" )
			)
			( pin "C7B26.1"
				( objectStatus "@baseboard_fab2_lib.baseboard_fab2(sch_1):page129_i79:a" )
			)
			( pin "C7B26.2"
				( objectStatus "@baseboard_fab2_lib.baseboard_fab2(sch_1):page129_i79:b" )
			)
			( pin "C3M44.1"
				( objectStatus "@baseboard_fab2_lib.baseboard_fab2(sch_1):page129_i80:a" )
			)
			( pin "C3M44.2"
				( objectStatus "@baseboard_fab2_lib.baseboard_fab2(sch_1):page129_i80:b" )
			)
			( pin "C3M41.1"
				( objectStatus "@baseboard_fab2_lib.baseboard_fab2(sch_1):page129_i81:a" )
			)
			( pin "C3M41.2"
				( objectStatus "@baseboard_fab2_lib.baseboard_fab2(sch_1):page129_i81:b" )
			)
			( pin "C3M45.1"
				( objectStatus "@baseboard_fab2_lib.baseboard_fab2(sch_1):page129_i82:a" )
			)
			( pin "C3M45.2"
				( objectStatus "@baseboard_fab2_lib.baseboard_fab2(sch_1):page129_i82:b" )
			)
			( pin "C3N13.1"
				( objectStatus "@baseboard_fab2_lib.baseboard_fab2(sch_1):page129_i83:a" )
			)
			( pin "C3N13.2"
				( objectStatus "@baseboard_fab2_lib.baseboard_fab2(sch_1):page129_i83:b" )
			)
			( pin "C7D2.1"
				( objectStatus "@baseboard_fab2_lib.baseboard_fab2(sch_1):page130_i2:a" )
			)
			( pin "C7D2.2"
				( objectStatus "@baseboard_fab2_lib.baseboard_fab2(sch_1):page130_i2:b" )
			)
			( pin "C2N26.1"
				( objectStatus "@baseboard_fab2_lib.baseboard_fab2(sch_1):page130_i4:a" )
			)
			( pin "C2N26.2"
				( objectStatus "@baseboard_fab2_lib.baseboard_fab2(sch_1):page130_i4:b" )
			)
			( pin "C2N19.1"
				( objectStatus "@baseboard_fab2_lib.baseboard_fab2(sch_1):page130_i7:a" )
			)
			( pin "C2N19.2"
				( objectStatus "@baseboard_fab2_lib.baseboard_fab2(sch_1):page130_i7:b" )
			)
			( pin "C2N24.1"
				( objectStatus "@baseboard_fab2_lib.baseboard_fab2(sch_1):page130_i8:a" )
			)
			( pin "C2N24.2"
				( objectStatus "@baseboard_fab2_lib.baseboard_fab2(sch_1):page130_i8:b" )
			)
			( pin "C2N22.1"
				( objectStatus "@baseboard_fab2_lib.baseboard_fab2(sch_1):page130_i9:a" )
			)
			( pin "C2N22.2"
				( objectStatus "@baseboard_fab2_lib.baseboard_fab2(sch_1):page130_i9:b" )
			)
			( pin "C2N20.1"
				( objectStatus "@baseboard_fab2_lib.baseboard_fab2(sch_1):page130_i12:a" )
			)
			( pin "C2N20.2"
				( objectStatus "@baseboard_fab2_lib.baseboard_fab2(sch_1):page130_i12:b" )
			)
			( pin "C2N21.1"
				( objectStatus "@baseboard_fab2_lib.baseboard_fab2(sch_1):page130_i15:a" )
			)
			( pin "C2N21.2"
				( objectStatus "@baseboard_fab2_lib.baseboard_fab2(sch_1):page130_i15:b" )
			)
			( pin "C3N29.1"
				( objectStatus "@baseboard_fab2_lib.baseboard_fab2(sch_1):page130_i16:a" )
			)
			( pin "C3N29.2"
				( objectStatus "@baseboard_fab2_lib.baseboard_fab2(sch_1):page130_i16:b" )
			)
			( pin "C8C3.1"
				( objectStatus "@baseboard_fab2_lib.baseboard_fab2(sch_1):page130_i19:a" )
			)
			( pin "C8C3.2"
				( objectStatus "@baseboard_fab2_lib.baseboard_fab2(sch_1):page130_i19:b" )
			)
			( pin "C8C4.1"
				( objectStatus "@baseboard_fab2_lib.baseboard_fab2(sch_1):page130_i20:a" )
			)
			( pin "C8C4.2"
				( objectStatus "@baseboard_fab2_lib.baseboard_fab2(sch_1):page130_i20:b" )
			)
			( pin "C8C5.1"
				( objectStatus "@baseboard_fab2_lib.baseboard_fab2(sch_1):page130_i21:a" )
			)
			( pin "C8C5.2"
				( objectStatus "@baseboard_fab2_lib.baseboard_fab2(sch_1):page130_i21:b" )
			)
			( pin "C8C6.1"
				( objectStatus "@baseboard_fab2_lib.baseboard_fab2(sch_1):page130_i22:a" )
			)
			( pin "C8C6.2"
				( objectStatus "@baseboard_fab2_lib.baseboard_fab2(sch_1):page130_i22:b" )
			)
			( pin "C2N23.1"
				( objectStatus "@baseboard_fab2_lib.baseboard_fab2(sch_1):page130_i24:a" )
			)
			( pin "C2N23.2"
				( objectStatus "@baseboard_fab2_lib.baseboard_fab2(sch_1):page130_i24:b" )
			)
			( pin "C2N14.1"
				( objectStatus "@baseboard_fab2_lib.baseboard_fab2(sch_1):page130_i25:a" )
			)
			( pin "C2N14.2"
				( objectStatus "@baseboard_fab2_lib.baseboard_fab2(sch_1):page130_i25:b" )
			)
			( pin "C2N17.1"
				( objectStatus "@baseboard_fab2_lib.baseboard_fab2(sch_1):page130_i28:a" )
			)
			( pin "C2N17.2"
				( objectStatus "@baseboard_fab2_lib.baseboard_fab2(sch_1):page130_i28:b" )
			)
			( pin "C2N18.1"
				( objectStatus "@baseboard_fab2_lib.baseboard_fab2(sch_1):page130_i29:a" )
			)
			( pin "C2N18.2"
				( objectStatus "@baseboard_fab2_lib.baseboard_fab2(sch_1):page130_i29:b" )
			)
			( pin "C8B2.1"
				( objectStatus "@baseboard_fab2_lib.baseboard_fab2(sch_1):page130_i30:a" )
			)
			( pin "C8B2.2"
				( objectStatus "@baseboard_fab2_lib.baseboard_fab2(sch_1):page130_i30:b" )
			)
			( pin "C8B3.1"
				( objectStatus "@baseboard_fab2_lib.baseboard_fab2(sch_1):page130_i32:a" )
			)
			( pin "C8B3.2"
				( objectStatus "@baseboard_fab2_lib.baseboard_fab2(sch_1):page130_i32:b" )
			)
			( pin "C2N25.1"
				( objectStatus "@baseboard_fab2_lib.baseboard_fab2(sch_1):page130_i34:a" )
			)
			( pin "C2N25.2"
				( objectStatus "@baseboard_fab2_lib.baseboard_fab2(sch_1):page130_i34:b" )
			)
			( pin "C2M16.1"
				( objectStatus "@baseboard_fab2_lib.baseboard_fab2(sch_1):page130_i37:a" )
			)
			( pin "C2M16.2"
				( objectStatus "@baseboard_fab2_lib.baseboard_fab2(sch_1):page130_i37:b" )
			)
			( pin "C7D3.1"
				( objectStatus "@baseboard_fab2_lib.baseboard_fab2(sch_1):page130_i38:a" )
			)
			( pin "C7D3.2"
				( objectStatus "@baseboard_fab2_lib.baseboard_fab2(sch_1):page130_i38:b" )
			)
			( pin "C8B4.1"
				( objectStatus "@baseboard_fab2_lib.baseboard_fab2(sch_1):page130_i39:a" )
			)
			( pin "C8B4.2"
				( objectStatus "@baseboard_fab2_lib.baseboard_fab2(sch_1):page130_i39:b" )
			)
			( pin "C8B1.1"
				( objectStatus "@baseboard_fab2_lib.baseboard_fab2(sch_1):page130_i41:a" )
			)
			( pin "C8B1.2"
				( objectStatus "@baseboard_fab2_lib.baseboard_fab2(sch_1):page130_i41:b" )
			)
			( pin "C3N23.1"
				( objectStatus "@baseboard_fab2_lib.baseboard_fab2(sch_1):page130_i42:a" )
			)
			( pin "C3N23.2"
				( objectStatus "@baseboard_fab2_lib.baseboard_fab2(sch_1):page130_i42:b" )
			)
			( pin "C2M1.1"
				( objectStatus "@baseboard_fab2_lib.baseboard_fab2(sch_1):page130_i43:a" )
			)
			( pin "C2M1.2"
				( objectStatus "@baseboard_fab2_lib.baseboard_fab2(sch_1):page130_i43:b" )
			)
			( pin "C2M2.1"
				( objectStatus "@baseboard_fab2_lib.baseboard_fab2(sch_1):page130_i45:a" )
			)
			( pin "C2M2.2"
				( objectStatus "@baseboard_fab2_lib.baseboard_fab2(sch_1):page130_i45:b" )
			)
			( pin "C2N15.1"
				( objectStatus "@baseboard_fab2_lib.baseboard_fab2(sch_1):page130_i47:a" )
			)
			( pin "C2N15.2"
				( objectStatus "@baseboard_fab2_lib.baseboard_fab2(sch_1):page130_i47:b" )
			)
			( pin "C3N21.1"
				( objectStatus "@baseboard_fab2_lib.baseboard_fab2(sch_1):page130_i49:a" )
			)
			( pin "C3N21.2"
				( objectStatus "@baseboard_fab2_lib.baseboard_fab2(sch_1):page130_i49:b" )
			)
			( pin "C3N25.1"
				( objectStatus "@baseboard_fab2_lib.baseboard_fab2(sch_1):page130_i50:a" )
			)
			( pin "C3N25.2"
				( objectStatus "@baseboard_fab2_lib.baseboard_fab2(sch_1):page130_i50:b" )
			)
			( pin "C2N16.1"
				( objectStatus "@baseboard_fab2_lib.baseboard_fab2(sch_1):page130_i52:a" )
			)
			( pin "C2N16.2"
				( objectStatus "@baseboard_fab2_lib.baseboard_fab2(sch_1):page130_i52:b" )
			)
			( pin "C3N22.1"
				( objectStatus "@baseboard_fab2_lib.baseboard_fab2(sch_1):page130_i53:a" )
			)
			( pin "C3N22.2"
				( objectStatus "@baseboard_fab2_lib.baseboard_fab2(sch_1):page130_i53:b" )
			)
			( pin "C7B15.1"
				( objectStatus "@baseboard_fab2_lib.baseboard_fab2(sch_1):page131_i1:a" )
			)
			( pin "C7B15.2"
				( objectStatus "@baseboard_fab2_lib.baseboard_fab2(sch_1):page131_i1:b" )
			)
			( pin "C7B19.1"
				( objectStatus "@baseboard_fab2_lib.baseboard_fab2(sch_1):page131_i2:a" )
			)
			( pin "C7B19.2"
				( objectStatus "@baseboard_fab2_lib.baseboard_fab2(sch_1):page131_i2:b" )
			)
			( pin "C7B16.1"
				( objectStatus "@baseboard_fab2_lib.baseboard_fab2(sch_1):page131_i3:a" )
			)
			( pin "C7B16.2"
				( objectStatus "@baseboard_fab2_lib.baseboard_fab2(sch_1):page131_i3:b" )
			)
			( pin "C7B21.1"
				( objectStatus "@baseboard_fab2_lib.baseboard_fab2(sch_1):page131_i4:a" )
			)
			( pin "C7B21.2"
				( objectStatus "@baseboard_fab2_lib.baseboard_fab2(sch_1):page131_i4:b" )
			)
			( pin "C7B20.1"
				( objectStatus "@baseboard_fab2_lib.baseboard_fab2(sch_1):page131_i6:a" )
			)
			( pin "C7B20.2"
				( objectStatus "@baseboard_fab2_lib.baseboard_fab2(sch_1):page131_i6:b" )
			)
			( pin "C7B23.1"
				( objectStatus "@baseboard_fab2_lib.baseboard_fab2(sch_1):page131_i7:a" )
			)
			( pin "C7B23.2"
				( objectStatus "@baseboard_fab2_lib.baseboard_fab2(sch_1):page131_i7:b" )
			)
			( pin "C8B10.1"
				( objectStatus "@baseboard_fab2_lib.baseboard_fab2(sch_1):page131_i8:a" )
			)
			( pin "C8B10.2"
				( objectStatus "@baseboard_fab2_lib.baseboard_fab2(sch_1):page131_i8:b" )
			)
			( pin "C7B22.1"
				( objectStatus "@baseboard_fab2_lib.baseboard_fab2(sch_1):page131_i10:a" )
			)
			( pin "C7B22.2"
				( objectStatus "@baseboard_fab2_lib.baseboard_fab2(sch_1):page131_i10:b" )
			)
			( pin "C7B24.1"
				( objectStatus "@baseboard_fab2_lib.baseboard_fab2(sch_1):page131_i11:a" )
			)
			( pin "C7B24.2"
				( objectStatus "@baseboard_fab2_lib.baseboard_fab2(sch_1):page131_i11:b" )
			)
			( pin "C7B18.1"
				( objectStatus "@baseboard_fab2_lib.baseboard_fab2(sch_1):page131_i12:a" )
			)
			( pin "C7B18.2"
				( objectStatus "@baseboard_fab2_lib.baseboard_fab2(sch_1):page131_i12:b" )
			)
			( pin "C8B9.1"
				( objectStatus "@baseboard_fab2_lib.baseboard_fab2(sch_1):page131_i14:a" )
			)
			( pin "C8B9.2"
				( objectStatus "@baseboard_fab2_lib.baseboard_fab2(sch_1):page131_i14:b" )
			)
			( pin "C8B11.1"
				( objectStatus "@baseboard_fab2_lib.baseboard_fab2(sch_1):page131_i15:a" )
			)
			( pin "C8B11.2"
				( objectStatus "@baseboard_fab2_lib.baseboard_fab2(sch_1):page131_i15:b" )
			)
			( pin "C8B14.1"
				( objectStatus "@baseboard_fab2_lib.baseboard_fab2(sch_1):page131_i16:a" )
			)
			( pin "C8B14.2"
				( objectStatus "@baseboard_fab2_lib.baseboard_fab2(sch_1):page131_i16:b" )
			)
			( pin "C7B17.1"
				( objectStatus "@baseboard_fab2_lib.baseboard_fab2(sch_1):page131_i18:a" )
			)
			( pin "C7B17.2"
				( objectStatus "@baseboard_fab2_lib.baseboard_fab2(sch_1):page131_i18:b" )
			)
			( pin "C8B13.1"
				( objectStatus "@baseboard_fab2_lib.baseboard_fab2(sch_1):page131_i20:a" )
			)
			( pin "C8B13.2"
				( objectStatus "@baseboard_fab2_lib.baseboard_fab2(sch_1):page131_i20:b" )
			)
			( pin "C8B16.1"
				( objectStatus "@baseboard_fab2_lib.baseboard_fab2(sch_1):page131_i22:a" )
			)
			( pin "C8B16.2"
				( objectStatus "@baseboard_fab2_lib.baseboard_fab2(sch_1):page131_i22:b" )
			)
			( pin "C8B15.1"
				( objectStatus "@baseboard_fab2_lib.baseboard_fab2(sch_1):page131_i24:a" )
			)
			( pin "C8B15.2"
				( objectStatus "@baseboard_fab2_lib.baseboard_fab2(sch_1):page131_i24:b" )
			)
			( pin "C2M22.1"
				( objectStatus "@baseboard_fab2_lib.baseboard_fab2(sch_1):page131_i27:a" )
			)
			( pin "C2M22.2"
				( objectStatus "@baseboard_fab2_lib.baseboard_fab2(sch_1):page131_i27:b" )
			)
			( pin "C2M21.1"
				( objectStatus "@baseboard_fab2_lib.baseboard_fab2(sch_1):page131_i28:a" )
			)
			( pin "C2M21.2"
				( objectStatus "@baseboard_fab2_lib.baseboard_fab2(sch_1):page131_i28:b" )
			)
			( pin "C2M18.1"
				( objectStatus "@baseboard_fab2_lib.baseboard_fab2(sch_1):page131_i29:a" )
			)
			( pin "C2M18.2"
				( objectStatus "@baseboard_fab2_lib.baseboard_fab2(sch_1):page131_i29:b" )
			)
			( pin "C2M19.1"
				( objectStatus "@baseboard_fab2_lib.baseboard_fab2(sch_1):page131_i31:a" )
			)
			( pin "C2M19.2"
				( objectStatus "@baseboard_fab2_lib.baseboard_fab2(sch_1):page131_i31:b" )
			)
			( pin "C3M38.1"
				( objectStatus "@baseboard_fab2_lib.baseboard_fab2(sch_1):page131_i32:a" )
			)
			( pin "C3M38.2"
				( objectStatus "@baseboard_fab2_lib.baseboard_fab2(sch_1):page131_i32:b" )
			)
			( pin "C2M17.1"
				( objectStatus "@baseboard_fab2_lib.baseboard_fab2(sch_1):page131_i34:a" )
			)
			( pin "C2M17.2"
				( objectStatus "@baseboard_fab2_lib.baseboard_fab2(sch_1):page131_i34:b" )
			)
			( pin "C2M11.1"
				( objectStatus "@baseboard_fab2_lib.baseboard_fab2(sch_1):page131_i35:a" )
			)
			( pin "C2M11.2"
				( objectStatus "@baseboard_fab2_lib.baseboard_fab2(sch_1):page131_i35:b" )
			)
			( pin "C8A13.1"
				( objectStatus "@baseboard_fab2_lib.baseboard_fab2(sch_1):page131_i37:a" )
			)
			( pin "C8A13.2"
				( objectStatus "@baseboard_fab2_lib.baseboard_fab2(sch_1):page131_i37:b" )
			)
			( pin "C2M20.1"
				( objectStatus "@baseboard_fab2_lib.baseboard_fab2(sch_1):page131_i39:a" )
			)
			( pin "C2M20.2"
				( objectStatus "@baseboard_fab2_lib.baseboard_fab2(sch_1):page131_i39:b" )
			)
			( pin "C2N13.1"
				( objectStatus "@baseboard_fab2_lib.baseboard_fab2(sch_1):page131_i40:a" )
			)
			( pin "C2N13.2"
				( objectStatus "@baseboard_fab2_lib.baseboard_fab2(sch_1):page131_i40:b" )
			)
			( pin "C2N2.1"
				( objectStatus "@baseboard_fab2_lib.baseboard_fab2(sch_1):page131_i41:a" )
			)
			( pin "C2N2.2"
				( objectStatus "@baseboard_fab2_lib.baseboard_fab2(sch_1):page131_i41:b" )
			)
			( pin "C3M43.1"
				( objectStatus "@baseboard_fab2_lib.baseboard_fab2(sch_1):page131_i42:a" )
			)
			( pin "C3M43.2"
				( objectStatus "@baseboard_fab2_lib.baseboard_fab2(sch_1):page131_i42:b" )
			)
			( pin "C2N7.1"
				( objectStatus "@baseboard_fab2_lib.baseboard_fab2(sch_1):page131_i43:a" )
			)
			( pin "C2N7.2"
				( objectStatus "@baseboard_fab2_lib.baseboard_fab2(sch_1):page131_i43:b" )
			)
			( pin "C3M39.1"
				( objectStatus "@baseboard_fab2_lib.baseboard_fab2(sch_1):page131_i44:a" )
			)
			( pin "C3M39.2"
				( objectStatus "@baseboard_fab2_lib.baseboard_fab2(sch_1):page131_i44:b" )
			)
			( pin "C3M42.1"
				( objectStatus "@baseboard_fab2_lib.baseboard_fab2(sch_1):page131_i45:a" )
			)
			( pin "C3M42.2"
				( objectStatus "@baseboard_fab2_lib.baseboard_fab2(sch_1):page131_i45:b" )
			)
			( pin "C2N8.1"
				( objectStatus "@baseboard_fab2_lib.baseboard_fab2(sch_1):page131_i47:a" )
			)
			( pin "C2N8.2"
				( objectStatus "@baseboard_fab2_lib.baseboard_fab2(sch_1):page131_i47:b" )
			)
			( pin "C2M13.1"
				( objectStatus "@baseboard_fab2_lib.baseboard_fab2(sch_1):page131_i48:a" )
			)
			( pin "C2M13.2"
				( objectStatus "@baseboard_fab2_lib.baseboard_fab2(sch_1):page131_i48:b" )
			)
			( pin "C2N10.1"
				( objectStatus "@baseboard_fab2_lib.baseboard_fab2(sch_1):page131_i50:a" )
			)
			( pin "C2N10.2"
				( objectStatus "@baseboard_fab2_lib.baseboard_fab2(sch_1):page131_i50:b" )
			)
			( pin "C2M12.1"
				( objectStatus "@baseboard_fab2_lib.baseboard_fab2(sch_1):page131_i52:a" )
			)
			( pin "C2M12.2"
				( objectStatus "@baseboard_fab2_lib.baseboard_fab2(sch_1):page131_i52:b" )
			)
			( pin "C3L25.1"
				( objectStatus "@baseboard_fab2_lib.baseboard_fab2(sch_1):page132_i1:a" )
			)
			( pin "C3L25.2"
				( objectStatus "@baseboard_fab2_lib.baseboard_fab2(sch_1):page132_i1:b" )
			)
			( pin "C3M7.1"
				( objectStatus "@baseboard_fab2_lib.baseboard_fab2(sch_1):page132_i2:a" )
			)
			( pin "C3M7.2"
				( objectStatus "@baseboard_fab2_lib.baseboard_fab2(sch_1):page132_i2:b" )
			)
			( pin "C3L26.1"
				( objectStatus "@baseboard_fab2_lib.baseboard_fab2(sch_1):page132_i3:a" )
			)
			( pin "C3L26.2"
				( objectStatus "@baseboard_fab2_lib.baseboard_fab2(sch_1):page132_i3:b" )
			)
			( pin "C3L27.1"
				( objectStatus "@baseboard_fab2_lib.baseboard_fab2(sch_1):page132_i4:a" )
			)
			( pin "C3L27.2"
				( objectStatus "@baseboard_fab2_lib.baseboard_fab2(sch_1):page132_i4:b" )
			)
			( pin "C3M6.1"
				( objectStatus "@baseboard_fab2_lib.baseboard_fab2(sch_1):page132_i6:a" )
			)
			( pin "C3M6.2"
				( objectStatus "@baseboard_fab2_lib.baseboard_fab2(sch_1):page132_i6:b" )
			)
			( pin "C7C9.1"
				( objectStatus "@baseboard_fab2_lib.baseboard_fab2(sch_1):page132_i7:a" )
			)
			( pin "C7C9.2"
				( objectStatus "@baseboard_fab2_lib.baseboard_fab2(sch_1):page132_i7:b" )
			)
			( pin "C3N27.1"
				( objectStatus "@baseboard_fab2_lib.baseboard_fab2(sch_1):page132_i8:a" )
			)
			( pin "C3N27.2"
				( objectStatus "@baseboard_fab2_lib.baseboard_fab2(sch_1):page132_i8:b" )
			)
			( pin "C3N30.1"
				( objectStatus "@baseboard_fab2_lib.baseboard_fab2(sch_1):page132_i9:a" )
			)
			( pin "C3N30.2"
				( objectStatus "@baseboard_fab2_lib.baseboard_fab2(sch_1):page132_i9:b" )
			)
			( pin "C7A36.1"
				( objectStatus "@baseboard_fab2_lib.baseboard_fab2(sch_1):page132_i11:a" )
			)
			( pin "C7A36.2"
				( objectStatus "@baseboard_fab2_lib.baseboard_fab2(sch_1):page132_i11:b" )
			)
			( pin "C3N12.1"
				( objectStatus "@baseboard_fab2_lib.baseboard_fab2(sch_1):page132_i12:a" )
			)
			( pin "C3N12.2"
				( objectStatus "@baseboard_fab2_lib.baseboard_fab2(sch_1):page132_i12:b" )
			)
			( pin "C3N10.1"
				( objectStatus "@baseboard_fab2_lib.baseboard_fab2(sch_1):page132_i13:a" )
			)
			( pin "C3N10.2"
				( objectStatus "@baseboard_fab2_lib.baseboard_fab2(sch_1):page132_i13:b" )
			)
			( pin "C3N24.1"
				( objectStatus "@baseboard_fab2_lib.baseboard_fab2(sch_1):page132_i16:a" )
			)
			( pin "C3N24.2"
				( objectStatus "@baseboard_fab2_lib.baseboard_fab2(sch_1):page132_i16:b" )
			)
			( pin "C3N28.1"
				( objectStatus "@baseboard_fab2_lib.baseboard_fab2(sch_1):page132_i17:a" )
			)
			( pin "C3N28.2"
				( objectStatus "@baseboard_fab2_lib.baseboard_fab2(sch_1):page132_i17:b" )
			)
			( pin "C3N11.1"
				( objectStatus "@baseboard_fab2_lib.baseboard_fab2(sch_1):page132_i19:a" )
			)
			( pin "C3N11.2"
				( objectStatus "@baseboard_fab2_lib.baseboard_fab2(sch_1):page132_i19:b" )
			)
			( pin "C3N31.1"
				( objectStatus "@baseboard_fab2_lib.baseboard_fab2(sch_1):page132_i20:a" )
			)
			( pin "C3N31.2"
				( objectStatus "@baseboard_fab2_lib.baseboard_fab2(sch_1):page132_i20:b" )
			)
			( pin "C7A33.1"
				( objectStatus "@baseboard_fab2_lib.baseboard_fab2(sch_1):page132_i23:a" )
			)
			( pin "C7A33.2"
				( objectStatus "@baseboard_fab2_lib.baseboard_fab2(sch_1):page132_i23:b" )
			)
			( pin "C7B4.1"
				( objectStatus "@baseboard_fab2_lib.baseboard_fab2(sch_1):page132_i24:a" )
			)
			( pin "C7B4.2"
				( objectStatus "@baseboard_fab2_lib.baseboard_fab2(sch_1):page132_i24:b" )
			)
			( pin "C2N9.1"
				( objectStatus "@baseboard_fab2_lib.baseboard_fab2(sch_1):page132_i26:a" )
			)
			( pin "C2N9.2"
				( objectStatus "@baseboard_fab2_lib.baseboard_fab2(sch_1):page132_i26:b" )
			)
			( pin "C2N3.1"
				( objectStatus "@baseboard_fab2_lib.baseboard_fab2(sch_1):page132_i27:a" )
			)
			( pin "C2N3.2"
				( objectStatus "@baseboard_fab2_lib.baseboard_fab2(sch_1):page132_i27:b" )
			)
			( pin "C2N4.1"
				( objectStatus "@baseboard_fab2_lib.baseboard_fab2(sch_1):page132_i28:a" )
			)
			( pin "C2N4.2"
				( objectStatus "@baseboard_fab2_lib.baseboard_fab2(sch_1):page132_i28:b" )
			)
			( pin "C2N12.1"
				( objectStatus "@baseboard_fab2_lib.baseboard_fab2(sch_1):page132_i29:a" )
			)
			( pin "C2N12.2"
				( objectStatus "@baseboard_fab2_lib.baseboard_fab2(sch_1):page132_i29:b" )
			)
			( pin "C2N11.1"
				( objectStatus "@baseboard_fab2_lib.baseboard_fab2(sch_1):page132_i30:a" )
			)
			( pin "C2N11.2"
				( objectStatus "@baseboard_fab2_lib.baseboard_fab2(sch_1):page132_i30:b" )
			)
			( pin "C3N19.1"
				( objectStatus "@baseboard_fab2_lib.baseboard_fab2(sch_1):page132_i31:a" )
			)
			( pin "C3N19.2"
				( objectStatus "@baseboard_fab2_lib.baseboard_fab2(sch_1):page132_i31:b" )
			)
			( pin "C3N3.1"
				( objectStatus "@baseboard_fab2_lib.baseboard_fab2(sch_1):page132_i32:a" )
			)
			( pin "C3N3.2"
				( objectStatus "@baseboard_fab2_lib.baseboard_fab2(sch_1):page132_i32:b" )
			)
			( pin "C3N1.1"
				( objectStatus "@baseboard_fab2_lib.baseboard_fab2(sch_1):page132_i34:a" )
			)
			( pin "C3N1.2"
				( objectStatus "@baseboard_fab2_lib.baseboard_fab2(sch_1):page132_i34:b" )
			)
			( pin "C3N7.1"
				( objectStatus "@baseboard_fab2_lib.baseboard_fab2(sch_1):page132_i35:a" )
			)
			( pin "C3N7.2"
				( objectStatus "@baseboard_fab2_lib.baseboard_fab2(sch_1):page132_i35:b" )
			)
			( pin "C3N16.1"
				( objectStatus "@baseboard_fab2_lib.baseboard_fab2(sch_1):page132_i36:a" )
			)
			( pin "C3N16.2"
				( objectStatus "@baseboard_fab2_lib.baseboard_fab2(sch_1):page132_i36:b" )
			)
			( pin "C7A32.1"
				( objectStatus "@baseboard_fab2_lib.baseboard_fab2(sch_1):page132_i38:a" )
			)
			( pin "C7A32.2"
				( objectStatus "@baseboard_fab2_lib.baseboard_fab2(sch_1):page132_i38:b" )
			)
			( pin "C7A31.1"
				( objectStatus "@baseboard_fab2_lib.baseboard_fab2(sch_1):page132_i40:a" )
			)
			( pin "C7A31.2"
				( objectStatus "@baseboard_fab2_lib.baseboard_fab2(sch_1):page132_i40:b" )
			)
			( pin "C3N18.1"
				( objectStatus "@baseboard_fab2_lib.baseboard_fab2(sch_1):page132_i42:a" )
			)
			( pin "C3N18.2"
				( objectStatus "@baseboard_fab2_lib.baseboard_fab2(sch_1):page132_i42:b" )
			)
			( pin "C3N2.1"
				( objectStatus "@baseboard_fab2_lib.baseboard_fab2(sch_1):page132_i43:a" )
			)
			( pin "C3N2.2"
				( objectStatus "@baseboard_fab2_lib.baseboard_fab2(sch_1):page132_i43:b" )
			)
			( pin "C3N6.1"
				( objectStatus "@baseboard_fab2_lib.baseboard_fab2(sch_1):page132_i44:a" )
			)
			( pin "C3N6.2"
				( objectStatus "@baseboard_fab2_lib.baseboard_fab2(sch_1):page132_i44:b" )
			)
			( pin "C3N17.1"
				( objectStatus "@baseboard_fab2_lib.baseboard_fab2(sch_1):page132_i45:a" )
			)
			( pin "C3N17.2"
				( objectStatus "@baseboard_fab2_lib.baseboard_fab2(sch_1):page132_i45:b" )
			)
			( pin "C3N4.1"
				( objectStatus "@baseboard_fab2_lib.baseboard_fab2(sch_1):page132_i46:a" )
			)
			( pin "C3N4.2"
				( objectStatus "@baseboard_fab2_lib.baseboard_fab2(sch_1):page132_i46:b" )
			)
			( pin "C3N5.1"
				( objectStatus "@baseboard_fab2_lib.baseboard_fab2(sch_1):page132_i48:a" )
			)
			( pin "C3N5.2"
				( objectStatus "@baseboard_fab2_lib.baseboard_fab2(sch_1):page132_i48:b" )
			)
			( pin "C3N15.1"
				( objectStatus "@baseboard_fab2_lib.baseboard_fab2(sch_1):page132_i49:a" )
			)
			( pin "C3N15.2"
				( objectStatus "@baseboard_fab2_lib.baseboard_fab2(sch_1):page132_i49:b" )
			)
			( pin "C3N20.1"
				( objectStatus "@baseboard_fab2_lib.baseboard_fab2(sch_1):page132_i51:a" )
			)
			( pin "C3N20.2"
				( objectStatus "@baseboard_fab2_lib.baseboard_fab2(sch_1):page132_i51:b" )
			)
			( pin "C3L23.1"
				( objectStatus "@baseboard_fab2_lib.baseboard_fab2(sch_1):page132_i52:a" )
			)
			( pin "C3L23.2"
				( objectStatus "@baseboard_fab2_lib.baseboard_fab2(sch_1):page132_i52:b" )
			)
			( pin "C3L22.1"
				( objectStatus "@baseboard_fab2_lib.baseboard_fab2(sch_1):page132_i54:a" )
			)
			( pin "C3L22.2"
				( objectStatus "@baseboard_fab2_lib.baseboard_fab2(sch_1):page132_i54:b" )
			)
			( pin "C3L24.1"
				( objectStatus "@baseboard_fab2_lib.baseboard_fab2(sch_1):page132_i56:a" )
			)
			( pin "C3L24.2"
				( objectStatus "@baseboard_fab2_lib.baseboard_fab2(sch_1):page132_i56:b" )
			)
			( pin "R3N3.1"
				( objectStatus "@baseboard_fab2_lib.baseboard_fab2(sch_1):page133_i120:a" )
			)
			( pin "R3N3.2"
				( objectStatus "@baseboard_fab2_lib.baseboard_fab2(sch_1):page133_i120:b" )
			)
			( pin "R2N12.1"
				( objectStatus "@baseboard_fab2_lib.baseboard_fab2(sch_1):page133_i122:a" )
			)
			( pin "R2N12.2"
				( objectStatus "@baseboard_fab2_lib.baseboard_fab2(sch_1):page133_i122:b" )
			)
			( pin "R7D8.1"
				( objectStatus "@baseboard_fab2_lib.baseboard_fab2(sch_1):page133_i200:a" )
			)
			( pin "R7D8.2"
				( objectStatus "@baseboard_fab2_lib.baseboard_fab2(sch_1):page133_i200:b" )
			)
			( pin "R7D10.1"
				( objectStatus "@baseboard_fab2_lib.baseboard_fab2(sch_1):page133_i202:a" )
			)
			( pin "R7D10.2"
				( objectStatus "@baseboard_fab2_lib.baseboard_fab2(sch_1):page133_i202:b" )
			)
			( pin "R7D12.1"
				( objectStatus "@baseboard_fab2_lib.baseboard_fab2(sch_1):page133_i237:a" )
			)
			( pin "R7D12.2"
				( objectStatus "@baseboard_fab2_lib.baseboard_fab2(sch_1):page133_i237:b" )
			)
			( pin "R7D3.1"
				( objectStatus "@baseboard_fab2_lib.baseboard_fab2(sch_1):page133_i243:a" )
			)
			( pin "R7D3.2"
				( objectStatus "@baseboard_fab2_lib.baseboard_fab2(sch_1):page133_i243:b" )
			)
			( pin "R7D4.1"
				( objectStatus "@baseboard_fab2_lib.baseboard_fab2(sch_1):page133_i245:a" )
			)
			( pin "R7D4.2"
				( objectStatus "@baseboard_fab2_lib.baseboard_fab2(sch_1):page133_i245:b" )
			)
			( pin "R2N16.1"
				( objectStatus "@baseboard_fab2_lib.baseboard_fab2(sch_1):page133_i247:a" )
			)
			( pin "R2N16.2"
				( objectStatus "@baseboard_fab2_lib.baseboard_fab2(sch_1):page133_i247:b" )
			)
			( pin "R2R5.1"
				( objectStatus "@baseboard_fab2_lib.baseboard_fab2(sch_1):page133_i258:a" )
			)
			( pin "R2R5.2"
				( objectStatus "@baseboard_fab2_lib.baseboard_fab2(sch_1):page133_i258:b" )
			)
			( pin "R2N9.1"
				( objectStatus "@baseboard_fab2_lib.baseboard_fab2(sch_1):page133_i267:a" )
			)
			( pin "R2N9.2"
				( objectStatus "@baseboard_fab2_lib.baseboard_fab2(sch_1):page133_i267:b" )
			)
			( pin "R8B23.1"
				( objectStatus "@baseboard_fab2_lib.baseboard_fab2(sch_1):page133_i280:a" )
			)
			( pin "R8B23.2"
				( objectStatus "@baseboard_fab2_lib.baseboard_fab2(sch_1):page133_i280:b" )
			)
			( pin "R8B30.1"
				( objectStatus "@baseboard_fab2_lib.baseboard_fab2(sch_1):page133_i282:a" )
			)
			( pin "R8B30.2"
				( objectStatus "@baseboard_fab2_lib.baseboard_fab2(sch_1):page133_i282:b" )
			)
			( pin "R2M4.1"
				( objectStatus "@baseboard_fab2_lib.baseboard_fab2(sch_1):page133_i284:a" )
			)
			( pin "R2M4.2"
				( objectStatus "@baseboard_fab2_lib.baseboard_fab2(sch_1):page133_i284:b" )
			)
			( pin "R8C4.1"
				( objectStatus "@baseboard_fab2_lib.baseboard_fab2(sch_1):page133_i286:a" )
			)
			( pin "R8C4.2"
				( objectStatus "@baseboard_fab2_lib.baseboard_fab2(sch_1):page133_i286:b" )
			)
			( pin "R7B6.1"
				( objectStatus "@baseboard_fab2_lib.baseboard_fab2(sch_1):page133_i295:a" )
			)
			( pin "R7B6.2"
				( objectStatus "@baseboard_fab2_lib.baseboard_fab2(sch_1):page133_i295:b" )
			)
			( pin "R7C8.1"
				( objectStatus "@baseboard_fab2_lib.baseboard_fab2(sch_1):page133_i296:a" )
			)
			( pin "R7C8.2"
				( objectStatus "@baseboard_fab2_lib.baseboard_fab2(sch_1):page133_i296:b" )
			)
			( pin "R7C5.1"
				( objectStatus "@baseboard_fab2_lib.baseboard_fab2(sch_1):page133_i297:a" )
			)
			( pin "R7C5.2"
				( objectStatus "@baseboard_fab2_lib.baseboard_fab2(sch_1):page133_i297:b" )
			)
			( pin "R8D14.1"
				( objectStatus "@baseboard_fab2_lib.baseboard_fab2(sch_1):page133_i301:a" )
			)
			( pin "R8D14.2"
				( objectStatus "@baseboard_fab2_lib.baseboard_fab2(sch_1):page133_i301:b" )
			)
			( pin "R8C6.1"
				( objectStatus "@baseboard_fab2_lib.baseboard_fab2(sch_1):page133_i303:a" )
			)
			( pin "R8C6.2"
				( objectStatus "@baseboard_fab2_lib.baseboard_fab2(sch_1):page133_i303:b" )
			)
			( pin "R8C2.1"
				( objectStatus "@baseboard_fab2_lib.baseboard_fab2(sch_1):page133_i304:a" )
			)
			( pin "R8C2.2"
				( objectStatus "@baseboard_fab2_lib.baseboard_fab2(sch_1):page133_i304:b" )
			)
			( pin "R7D6.1"
				( objectStatus "@baseboard_fab2_lib.baseboard_fab2(sch_1):page133_i306:a" )
			)
			( pin "R7D6.2"
				( objectStatus "@baseboard_fab2_lib.baseboard_fab2(sch_1):page133_i306:b" )
			)
			( pin "R8B31.1"
				( objectStatus "@baseboard_fab2_lib.baseboard_fab2(sch_1):page133_i307:a" )
			)
			( pin "R8B31.2"
				( objectStatus "@baseboard_fab2_lib.baseboard_fab2(sch_1):page133_i307:b" )
			)
			( pin "R2N7.1"
				( objectStatus "@baseboard_fab2_lib.baseboard_fab2(sch_1):page133_i309:a" )
			)
			( pin "R2N7.2"
				( objectStatus "@baseboard_fab2_lib.baseboard_fab2(sch_1):page133_i309:b" )
			)
			( pin "R3P7.1"
				( objectStatus "@baseboard_fab2_lib.baseboard_fab2(sch_1):page133_i315:a" )
			)
			( pin "R3P7.2"
				( objectStatus "@baseboard_fab2_lib.baseboard_fab2(sch_1):page133_i315:b" )
			)
			( pin "R3P5.1"
				( objectStatus "@baseboard_fab2_lib.baseboard_fab2(sch_1):page133_i316:a" )
			)
			( pin "R3P5.2"
				( objectStatus "@baseboard_fab2_lib.baseboard_fab2(sch_1):page133_i316:b" )
			)
			( pin "R3P6.1"
				( objectStatus "@baseboard_fab2_lib.baseboard_fab2(sch_1):page133_i317:a" )
			)
			( pin "R3P6.2"
				( objectStatus "@baseboard_fab2_lib.baseboard_fab2(sch_1):page133_i317:b" )
			)
			( pin "R3N15.1"
				( objectStatus "@baseboard_fab2_lib.baseboard_fab2(sch_1):page133_i318:a" )
			)
			( pin "R3N15.2"
				( objectStatus "@baseboard_fab2_lib.baseboard_fab2(sch_1):page133_i318:b" )
			)
			( pin "R3N16.1"
				( objectStatus "@baseboard_fab2_lib.baseboard_fab2(sch_1):page133_i321:a" )
			)
			( pin "R3N16.2"
				( objectStatus "@baseboard_fab2_lib.baseboard_fab2(sch_1):page133_i321:b" )
			)
			( pin "R3P8.1"
				( objectStatus "@baseboard_fab2_lib.baseboard_fab2(sch_1):page133_i322:a" )
			)
			( pin "R3P8.2"
				( objectStatus "@baseboard_fab2_lib.baseboard_fab2(sch_1):page133_i322:b" )
			)
			( pin "R8C1.1"
				( objectStatus "@baseboard_fab2_lib.baseboard_fab2(sch_1):page133_i326:a" )
			)
			( pin "R8C1.2"
				( objectStatus "@baseboard_fab2_lib.baseboard_fab2(sch_1):page133_i326:b" )
			)
			( pin "R8C7.1"
				( objectStatus "@baseboard_fab2_lib.baseboard_fab2(sch_1):page133_i327:a" )
			)
			( pin "R8C7.2"
				( objectStatus "@baseboard_fab2_lib.baseboard_fab2(sch_1):page133_i327:b" )
			)
			( pin "R7D7.1"
				( objectStatus "@baseboard_fab2_lib.baseboard_fab2(sch_1):page133_i331:a" )
			)
			( pin "R7D7.2"
				( objectStatus "@baseboard_fab2_lib.baseboard_fab2(sch_1):page133_i331:b" )
			)
			( pin "R7D2.1"
				( objectStatus "@baseboard_fab2_lib.baseboard_fab2(sch_1):page133_i332:a" )
			)
			( pin "R7D2.2"
				( objectStatus "@baseboard_fab2_lib.baseboard_fab2(sch_1):page133_i332:b" )
			)
			( pin "R8C25.1"
				( objectStatus "@baseboard_fab2_lib.baseboard_fab2(sch_1):page133_i333:a" )
			)
			( pin "R8C25.2"
				( objectStatus "@baseboard_fab2_lib.baseboard_fab2(sch_1):page133_i333:b" )
			)
			( pin "R2N32.1"
				( objectStatus "@baseboard_fab2_lib.baseboard_fab2(sch_1):page133_i341:a" )
			)
			( pin "R2N32.2"
				( objectStatus "@baseboard_fab2_lib.baseboard_fab2(sch_1):page133_i341:b" )
			)
			( pin "R2M8.1"
				( objectStatus "@baseboard_fab2_lib.baseboard_fab2(sch_1):page133_i349:a" )
			)
			( pin "R2M8.2"
				( objectStatus "@baseboard_fab2_lib.baseboard_fab2(sch_1):page133_i349:b" )
			)
			( pin "R2N29.1"
				( objectStatus "@baseboard_fab2_lib.baseboard_fab2(sch_1):page133_i352:a" )
			)
			( pin "R2N29.2"
				( objectStatus "@baseboard_fab2_lib.baseboard_fab2(sch_1):page133_i352:b" )
			)
			( pin "R8E3.1"
				( objectStatus "@baseboard_fab2_lib.baseboard_fab2(sch_1):page133_i355:a" )
			)
			( pin "R8E3.2"
				( objectStatus "@baseboard_fab2_lib.baseboard_fab2(sch_1):page133_i355:b" )
			)
			( pin "R7D44.1"
				( objectStatus "@baseboard_fab2_lib.baseboard_fab2(sch_1):page133_i356:a" )
			)
			( pin "R7D44.2"
				( objectStatus "@baseboard_fab2_lib.baseboard_fab2(sch_1):page133_i356:b" )
			)
			( pin "R3P53.1"
				( objectStatus "@baseboard_fab2_lib.baseboard_fab2(sch_1):page133_i357:a" )
			)
			( pin "R3P53.2"
				( objectStatus "@baseboard_fab2_lib.baseboard_fab2(sch_1):page133_i357:b" )
			)
			( pin "R2P22.1"
				( objectStatus "@baseboard_fab2_lib.baseboard_fab2(sch_1):page133_i360:a" )
			)
			( pin "R2P22.2"
				( objectStatus "@baseboard_fab2_lib.baseboard_fab2(sch_1):page133_i360:b" )
			)
			( pin "R8D44.1"
				( objectStatus "@baseboard_fab2_lib.baseboard_fab2(sch_1):page133_i362:a" )
			)
			( pin "R8D44.2"
				( objectStatus "@baseboard_fab2_lib.baseboard_fab2(sch_1):page133_i362:b" )
			)
			( pin "R2P17.1"
				( objectStatus "@baseboard_fab2_lib.baseboard_fab2(sch_1):page134_i3:a" )
			)
			( pin "R2P17.2"
				( objectStatus "@baseboard_fab2_lib.baseboard_fab2(sch_1):page134_i3:b" )
			)
			( pin "Q8D2.3"
				( objectStatus "@baseboard_fab2_lib.baseboard_fab2(sch_1):page134_i4:drn" )
			)
			( pin "Q8D2.1"
				( objectStatus "@baseboard_fab2_lib.baseboard_fab2(sch_1):page134_i4:gate" )
			)
			( pin "Q8D2.2"
				( objectStatus "@baseboard_fab2_lib.baseboard_fab2(sch_1):page134_i4:src" )
			)
			( pin "R7C21.1"
				( objectStatus "@baseboard_fab2_lib.baseboard_fab2(sch_1):page134_i9:a" )
			)
			( pin "R7C21.2"
				( objectStatus "@baseboard_fab2_lib.baseboard_fab2(sch_1):page134_i9:b" )
			)
			( pin "Q7D1.3"
				( objectStatus "@baseboard_fab2_lib.baseboard_fab2(sch_1):page134_i10:drn" )
			)
			( pin "Q7D1.1"
				( objectStatus "@baseboard_fab2_lib.baseboard_fab2(sch_1):page134_i10:gate" )
			)
			( pin "Q7D1.2"
				( objectStatus "@baseboard_fab2_lib.baseboard_fab2(sch_1):page134_i10:src" )
			)
			( pin "R7D18.1"
				( objectStatus "@baseboard_fab2_lib.baseboard_fab2(sch_1):page134_i11:a" )
			)
			( pin "R7D18.2"
				( objectStatus "@baseboard_fab2_lib.baseboard_fab2(sch_1):page134_i11:b" )
			)
			( pin "R2P19.1"
				( objectStatus "@baseboard_fab2_lib.baseboard_fab2(sch_1):page135_i107:a" )
			)
			( pin "R2P19.2"
				( objectStatus "@baseboard_fab2_lib.baseboard_fab2(sch_1):page135_i107:b" )
			)
			( pin "R2N23.1"
				( objectStatus "@baseboard_fab2_lib.baseboard_fab2(sch_1):page135_i112:a" )
			)
			( pin "R2N23.2"
				( objectStatus "@baseboard_fab2_lib.baseboard_fab2(sch_1):page135_i112:b" )
			)
			( pin "R2N24.1"
				( objectStatus "@baseboard_fab2_lib.baseboard_fab2(sch_1):page135_i113:a" )
			)
			( pin "R2N24.2"
				( objectStatus "@baseboard_fab2_lib.baseboard_fab2(sch_1):page135_i113:b" )
			)
			( pin "R9A12.1"
				( objectStatus "@baseboard_fab2_lib.baseboard_fab2(sch_1):page135_i117:a" )
			)
			( pin "R9A12.2"
				( objectStatus "@baseboard_fab2_lib.baseboard_fab2(sch_1):page135_i117:b" )
			)
			( pin "R9A13.1"
				( objectStatus "@baseboard_fab2_lib.baseboard_fab2(sch_1):page135_i118:a" )
			)
			( pin "R9A13.2"
				( objectStatus "@baseboard_fab2_lib.baseboard_fab2(sch_1):page135_i118:b" )
			)
			( pin "R8D21.1"
				( objectStatus "@baseboard_fab2_lib.baseboard_fab2(sch_1):page135_i120:a" )
			)
			( pin "R8D21.2"
				( objectStatus "@baseboard_fab2_lib.baseboard_fab2(sch_1):page135_i120:b" )
			)
			( pin "R7D30.1"
				( objectStatus "@baseboard_fab2_lib.baseboard_fab2(sch_1):page135_i121:a" )
			)
			( pin "R7D30.2"
				( objectStatus "@baseboard_fab2_lib.baseboard_fab2(sch_1):page135_i121:b" )
			)
			( pin "J8G2.1"
				( objectStatus "@baseboard_fab2_lib.baseboard_fab2(sch_1):page135_i124:io1" )
			)
			( pin "J8G2.2"
				( objectStatus "@baseboard_fab2_lib.baseboard_fab2(sch_1):page135_i124:io2" )
			)
			( pin "J8G2.3"
				( objectStatus "@baseboard_fab2_lib.baseboard_fab2(sch_1):page135_i124:io3" )
			)
			( pin "J8G2.4"
				( objectStatus "@baseboard_fab2_lib.baseboard_fab2(sch_1):page135_i124:io4" )
			)
			( pin "J8G2.5"
				( objectStatus "@baseboard_fab2_lib.baseboard_fab2(sch_1):page135_i124:io5" )
			)
			( pin "J8G2.6"
				( objectStatus "@baseboard_fab2_lib.baseboard_fab2(sch_1):page135_i124:io6" )
			)
			( pin "J8G2.7"
				( objectStatus "@baseboard_fab2_lib.baseboard_fab2(sch_1):page135_i124:io7" )
			)
			( pin "J8G2.8"
				( objectStatus "@baseboard_fab2_lib.baseboard_fab2(sch_1):page135_i124:io8" )
			)
			( pin "J8G2.9"
				( objectStatus "@baseboard_fab2_lib.baseboard_fab2(sch_1):page135_i124:io9" )
			)
			( pin "J8G2.10"
				( objectStatus "@baseboard_fab2_lib.baseboard_fab2(sch_1):page135_i124:io10" )
			)
			( pin "J8G2.11"
				( objectStatus "@baseboard_fab2_lib.baseboard_fab2(sch_1):page135_i124:io11" )
			)
			( pin "J8G2.12"
				( objectStatus "@baseboard_fab2_lib.baseboard_fab2(sch_1):page135_i124:io12" )
			)
			( pin "R9A16.1"
				( objectStatus "@baseboard_fab2_lib.baseboard_fab2(sch_1):page135_i129:a" )
			)
			( pin "R9A16.2"
				( objectStatus "@baseboard_fab2_lib.baseboard_fab2(sch_1):page135_i129:b" )
			)
			( pin "J9A1.1"
				( objectStatus "@baseboard_fab2_lib.baseboard_fab2(sch_1):page135_i131:io1" )
			)
			( pin "J9A1.2"
				( objectStatus "@baseboard_fab2_lib.baseboard_fab2(sch_1):page135_i131:io2" )
			)
			( pin "J9A1.3"
				( objectStatus "@baseboard_fab2_lib.baseboard_fab2(sch_1):page135_i131:io3" )
			)
			( pin "J9A1.4"
				( objectStatus "@baseboard_fab2_lib.baseboard_fab2(sch_1):page135_i131:io4" )
			)
			( pin "R7G26.1"
				( objectStatus "@baseboard_fab2_lib.baseboard_fab2(sch_1):page136_i101:a" )
			)
			( pin "R7G26.2"
				( objectStatus "@baseboard_fab2_lib.baseboard_fab2(sch_1):page136_i101:b" )
			)
			( pin "R7G28.1"
				( objectStatus "@baseboard_fab2_lib.baseboard_fab2(sch_1):page136_i102:a" )
			)
			( pin "R7G28.2"
				( objectStatus "@baseboard_fab2_lib.baseboard_fab2(sch_1):page136_i102:b" )
			)
			( pin "R8E20.1"
				( objectStatus "@baseboard_fab2_lib.baseboard_fab2(sch_1):page136_i126:a" )
			)
			( pin "R8E20.2"
				( objectStatus "@baseboard_fab2_lib.baseboard_fab2(sch_1):page136_i126:b" )
			)
			( pin "C8E8.1"
				( objectStatus "@baseboard_fab2_lib.baseboard_fab2(sch_1):page136_i128:a" )
			)
			( pin "C8E8.2"
				( objectStatus "@baseboard_fab2_lib.baseboard_fab2(sch_1):page136_i128:b" )
			)
			( pin "U8E3.2"
				( objectStatus "@baseboard_fab2_lib.baseboard_fab2(sch_1):page136_i130:a" )
			)
			( pin "U8E3.1"
				( objectStatus "@baseboard_fab2_lib.baseboard_fab2(sch_1):page136_i130:oe" )
			)
			( pin "U8E3.4"
				( objectStatus "@baseboard_fab2_lib.baseboard_fab2(sch_1):page136_i130:y" )
			)
			( pin "R8E14.1"
				( objectStatus "@baseboard_fab2_lib.baseboard_fab2(sch_1):page136_i133:a" )
			)
			( pin "R8E14.2"
				( objectStatus "@baseboard_fab2_lib.baseboard_fab2(sch_1):page136_i133:b" )
			)
			( pin "Q8E1.3"
				( objectStatus "@baseboard_fab2_lib.baseboard_fab2(sch_1):page136_i134:drn" )
			)
			( pin "Q8E1.1"
				( objectStatus "@baseboard_fab2_lib.baseboard_fab2(sch_1):page136_i134:gate" )
			)
			( pin "Q8E1.2"
				( objectStatus "@baseboard_fab2_lib.baseboard_fab2(sch_1):page136_i134:src" )
			)
			( pin "R7G31.1"
				( objectStatus "@baseboard_fab2_lib.baseboard_fab2(sch_1):page136_i139:a" )
			)
			( pin "R7G31.2"
				( objectStatus "@baseboard_fab2_lib.baseboard_fab2(sch_1):page136_i139:b" )
			)
			( pin "R8E16.1"
				( objectStatus "@baseboard_fab2_lib.baseboard_fab2(sch_1):page136_i140:a" )
			)
			( pin "R8E16.2"
				( objectStatus "@baseboard_fab2_lib.baseboard_fab2(sch_1):page136_i140:b" )
			)
			( pin "R2N28.1"
				( objectStatus "@baseboard_fab2_lib.baseboard_fab2(sch_1):page136_i147:a" )
			)
			( pin "R2N28.2"
				( objectStatus "@baseboard_fab2_lib.baseboard_fab2(sch_1):page136_i147:b" )
			)
			( pin "R7G29.1"
				( objectStatus "@baseboard_fab2_lib.baseboard_fab2(sch_1):page136_i148:a" )
			)
			( pin "R7G29.2"
				( objectStatus "@baseboard_fab2_lib.baseboard_fab2(sch_1):page136_i148:b" )
			)
			( pin "R7G27.1"
				( objectStatus "@baseboard_fab2_lib.baseboard_fab2(sch_1):page136_i155:a" )
			)
			( pin "R7G27.2"
				( objectStatus "@baseboard_fab2_lib.baseboard_fab2(sch_1):page136_i155:b" )
			)
			( pin "R3T14.1"
				( objectStatus "@baseboard_fab2_lib.baseboard_fab2(sch_1):page136_i156:a" )
			)
			( pin "R3T14.2"
				( objectStatus "@baseboard_fab2_lib.baseboard_fab2(sch_1):page136_i156:b" )
			)
			( pin "J7G3.1"
				( objectStatus "@baseboard_fab2_lib.baseboard_fab2(sch_1):page136_i174:io1" )
			)
			( pin "J7G3.2"
				( objectStatus "@baseboard_fab2_lib.baseboard_fab2(sch_1):page136_i174:io2" )
			)
			( pin "J7G3.3"
				( objectStatus "@baseboard_fab2_lib.baseboard_fab2(sch_1):page136_i174:io3" )
			)
			( pin "J7G3.4"
				( objectStatus "@baseboard_fab2_lib.baseboard_fab2(sch_1):page136_i174:io4" )
			)
			( pin "J7G3.5"
				( objectStatus "@baseboard_fab2_lib.baseboard_fab2(sch_1):page136_i174:io5" )
			)
			( pin "J7G3.6"
				( objectStatus "@baseboard_fab2_lib.baseboard_fab2(sch_1):page136_i174:io6" )
			)
			( pin "J7G3.7"
				( objectStatus "@baseboard_fab2_lib.baseboard_fab2(sch_1):page136_i174:io7" )
			)
			( pin "J7G3.8"
				( objectStatus "@baseboard_fab2_lib.baseboard_fab2(sch_1):page136_i174:io8" )
			)
			( pin "J7G3.9"
				( objectStatus "@baseboard_fab2_lib.baseboard_fab2(sch_1):page136_i174:io9" )
			)
			( pin "J7G3.10"
				( objectStatus "@baseboard_fab2_lib.baseboard_fab2(sch_1):page136_i174:io10" )
			)
			( pin "J7G3.11"
				( objectStatus "@baseboard_fab2_lib.baseboard_fab2(sch_1):page136_i174:io11" )
			)
			( pin "J7G3.12"
				( objectStatus "@baseboard_fab2_lib.baseboard_fab2(sch_1):page136_i174:io12" )
			)
			( pin "R7C11.1"
				( objectStatus "@baseboard_fab2_lib.baseboard_fab2(sch_1):page137_i11:a" )
			)
			( pin "R7C11.2"
				( objectStatus "@baseboard_fab2_lib.baseboard_fab2(sch_1):page137_i11:b" )
			)
			( pin "R7C10.1"
				( objectStatus "@baseboard_fab2_lib.baseboard_fab2(sch_1):page137_i13:a" )
			)
			( pin "R7C10.2"
				( objectStatus "@baseboard_fab2_lib.baseboard_fab2(sch_1):page137_i13:b" )
			)
			( pin "C7C19.1"
				( objectStatus "@baseboard_fab2_lib.baseboard_fab2(sch_1):page137_i14:a" )
			)
			( pin "C7C19.2"
				( objectStatus "@baseboard_fab2_lib.baseboard_fab2(sch_1):page137_i14:b" )
			)
			( pin "R1U63.1"
				( objectStatus "@baseboard_fab2_lib.baseboard_fab2(sch_1):page137_i15:a" )
			)
			( pin "R1U63.2"
				( objectStatus "@baseboard_fab2_lib.baseboard_fab2(sch_1):page137_i15:b" )
			)
			( pin "R3N4.1"
				( objectStatus "@baseboard_fab2_lib.baseboard_fab2(sch_1):page137_i19:a" )
			)
			( pin "R3N4.2"
				( objectStatus "@baseboard_fab2_lib.baseboard_fab2(sch_1):page137_i19:b" )
			)
			( pin "C3N32.1"
				( objectStatus "@baseboard_fab2_lib.baseboard_fab2(sch_1):page137_i20:a" )
			)
			( pin "C3N32.2"
				( objectStatus "@baseboard_fab2_lib.baseboard_fab2(sch_1):page137_i20:b" )
			)
			( pin "R7C13.1"
				( objectStatus "@baseboard_fab2_lib.baseboard_fab2(sch_1):page137_i67:a" )
			)
			( pin "R7C13.2"
				( objectStatus "@baseboard_fab2_lib.baseboard_fab2(sch_1):page137_i67:b" )
			)
			( pin "R1U64.1"
				( objectStatus "@baseboard_fab2_lib.baseboard_fab2(sch_1):page137_i69:a" )
			)
			( pin "R1U64.2"
				( objectStatus "@baseboard_fab2_lib.baseboard_fab2(sch_1):page137_i69:b" )
			)
			( pin "J9G1.1"
				( objectStatus "@baseboard_fab2_lib.baseboard_fab2(sch_1):page137_i128:io1" )
			)
			( pin "J9G1.2"
				( objectStatus "@baseboard_fab2_lib.baseboard_fab2(sch_1):page137_i128:io2" )
			)
			( pin "J9G1.3"
				( objectStatus "@baseboard_fab2_lib.baseboard_fab2(sch_1):page137_i128:io3" )
			)
			( pin "J9G1.4"
				( objectStatus "@baseboard_fab2_lib.baseboard_fab2(sch_1):page137_i128:io4" )
			)
			( pin "J9G1.5"
				( objectStatus "@baseboard_fab2_lib.baseboard_fab2(sch_1):page137_i128:io5" )
			)
			( pin "J9G1.6"
				( objectStatus "@baseboard_fab2_lib.baseboard_fab2(sch_1):page137_i128:io6" )
			)
			( pin "J9G1.7"
				( objectStatus "@baseboard_fab2_lib.baseboard_fab2(sch_1):page137_i128:io7" )
			)
			( pin "J9G1.8"
				( objectStatus "@baseboard_fab2_lib.baseboard_fab2(sch_1):page137_i128:io8" )
			)
			( pin "J9G1.9"
				( objectStatus "@baseboard_fab2_lib.baseboard_fab2(sch_1):page137_i128:io9" )
			)
			( pin "J9G1.10"
				( objectStatus "@baseboard_fab2_lib.baseboard_fab2(sch_1):page137_i128:io10" )
			)
			( pin "J9G1.11"
				( objectStatus "@baseboard_fab2_lib.baseboard_fab2(sch_1):page137_i128:io11" )
			)
			( pin "J9G1.12"
				( objectStatus "@baseboard_fab2_lib.baseboard_fab2(sch_1):page137_i128:io12" )
			)
			( pin "R2T53.1"
				( objectStatus "@baseboard_fab2_lib.baseboard_fab2(sch_1):page138_i83:a" )
			)
			( pin "R2T53.2"
				( objectStatus "@baseboard_fab2_lib.baseboard_fab2(sch_1):page138_i83:b" )
			)
			( pin "R2T54.1"
				( objectStatus "@baseboard_fab2_lib.baseboard_fab2(sch_1):page138_i84:a" )
			)
			( pin "R2T54.2"
				( objectStatus "@baseboard_fab2_lib.baseboard_fab2(sch_1):page138_i84:b" )
			)
			( pin "R8D17.1"
				( objectStatus "@baseboard_fab2_lib.baseboard_fab2(sch_1):page138_i87:a" )
			)
			( pin "R8D17.2"
				( objectStatus "@baseboard_fab2_lib.baseboard_fab2(sch_1):page138_i87:b" )
			)
			( pin "R8D15.1"
				( objectStatus "@baseboard_fab2_lib.baseboard_fab2(sch_1):page138_i88:a" )
			)
			( pin "R8D15.2"
				( objectStatus "@baseboard_fab2_lib.baseboard_fab2(sch_1):page138_i88:b" )
			)
			( pin "R2N8.1"
				( objectStatus "@baseboard_fab2_lib.baseboard_fab2(sch_1):page138_i89:a" )
			)
			( pin "R2N8.2"
				( objectStatus "@baseboard_fab2_lib.baseboard_fab2(sch_1):page138_i89:b" )
			)
			( pin "R2N5.1"
				( objectStatus "@baseboard_fab2_lib.baseboard_fab2(sch_1):page138_i90:a" )
			)
			( pin "R2N5.2"
				( objectStatus "@baseboard_fab2_lib.baseboard_fab2(sch_1):page138_i90:b" )
			)
			( pin "R8C16.1"
				( objectStatus "@baseboard_fab2_lib.baseboard_fab2(sch_1):page138_i91:a" )
			)
			( pin "R8C16.2"
				( objectStatus "@baseboard_fab2_lib.baseboard_fab2(sch_1):page138_i91:b" )
			)
			( pin "R8C15.1"
				( objectStatus "@baseboard_fab2_lib.baseboard_fab2(sch_1):page138_i92:a" )
			)
			( pin "R8C15.2"
				( objectStatus "@baseboard_fab2_lib.baseboard_fab2(sch_1):page138_i92:b" )
			)
			( pin "R8B24.1"
				( objectStatus "@baseboard_fab2_lib.baseboard_fab2(sch_1):page138_i95:a" )
			)
			( pin "R8B24.2"
				( objectStatus "@baseboard_fab2_lib.baseboard_fab2(sch_1):page138_i95:b" )
			)
			( pin "R8B26.1"
				( objectStatus "@baseboard_fab2_lib.baseboard_fab2(sch_1):page138_i96:a" )
			)
			( pin "R8B26.2"
				( objectStatus "@baseboard_fab2_lib.baseboard_fab2(sch_1):page138_i96:b" )
			)
			( pin "R2U11.1"
				( objectStatus "@baseboard_fab2_lib.baseboard_fab2(sch_1):page138_i97:a" )
			)
			( pin "R2U11.2"
				( objectStatus "@baseboard_fab2_lib.baseboard_fab2(sch_1):page138_i97:b" )
			)
			( pin "R2U3.1"
				( objectStatus "@baseboard_fab2_lib.baseboard_fab2(sch_1):page138_i98:a" )
			)
			( pin "R2U3.2"
				( objectStatus "@baseboard_fab2_lib.baseboard_fab2(sch_1):page138_i98:b" )
			)
			( pin "R2T55.1"
				( objectStatus "@baseboard_fab2_lib.baseboard_fab2(sch_1):page138_i116:a" )
			)
			( pin "R2T55.2"
				( objectStatus "@baseboard_fab2_lib.baseboard_fab2(sch_1):page138_i116:b" )
			)
			( pin "R2U8.1"
				( objectStatus "@baseboard_fab2_lib.baseboard_fab2(sch_1):page138_i158:a" )
			)
			( pin "R2U8.2"
				( objectStatus "@baseboard_fab2_lib.baseboard_fab2(sch_1):page138_i158:b" )
			)
			( pin "R2U12.1"
				( objectStatus "@baseboard_fab2_lib.baseboard_fab2(sch_1):page138_i159:a" )
			)
			( pin "R2U12.2"
				( objectStatus "@baseboard_fab2_lib.baseboard_fab2(sch_1):page138_i159:b" )
			)
			( pin "R2T56.1"
				( objectStatus "@baseboard_fab2_lib.baseboard_fab2(sch_1):page138_i160:a" )
			)
			( pin "R2T56.2"
				( objectStatus "@baseboard_fab2_lib.baseboard_fab2(sch_1):page138_i160:b" )
			)
			( pin "R8D3.1"
				( objectStatus "@baseboard_fab2_lib.baseboard_fab2(sch_1):page138_i161:a" )
			)
			( pin "R8D3.2"
				( objectStatus "@baseboard_fab2_lib.baseboard_fab2(sch_1):page138_i161:b" )
			)
			( pin "R8D6.1"
				( objectStatus "@baseboard_fab2_lib.baseboard_fab2(sch_1):page138_i162:a" )
			)
			( pin "R8D6.2"
				( objectStatus "@baseboard_fab2_lib.baseboard_fab2(sch_1):page138_i162:b" )
			)
			( pin "R8D7.1"
				( objectStatus "@baseboard_fab2_lib.baseboard_fab2(sch_1):page138_i163:a" )
			)
			( pin "R8D7.2"
				( objectStatus "@baseboard_fab2_lib.baseboard_fab2(sch_1):page138_i163:b" )
			)
			( pin "R8D4.1"
				( objectStatus "@baseboard_fab2_lib.baseboard_fab2(sch_1):page138_i164:a" )
			)
			( pin "R8D4.2"
				( objectStatus "@baseboard_fab2_lib.baseboard_fab2(sch_1):page138_i164:b" )
			)
			( pin "R2U9.1"
				( objectStatus "@baseboard_fab2_lib.baseboard_fab2(sch_1):page138_i165:a" )
			)
			( pin "R2U9.2"
				( objectStatus "@baseboard_fab2_lib.baseboard_fab2(sch_1):page138_i165:b" )
			)
			( pin "R2U6.1"
				( objectStatus "@baseboard_fab2_lib.baseboard_fab2(sch_1):page138_i166:a" )
			)
			( pin "R2U6.2"
				( objectStatus "@baseboard_fab2_lib.baseboard_fab2(sch_1):page138_i166:b" )
			)
			( pin "R8C20.1"
				( objectStatus "@baseboard_fab2_lib.baseboard_fab2(sch_1):page138_i167:a" )
			)
			( pin "R8C20.2"
				( objectStatus "@baseboard_fab2_lib.baseboard_fab2(sch_1):page138_i167:b" )
			)
			( pin "R8C14.1"
				( objectStatus "@baseboard_fab2_lib.baseboard_fab2(sch_1):page138_i168:a" )
			)
			( pin "R8C14.2"
				( objectStatus "@baseboard_fab2_lib.baseboard_fab2(sch_1):page138_i168:b" )
			)
			( pin "R8C11.1"
				( objectStatus "@baseboard_fab2_lib.baseboard_fab2(sch_1):page138_i169:a" )
			)
			( pin "R8C11.2"
				( objectStatus "@baseboard_fab2_lib.baseboard_fab2(sch_1):page138_i169:b" )
			)
			( pin "R8C12.1"
				( objectStatus "@baseboard_fab2_lib.baseboard_fab2(sch_1):page138_i170:a" )
			)
			( pin "R8C12.2"
				( objectStatus "@baseboard_fab2_lib.baseboard_fab2(sch_1):page138_i170:b" )
			)
			( pin "R2N20.1"
				( objectStatus "@baseboard_fab2_lib.baseboard_fab2(sch_1):page138_i171:a" )
			)
			( pin "R2N20.2"
				( objectStatus "@baseboard_fab2_lib.baseboard_fab2(sch_1):page138_i171:b" )
			)
			( pin "R8B27.1"
				( objectStatus "@baseboard_fab2_lib.baseboard_fab2(sch_1):page138_i173:a" )
			)
			( pin "R8B27.2"
				( objectStatus "@baseboard_fab2_lib.baseboard_fab2(sch_1):page138_i173:b" )
			)
			( pin "R8B28.1"
				( objectStatus "@baseboard_fab2_lib.baseboard_fab2(sch_1):page138_i174:a" )
			)
			( pin "R8B28.2"
				( objectStatus "@baseboard_fab2_lib.baseboard_fab2(sch_1):page138_i174:b" )
			)
			( pin "R2N21.1"
				( objectStatus "@baseboard_fab2_lib.baseboard_fab2(sch_1):page138_i175:a" )
			)
			( pin "R2N21.2"
				( objectStatus "@baseboard_fab2_lib.baseboard_fab2(sch_1):page138_i175:b" )
			)
			( pin "EU9E1.37"
				( objectStatus "@baseboard_fab2_lib.baseboard_fab2(sch_1):page139_i72:cbot" )
			)
			( pin "EU9E1.40"
				( objectStatus "@baseboard_fab2_lib.baseboard_fab2(sch_1):page139_i72:ctop" )
			)
			( pin "EU9E1.28"
				( objectStatus "@baseboard_fab2_lib.baseboard_fab2(sch_1):page139_i72:dev_off_n" )
			)
			( pin "EU9E1.65"
				( objectStatus "@baseboard_fab2_lib.baseboard_fab2(sch_1):page139_i72:gnd" )
			)
			( pin "EU9E1.19"
				( objectStatus "@baseboard_fab2_lib.baseboard_fab2(sch_1):page139_i72:jtag_clk" )
			)
			( pin "EU9E1.29"
				( objectStatus "@baseboard_fab2_lib.baseboard_fab2(sch_1):page139_i72:jtag_tdi" )
			)
			( pin "EU9E1.4"
				( objectStatus "@baseboard_fab2_lib.baseboard_fab2(sch_1):page139_i72:jtag_tdo" )
			)
			( pin "EU9E1.18"
				( objectStatus "@baseboard_fab2_lib.baseboard_fab2(sch_1):page139_i72:jtag_tms" )
			)
			( pin "EU9E1.1"
				( objectStatus "@baseboard_fab2_lib.baseboard_fab2(sch_1):page139_i72:lan_pwr_good" )
			)
			( pin "EU9E1.31"
				( objectStatus "@baseboard_fab2_lib.baseboard_fab2(sch_1):page139_i72:led0" )
			)
			( pin "EU9E1.30"
				( objectStatus "@baseboard_fab2_lib.baseboard_fab2(sch_1):page139_i72:led1" )
			)
			( pin "EU9E1.33"
				( objectStatus "@baseboard_fab2_lib.baseboard_fab2(sch_1):page139_i72:led2" )
			)
			( pin "EU9E1.57"
				( objectStatus "@baseboard_fab2_lib.baseboard_fab2(sch_1):page139_i72:mdi_minus0_sfp_i2c_data" )
			)
			( pin "EU9E1.54"
				( objectStatus "@baseboard_fab2_lib.baseboard_fab2(sch_1):page139_i72:mdi_minus1_srds_sig_det" )
			)
			( pin "EU9E1.52"
				( objectStatus "@baseboard_fab2_lib.baseboard_fab2(sch_1):page139_i72:mdi_minus2_setn" )
			)
			( pin "EU9E1.49"
				( objectStatus "@baseboard_fab2_lib.baseboard_fab2(sch_1):page139_i72:mdi_minus3_sern" )
			)
			( pin "EU9E1.58"
				( objectStatus "@baseboard_fab2_lib.baseboard_fab2(sch_1):page139_i72:mdi_plus0_nc" )
			)
			( pin "EU9E1.55"
				( objectStatus "@baseboard_fab2_lib.baseboard_fab2(sch_1):page139_i72:mdi_plus1_sfp_i2c_clk" )
			)
			( pin "EU9E1.53"
				( objectStatus "@baseboard_fab2_lib.baseboard_fab2(sch_1):page139_i72:mdi_plus2_setp" )
			)
			( pin "EU9E1.50"
				( objectStatus "@baseboard_fab2_lib.baseboard_fab2(sch_1):page139_i72:mdi_plus3_serp" )
			)
			( pin "EU9E1.22"
				( objectStatus "@baseboard_fab2_lib.baseboard_fab2(sch_1):page139_i72:nc" )
			)
			( pin "EU9E1.43"
				( objectStatus "@baseboard_fab2_lib.baseboard_fab2(sch_1):page139_i72:nc_si_arb_in" )
			)
			( pin "EU9E1.44"
				( objectStatus "@baseboard_fab2_lib.baseboard_fab2(sch_1):page139_i72:nc_si_arb_out" )
			)
			( pin "EU9E1.2"
				( objectStatus "@baseboard_fab2_lib.baseboard_fab2(sch_1):page139_i72:nc_si_clk_in" )
			)
			( pin "EU9E1.3"
				( objectStatus "@baseboard_fab2_lib.baseboard_fab2(sch_1):page139_i72:nc_si_crs_dv" )
			)
			( pin "EU9E1.6"
				( objectStatus "@baseboard_fab2_lib.baseboard_fab2(sch_1):page139_i72:nc_si_rxd0" )
			)
			( pin "EU9E1.5"
				( objectStatus "@baseboard_fab2_lib.baseboard_fab2(sch_1):page139_i72:nc_si_rxd1" )
			)
			( pin "EU9E1.7"
				( objectStatus "@baseboard_fab2_lib.baseboard_fab2(sch_1):page139_i72:nc_si_tx_en" )
			)
			( pin "EU9E1.9"
				( objectStatus "@baseboard_fab2_lib.baseboard_fab2(sch_1):page139_i72:nc_si_txd0" )
			)
			( pin "EU9E1.8"
				( objectStatus "@baseboard_fab2_lib.baseboard_fab2(sch_1):page139_i72:nc_si_txd1" )
			)
			( pin "EU9E1.15"
				( objectStatus "@baseboard_fab2_lib.baseboard_fab2(sch_1):page139_i72:nvm_cs_n" )
			)
			( pin "EU9E1.12"
				( objectStatus "@baseboard_fab2_lib.baseboard_fab2(sch_1):page139_i72:nvm_si" )
			)
			( pin "EU9E1.13"
				( objectStatus "@baseboard_fab2_lib.baseboard_fab2(sch_1):page139_i72:nvm_sk" )
			)
			( pin "EU9E1.14"
				( objectStatus "@baseboard_fab2_lib.baseboard_fab2(sch_1):page139_i72:nvm_so" )
			)
			( pin "EU9E1.23"
				( objectStatus "@baseboard_fab2_lib.baseboard_fab2(sch_1):page139_i72:pe_rn" )
			)
			( pin "EU9E1.24"
				( objectStatus "@baseboard_fab2_lib.baseboard_fab2(sch_1):page139_i72:pe_rp" )
			)
			( pin "EU9E1.17"
				( objectStatus "@baseboard_fab2_lib.baseboard_fab2(sch_1):page139_i72:pe_rst_n" )
			)
			( pin "EU9E1.20"
				( objectStatus "@baseboard_fab2_lib.baseboard_fab2(sch_1):page139_i72:pe_tn" )
			)
			( pin "EU9E1.21"
				( objectStatus "@baseboard_fab2_lib.baseboard_fab2(sch_1):page139_i72:pe_tp" )
			)
			( pin "EU9E1.16"
				( objectStatus "@baseboard_fab2_lib.baseboard_fab2(sch_1):page139_i72:pe_wake_n" )
			)
			( pin "EU9E1.25"
				( objectStatus "@baseboard_fab2_lib.baseboard_fab2(sch_1):page139_i72:peclkn" )
			)
			( pin "EU9E1.26"
				( objectStatus "@baseboard_fab2_lib.baseboard_fab2(sch_1):page139_i72:peclkp" )
			)
			( pin "EU9E1.48"
				( objectStatus "@baseboard_fab2_lib.baseboard_fab2(sch_1):page139_i72:rset" )
			)
			( pin "EU9E1.63"
				( objectStatus "@baseboard_fab2_lib.baseboard_fab2(sch_1):page139_i72:sdp0" )
			)
			( pin "EU9E1.61"
				( objectStatus "@baseboard_fab2_lib.baseboard_fab2(sch_1):page139_i72:sdp1_pcie_dis_sdp1" )
			)
			( pin "EU9E1.62"
				( objectStatus "@baseboard_fab2_lib.baseboard_fab2(sch_1):page139_i72:sdp2" )
			)
			( pin "EU9E1.60"
				( objectStatus "@baseboard_fab2_lib.baseboard_fab2(sch_1):page139_i72:sdp3" )
			)
			( pin "EU9E1.35"
				( objectStatus "@baseboard_fab2_lib.baseboard_fab2(sch_1):page139_i72:smb_alrt_n" )
			)
			( pin "EU9E1.34"
				( objectStatus "@baseboard_fab2_lib.baseboard_fab2(sch_1):page139_i72:smb_clk" )
			)
			( pin "EU9E1.36"
				( objectStatus "@baseboard_fab2_lib.baseboard_fab2(sch_1):page139_i72:smb_data" )
			)
			( pin "EU9E1.59"
				( objectStatus "@baseboard_fab2_lib.baseboard_fab2(sch_1):page139_i72:vdd0p9(0)" )
			)
			( pin "EU9E1.32"
				( objectStatus "@baseboard_fab2_lib.baseboard_fab2(sch_1):page139_i72:vdd0p9(1)" )
			)
			( pin "EU9E1.11"
				( objectStatus "@baseboard_fab2_lib.baseboard_fab2(sch_1):page139_i72:vdd0p9(2)" )
			)
			( pin "EU9E1.42"
				( objectStatus "@baseboard_fab2_lib.baseboard_fab2(sch_1):page139_i72:vdd0p9(3)" )
			)
			( pin "EU9E1.38"
				( objectStatus "@baseboard_fab2_lib.baseboard_fab2(sch_1):page139_i72:vdd0p9_out" )
			)
			( pin "EU9E1.56"
				( objectStatus "@baseboard_fab2_lib.baseboard_fab2(sch_1):page139_i72:vdd1p5(0)" )
			)
			( pin "EU9E1.47"
				( objectStatus "@baseboard_fab2_lib.baseboard_fab2(sch_1):page139_i72:vdd1p5(1)" )
			)
			( pin "EU9E1.39"
				( objectStatus "@baseboard_fab2_lib.baseboard_fab2(sch_1):page139_i72:vdd1p5_out" )
			)
			( pin "EU9E1.64"
				( objectStatus "@baseboard_fab2_lib.baseboard_fab2(sch_1):page139_i72:vdd3p3(0)" )
			)
			( pin "EU9E1.51"
				( objectStatus "@baseboard_fab2_lib.baseboard_fab2(sch_1):page139_i72:vdd3p3(1)" )
			)
			( pin "EU9E1.41"
				( objectStatus "@baseboard_fab2_lib.baseboard_fab2(sch_1):page139_i72:vdd3p3(2)" )
			)
			( pin "EU9E1.27"
				( objectStatus "@baseboard_fab2_lib.baseboard_fab2(sch_1):page139_i72:vdd3p3(3)" )
			)
			( pin "EU9E1.10"
				( objectStatus "@baseboard_fab2_lib.baseboard_fab2(sch_1):page139_i72:vdd3p3(4)" )
			)
			( pin "EU9E1.46"
				( objectStatus "@baseboard_fab2_lib.baseboard_fab2(sch_1):page139_i72:xtal1" )
			)
			( pin "EU9E1.45"
				( objectStatus "@baseboard_fab2_lib.baseboard_fab2(sch_1):page139_i72:xtal2" )
			)
			( pin "C9E7.1"
				( objectStatus "@baseboard_fab2_lib.baseboard_fab2(sch_1):page139_i76:a" )
			)
			( pin "C9E7.2"
				( objectStatus "@baseboard_fab2_lib.baseboard_fab2(sch_1):page139_i76:b" )
			)
			( pin "C9E5.1"
				( objectStatus "@baseboard_fab2_lib.baseboard_fab2(sch_1):page139_i87:a" )
			)
			( pin "C9E5.2"
				( objectStatus "@baseboard_fab2_lib.baseboard_fab2(sch_1):page139_i87:b" )
			)
			( pin "C9E4.1"
				( objectStatus "@baseboard_fab2_lib.baseboard_fab2(sch_1):page139_i88:a" )
			)
			( pin "C9E4.2"
				( objectStatus "@baseboard_fab2_lib.baseboard_fab2(sch_1):page139_i88:b" )
			)
			( pin "C2M23.1"
				( objectStatus "@baseboard_fab2_lib.baseboard_fab2(sch_1):page139_i89:a" )
			)
			( pin "C2M23.2"
				( objectStatus "@baseboard_fab2_lib.baseboard_fab2(sch_1):page139_i89:b" )
			)
			( pin "C2M24.1"
				( objectStatus "@baseboard_fab2_lib.baseboard_fab2(sch_1):page139_i90:a" )
			)
			( pin "C2M24.2"
				( objectStatus "@baseboard_fab2_lib.baseboard_fab2(sch_1):page139_i90:b" )
			)
			( pin "Y9E1.1"
				( objectStatus "@baseboard_fab2_lib.baseboard_fab2(sch_1):page139_i109:a" )
			)
			( pin "Y9E1.3"
				( objectStatus "@baseboard_fab2_lib.baseboard_fab2(sch_1):page139_i109:b" )
			)
			( pin "R9E20.1"
				( objectStatus "@baseboard_fab2_lib.baseboard_fab2(sch_1):page139_i110:a" )
			)
			( pin "R9E20.2"
				( objectStatus "@baseboard_fab2_lib.baseboard_fab2(sch_1):page139_i110:b" )
			)
			( pin "C9E8.1"
				( objectStatus "@baseboard_fab2_lib.baseboard_fab2(sch_1):page139_i111:a" )
			)
			( pin "C9E8.2"
				( objectStatus "@baseboard_fab2_lib.baseboard_fab2(sch_1):page139_i111:b" )
			)
			( pin "C9E9.1"
				( objectStatus "@baseboard_fab2_lib.baseboard_fab2(sch_1):page139_i112:a" )
			)
			( pin "C9E9.2"
				( objectStatus "@baseboard_fab2_lib.baseboard_fab2(sch_1):page139_i112:b" )
			)
			( pin "R9E9.1"
				( objectStatus "@baseboard_fab2_lib.baseboard_fab2(sch_1):page139_i128:a" )
			)
			( pin "R9E9.2"
				( objectStatus "@baseboard_fab2_lib.baseboard_fab2(sch_1):page139_i128:b" )
			)
			( pin "R9E5.1"
				( objectStatus "@baseboard_fab2_lib.baseboard_fab2(sch_1):page139_i129:a" )
			)
			( pin "R9E5.2"
				( objectStatus "@baseboard_fab2_lib.baseboard_fab2(sch_1):page139_i129:b" )
			)
			( pin "R9E8.1"
				( objectStatus "@baseboard_fab2_lib.baseboard_fab2(sch_1):page139_i130:a" )
			)
			( pin "R9E8.2"
				( objectStatus "@baseboard_fab2_lib.baseboard_fab2(sch_1):page139_i130:b" )
			)
			( pin "C1T4.1"
				( objectStatus "@baseboard_fab2_lib.baseboard_fab2(sch_1):page139_i134:a" )
			)
			( pin "C1T4.2"
				( objectStatus "@baseboard_fab2_lib.baseboard_fab2(sch_1):page139_i134:b" )
			)
			( pin "C1R30.1"
				( objectStatus "@baseboard_fab2_lib.baseboard_fab2(sch_1):page139_i135:a" )
			)
			( pin "C1R30.2"
				( objectStatus "@baseboard_fab2_lib.baseboard_fab2(sch_1):page139_i135:b" )
			)
			( pin "C1R22.1"
				( objectStatus "@baseboard_fab2_lib.baseboard_fab2(sch_1):page139_i136:a" )
			)
			( pin "C1R22.2"
				( objectStatus "@baseboard_fab2_lib.baseboard_fab2(sch_1):page139_i136:b" )
			)
			( pin "C9F2.1"
				( objectStatus "@baseboard_fab2_lib.baseboard_fab2(sch_1):page139_i140:a" )
			)
			( pin "C9F2.2"
				( objectStatus "@baseboard_fab2_lib.baseboard_fab2(sch_1):page139_i140:b" )
			)
			( pin "C1R13.1"
				( objectStatus "@baseboard_fab2_lib.baseboard_fab2(sch_1):page139_i142:a" )
			)
			( pin "C1R13.2"
				( objectStatus "@baseboard_fab2_lib.baseboard_fab2(sch_1):page139_i142:b" )
			)
			( pin "C1R20.1"
				( objectStatus "@baseboard_fab2_lib.baseboard_fab2(sch_1):page139_i143:a" )
			)
			( pin "C1R20.2"
				( objectStatus "@baseboard_fab2_lib.baseboard_fab2(sch_1):page139_i143:b" )
			)
			( pin "C1T3.1"
				( objectStatus "@baseboard_fab2_lib.baseboard_fab2(sch_1):page139_i144:a" )
			)
			( pin "C1T3.2"
				( objectStatus "@baseboard_fab2_lib.baseboard_fab2(sch_1):page139_i144:b" )
			)
			( pin "C1R14.1"
				( objectStatus "@baseboard_fab2_lib.baseboard_fab2(sch_1):page139_i145:a" )
			)
			( pin "C1R14.2"
				( objectStatus "@baseboard_fab2_lib.baseboard_fab2(sch_1):page139_i145:b" )
			)
			( pin "C1R21.1"
				( objectStatus "@baseboard_fab2_lib.baseboard_fab2(sch_1):page139_i146:a" )
			)
			( pin "C1R21.2"
				( objectStatus "@baseboard_fab2_lib.baseboard_fab2(sch_1):page139_i146:b" )
			)
			( pin "C1R26.1"
				( objectStatus "@baseboard_fab2_lib.baseboard_fab2(sch_1):page139_i149:a" )
			)
			( pin "C1R26.2"
				( objectStatus "@baseboard_fab2_lib.baseboard_fab2(sch_1):page139_i149:b" )
			)
			( pin "C1R29.1"
				( objectStatus "@baseboard_fab2_lib.baseboard_fab2(sch_1):page139_i150:a" )
			)
			( pin "C1R29.2"
				( objectStatus "@baseboard_fab2_lib.baseboard_fab2(sch_1):page139_i150:b" )
			)
			( pin "C1R19.1"
				( objectStatus "@baseboard_fab2_lib.baseboard_fab2(sch_1):page139_i151:a" )
			)
			( pin "C1R19.2"
				( objectStatus "@baseboard_fab2_lib.baseboard_fab2(sch_1):page139_i151:b" )
			)
			( pin "C1R31.1"
				( objectStatus "@baseboard_fab2_lib.baseboard_fab2(sch_1):page139_i152:a" )
			)
			( pin "C1R31.2"
				( objectStatus "@baseboard_fab2_lib.baseboard_fab2(sch_1):page139_i152:b" )
			)
			( pin "C1R17.1"
				( objectStatus "@baseboard_fab2_lib.baseboard_fab2(sch_1):page139_i153:a" )
			)
			( pin "C1R17.2"
				( objectStatus "@baseboard_fab2_lib.baseboard_fab2(sch_1):page139_i153:b" )
			)
			( pin "C9E6.1"
				( objectStatus "@baseboard_fab2_lib.baseboard_fab2(sch_1):page139_i155:a" )
			)
			( pin "C9E6.2"
				( objectStatus "@baseboard_fab2_lib.baseboard_fab2(sch_1):page139_i155:b" )
			)
			( pin "C1R18.1"
				( objectStatus "@baseboard_fab2_lib.baseboard_fab2(sch_1):page139_i157:a" )
			)
			( pin "C1R18.2"
				( objectStatus "@baseboard_fab2_lib.baseboard_fab2(sch_1):page139_i157:b" )
			)
			( pin "C1T5.1"
				( objectStatus "@baseboard_fab2_lib.baseboard_fab2(sch_1):page139_i158:a" )
			)
			( pin "C1T5.2"
				( objectStatus "@baseboard_fab2_lib.baseboard_fab2(sch_1):page139_i158:b" )
			)
			( pin "C1R24.1"
				( objectStatus "@baseboard_fab2_lib.baseboard_fab2(sch_1):page139_i159:a" )
			)
			( pin "C1R24.2"
				( objectStatus "@baseboard_fab2_lib.baseboard_fab2(sch_1):page139_i159:b" )
			)
			( pin "C1R15.1"
				( objectStatus "@baseboard_fab2_lib.baseboard_fab2(sch_1):page139_i160:a" )
			)
			( pin "C1R15.2"
				( objectStatus "@baseboard_fab2_lib.baseboard_fab2(sch_1):page139_i160:b" )
			)
			( pin "C1R16.1"
				( objectStatus "@baseboard_fab2_lib.baseboard_fab2(sch_1):page139_i161:a" )
			)
			( pin "C1R16.2"
				( objectStatus "@baseboard_fab2_lib.baseboard_fab2(sch_1):page139_i161:b" )
			)
			( pin "C9E1.1"
				( objectStatus "@baseboard_fab2_lib.baseboard_fab2(sch_1):page139_i163:a" )
			)
			( pin "C9E1.2"
				( objectStatus "@baseboard_fab2_lib.baseboard_fab2(sch_1):page139_i163:b" )
			)
			( pin "R9F5.1"
				( objectStatus "@baseboard_fab2_lib.baseboard_fab2(sch_1):page139_i173:a" )
			)
			( pin "R9F5.2"
				( objectStatus "@baseboard_fab2_lib.baseboard_fab2(sch_1):page139_i173:b" )
			)
			( pin "R9E23.1"
				( objectStatus "@baseboard_fab2_lib.baseboard_fab2(sch_1):page139_i174:a" )
			)
			( pin "R9E23.2"
				( objectStatus "@baseboard_fab2_lib.baseboard_fab2(sch_1):page139_i174:b" )
			)
			( pin "R9E2.1"
				( objectStatus "@baseboard_fab2_lib.baseboard_fab2(sch_1):page139_i177:a" )
			)
			( pin "R9E2.2"
				( objectStatus "@baseboard_fab2_lib.baseboard_fab2(sch_1):page139_i177:b" )
			)
			( pin "R9E3.1"
				( objectStatus "@baseboard_fab2_lib.baseboard_fab2(sch_1):page139_i178:a" )
			)
			( pin "R9E3.2"
				( objectStatus "@baseboard_fab2_lib.baseboard_fab2(sch_1):page139_i178:b" )
			)
			( pin "R9E1.1"
				( objectStatus "@baseboard_fab2_lib.baseboard_fab2(sch_1):page139_i179:a" )
			)
			( pin "R9E1.2"
				( objectStatus "@baseboard_fab2_lib.baseboard_fab2(sch_1):page139_i179:b" )
			)
			( pin "R9E22.1"
				( objectStatus "@baseboard_fab2_lib.baseboard_fab2(sch_1):page139_i181:a" )
			)
			( pin "R9E22.2"
				( objectStatus "@baseboard_fab2_lib.baseboard_fab2(sch_1):page139_i181:b" )
			)
			( pin "R9E7.1"
				( objectStatus "@baseboard_fab2_lib.baseboard_fab2(sch_1):page139_i193:a" )
			)
			( pin "R9E7.2"
				( objectStatus "@baseboard_fab2_lib.baseboard_fab2(sch_1):page139_i193:b" )
			)
			( pin "R1R1.1"
				( objectStatus "@baseboard_fab2_lib.baseboard_fab2(sch_1):page139_i195:a" )
			)
			( pin "R1R1.2"
				( objectStatus "@baseboard_fab2_lib.baseboard_fab2(sch_1):page139_i195:b" )
			)
			( pin "R9E4.1"
				( objectStatus "@baseboard_fab2_lib.baseboard_fab2(sch_1):page139_i200:a" )
			)
			( pin "R9E4.2"
				( objectStatus "@baseboard_fab2_lib.baseboard_fab2(sch_1):page139_i200:b" )
			)
			( pin "R9E18.1"
				( objectStatus "@baseboard_fab2_lib.baseboard_fab2(sch_1):page139_i201:a" )
			)
			( pin "R9E18.2"
				( objectStatus "@baseboard_fab2_lib.baseboard_fab2(sch_1):page139_i201:b" )
			)
			( pin "R9E13.1"
				( objectStatus "@baseboard_fab2_lib.baseboard_fab2(sch_1):page139_i212:a" )
			)
			( pin "R9E13.2"
				( objectStatus "@baseboard_fab2_lib.baseboard_fab2(sch_1):page139_i212:b" )
			)
			( pin "R1R12.1"
				( objectStatus "@baseboard_fab2_lib.baseboard_fab2(sch_1):page139_i213:a" )
			)
			( pin "R1R12.2"
				( objectStatus "@baseboard_fab2_lib.baseboard_fab2(sch_1):page139_i213:b" )
			)
			( pin "R1T1.1"
				( objectStatus "@baseboard_fab2_lib.baseboard_fab2(sch_1):page139_i214:a" )
			)
			( pin "R1T1.2"
				( objectStatus "@baseboard_fab2_lib.baseboard_fab2(sch_1):page139_i214:b" )
			)
			( pin "R9F1.1"
				( objectStatus "@baseboard_fab2_lib.baseboard_fab2(sch_1):page139_i225:a" )
			)
			( pin "R9F1.2"
				( objectStatus "@baseboard_fab2_lib.baseboard_fab2(sch_1):page139_i225:b" )
			)
			( pin "R9E19.1"
				( objectStatus "@baseboard_fab2_lib.baseboard_fab2(sch_1):page139_i228:a" )
			)
			( pin "R9E19.2"
				( objectStatus "@baseboard_fab2_lib.baseboard_fab2(sch_1):page139_i228:b" )
			)
			( pin "R9E17.1"
				( objectStatus "@baseboard_fab2_lib.baseboard_fab2(sch_1):page139_i229:a" )
			)
			( pin "R9E17.2"
				( objectStatus "@baseboard_fab2_lib.baseboard_fab2(sch_1):page139_i229:b" )
			)
			( pin "R9E16.1"
				( objectStatus "@baseboard_fab2_lib.baseboard_fab2(sch_1):page139_i235:a" )
			)
			( pin "R9E16.2"
				( objectStatus "@baseboard_fab2_lib.baseboard_fab2(sch_1):page139_i235:b" )
			)
			( pin "R1R15.1"
				( objectStatus "@baseboard_fab2_lib.baseboard_fab2(sch_1):page139_i237:a" )
			)
			( pin "R1R15.2"
				( objectStatus "@baseboard_fab2_lib.baseboard_fab2(sch_1):page139_i237:b" )
			)
			( pin "R1T32.1"
				( objectStatus "@baseboard_fab2_lib.baseboard_fab2(sch_1):page139_i238:a" )
			)
			( pin "R1T32.2"
				( objectStatus "@baseboard_fab2_lib.baseboard_fab2(sch_1):page139_i238:b" )
			)
			( pin "R1T34.1"
				( objectStatus "@baseboard_fab2_lib.baseboard_fab2(sch_1):page139_i239:a" )
			)
			( pin "R1T34.2"
				( objectStatus "@baseboard_fab2_lib.baseboard_fab2(sch_1):page139_i239:b" )
			)
			( pin "R1T33.1"
				( objectStatus "@baseboard_fab2_lib.baseboard_fab2(sch_1):page139_i240:a" )
			)
			( pin "R1T33.2"
				( objectStatus "@baseboard_fab2_lib.baseboard_fab2(sch_1):page139_i240:b" )
			)
			( pin "C9E12.1"
				( objectStatus "@baseboard_fab2_lib.baseboard_fab2(sch_1):page139_i241:a" )
			)
			( pin "C9E12.2"
				( objectStatus "@baseboard_fab2_lib.baseboard_fab2(sch_1):page139_i241:b" )
			)
			( pin "U9E1.6"
				( objectStatus "@baseboard_fab2_lib.baseboard_fab2(sch_1):page140_i1:c" )
			)
			( pin "U9E1.5"
				( objectStatus "@baseboard_fab2_lib.baseboard_fab2(sch_1):page140_i1:dq0" )
			)
			( pin "U9E1.2"
				( objectStatus "@baseboard_fab2_lib.baseboard_fab2(sch_1):page140_i1:dq1" )
			)
			( pin "U9E1.7"
				( objectStatus "@baseboard_fab2_lib.baseboard_fab2(sch_1):page140_i1:reset_n" )
			)
			( pin "U9E1.1"
				( objectStatus "@baseboard_fab2_lib.baseboard_fab2(sch_1):page140_i1:s_n" )
			)
			( pin "U9E1.8"
				( objectStatus "@baseboard_fab2_lib.baseboard_fab2(sch_1):page140_i1:vcc" )
			)
			( pin "U9E1.4"
				( objectStatus "@baseboard_fab2_lib.baseboard_fab2(sch_1):page140_i1:vss" )
			)
			( pin "U9E1.3"
				( objectStatus "@baseboard_fab2_lib.baseboard_fab2(sch_1):page140_i1:w_n" )
			)
			( pin "C1R25.1"
				( objectStatus "@baseboard_fab2_lib.baseboard_fab2(sch_1):page140_i3:a" )
			)
			( pin "C1R25.2"
				( objectStatus "@baseboard_fab2_lib.baseboard_fab2(sch_1):page140_i3:b" )
			)
			( pin "R1R9.1"
				( objectStatus "@baseboard_fab2_lib.baseboard_fab2(sch_1):page140_i10:a" )
			)
			( pin "R1R9.2"
				( objectStatus "@baseboard_fab2_lib.baseboard_fab2(sch_1):page140_i10:b" )
			)
			( pin "R1R3.1"
				( objectStatus "@baseboard_fab2_lib.baseboard_fab2(sch_1):page140_i11:a" )
			)
			( pin "R1R3.2"
				( objectStatus "@baseboard_fab2_lib.baseboard_fab2(sch_1):page140_i11:b" )
			)
			( pin "R1R7.1"
				( objectStatus "@baseboard_fab2_lib.baseboard_fab2(sch_1):page140_i12:a" )
			)
			( pin "R1R7.2"
				( objectStatus "@baseboard_fab2_lib.baseboard_fab2(sch_1):page140_i12:b" )
			)
			( pin "R1R6.1"
				( objectStatus "@baseboard_fab2_lib.baseboard_fab2(sch_1):page140_i14:a" )
			)
			( pin "R1R6.2"
				( objectStatus "@baseboard_fab2_lib.baseboard_fab2(sch_1):page140_i14:b" )
			)
			( pin "R9E6.1"
				( objectStatus "@baseboard_fab2_lib.baseboard_fab2(sch_1):page140_i17:a" )
			)
			( pin "R9E6.2"
				( objectStatus "@baseboard_fab2_lib.baseboard_fab2(sch_1):page140_i17:b" )
			)
			( pin "R9G3.1"
				( objectStatus "@baseboard_fab2_lib.baseboard_fab2(sch_1):page141_i28:a" )
			)
			( pin "R9G3.2"
				( objectStatus "@baseboard_fab2_lib.baseboard_fab2(sch_1):page141_i28:b" )
			)
			( pin "R9G2.1"
				( objectStatus "@baseboard_fab2_lib.baseboard_fab2(sch_1):page141_i30:a" )
			)
			( pin "R9G2.2"
				( objectStatus "@baseboard_fab2_lib.baseboard_fab2(sch_1):page141_i30:b" )
			)
			( pin "C9G7.1"
				( objectStatus "@baseboard_fab2_lib.baseboard_fab2(sch_1):page141_i33:a" )
			)
			( pin "C9G7.2"
				( objectStatus "@baseboard_fab2_lib.baseboard_fab2(sch_1):page141_i33:b" )
			)
			( pin "C9G2.1"
				( objectStatus "@baseboard_fab2_lib.baseboard_fab2(sch_1):page141_i36:a" )
			)
			( pin "C9G2.2"
				( objectStatus "@baseboard_fab2_lib.baseboard_fab2(sch_1):page141_i36:b" )
			)
			( pin "C9G4.1"
				( objectStatus "@baseboard_fab2_lib.baseboard_fab2(sch_1):page141_i46:a" )
			)
			( pin "C9G4.2"
				( objectStatus "@baseboard_fab2_lib.baseboard_fab2(sch_1):page141_i46:b" )
			)
			( pin "C9G6.1"
				( objectStatus "@baseboard_fab2_lib.baseboard_fab2(sch_1):page141_i47:a" )
			)
			( pin "C9G6.2"
				( objectStatus "@baseboard_fab2_lib.baseboard_fab2(sch_1):page141_i47:b" )
			)
			( pin "C9G5.1"
				( objectStatus "@baseboard_fab2_lib.baseboard_fab2(sch_1):page141_i48:a" )
			)
			( pin "C9G5.2"
				( objectStatus "@baseboard_fab2_lib.baseboard_fab2(sch_1):page141_i48:b" )
			)
			( pin "R9G1.1"
				( objectStatus "@baseboard_fab2_lib.baseboard_fab2(sch_1):page141_i54:a" )
			)
			( pin "R9G1.2"
				( objectStatus "@baseboard_fab2_lib.baseboard_fab2(sch_1):page141_i54:b" )
			)
			( pin "R9G4.1"
				( objectStatus "@baseboard_fab2_lib.baseboard_fab2(sch_1):page141_i56:a" )
			)
			( pin "R9G4.2"
				( objectStatus "@baseboard_fab2_lib.baseboard_fab2(sch_1):page141_i56:b" )
			)
			( pin "C9G1.1"
				( objectStatus "@baseboard_fab2_lib.baseboard_fab2(sch_1):page141_i58:a" )
			)
			( pin "C9G1.2"
				( objectStatus "@baseboard_fab2_lib.baseboard_fab2(sch_1):page141_i58:b" )
			)
			( pin "C9G3.1"
				( objectStatus "@baseboard_fab2_lib.baseboard_fab2(sch_1):page141_i59:a" )
			)
			( pin "C9G3.2"
				( objectStatus "@baseboard_fab2_lib.baseboard_fab2(sch_1):page141_i59:b" )
			)
			( pin "C9F22.1"
				( objectStatus "@baseboard_fab2_lib.baseboard_fab2(sch_1):page141_i60:a" )
			)
			( pin "C9F22.2"
				( objectStatus "@baseboard_fab2_lib.baseboard_fab2(sch_1):page141_i60:b" )
			)
			( pin "R9G9.1"
				( objectStatus "@baseboard_fab2_lib.baseboard_fab2(sch_1):page141_i75:a" )
			)
			( pin "R9G9.2"
				( objectStatus "@baseboard_fab2_lib.baseboard_fab2(sch_1):page141_i75:b" )
			)
			( pin "R9G11.1"
				( objectStatus "@baseboard_fab2_lib.baseboard_fab2(sch_1):page141_i76:a" )
			)
			( pin "R9G11.2"
				( objectStatus "@baseboard_fab2_lib.baseboard_fab2(sch_1):page141_i76:b" )
			)
			( pin "R9G18.1"
				( objectStatus "@baseboard_fab2_lib.baseboard_fab2(sch_1):page141_i77:a" )
			)
			( pin "R9G18.2"
				( objectStatus "@baseboard_fab2_lib.baseboard_fab2(sch_1):page141_i77:b" )
			)
			( pin "R9G17.1"
				( objectStatus "@baseboard_fab2_lib.baseboard_fab2(sch_1):page141_i78:a" )
			)
			( pin "R9G17.2"
				( objectStatus "@baseboard_fab2_lib.baseboard_fab2(sch_1):page141_i78:b" )
			)
			( pin "R9G19.1"
				( objectStatus "@baseboard_fab2_lib.baseboard_fab2(sch_1):page141_i79:a" )
			)
			( pin "R9G19.2"
				( objectStatus "@baseboard_fab2_lib.baseboard_fab2(sch_1):page141_i79:b" )
			)
			( pin "R9G20.1"
				( objectStatus "@baseboard_fab2_lib.baseboard_fab2(sch_1):page141_i80:a" )
			)
			( pin "R9G20.2"
				( objectStatus "@baseboard_fab2_lib.baseboard_fab2(sch_1):page141_i80:b" )
			)
			( pin "R9G24.1"
				( objectStatus "@baseboard_fab2_lib.baseboard_fab2(sch_1):page141_i81:a" )
			)
			( pin "R9G24.2"
				( objectStatus "@baseboard_fab2_lib.baseboard_fab2(sch_1):page141_i81:b" )
			)
			( pin "R9G22.1"
				( objectStatus "@baseboard_fab2_lib.baseboard_fab2(sch_1):page141_i82:a" )
			)
			( pin "R9G22.2"
				( objectStatus "@baseboard_fab2_lib.baseboard_fab2(sch_1):page141_i82:b" )
			)
			( pin "C9G9.1"
				( objectStatus "@baseboard_fab2_lib.baseboard_fab2(sch_1):page141_i99:a" )
			)
			( pin "C9G9.2"
				( objectStatus "@baseboard_fab2_lib.baseboard_fab2(sch_1):page141_i99:b" )
			)
			( pin "C9G12.1"
				( objectStatus "@baseboard_fab2_lib.baseboard_fab2(sch_1):page141_i100:a" )
			)
			( pin "C9G12.2"
				( objectStatus "@baseboard_fab2_lib.baseboard_fab2(sch_1):page141_i100:b" )
			)
			( pin "C9G16.1"
				( objectStatus "@baseboard_fab2_lib.baseboard_fab2(sch_1):page141_i101:a" )
			)
			( pin "C9G16.2"
				( objectStatus "@baseboard_fab2_lib.baseboard_fab2(sch_1):page141_i101:b" )
			)
			( pin "C9G13.1"
				( objectStatus "@baseboard_fab2_lib.baseboard_fab2(sch_1):page141_i102:a" )
			)
			( pin "C9G13.2"
				( objectStatus "@baseboard_fab2_lib.baseboard_fab2(sch_1):page141_i102:b" )
			)
			( pin "JA9G1.L1"
				( objectStatus "@baseboard_fab2_lib.baseboard_fab2(sch_1):page141_i109:l1" )
			)
			( pin "JA9G1.L2"
				( objectStatus "@baseboard_fab2_lib.baseboard_fab2(sch_1):page141_i109:l2" )
			)
			( pin "JA9G1.L3"
				( objectStatus "@baseboard_fab2_lib.baseboard_fab2(sch_1):page141_i109:l3" )
			)
			( pin "JA9G1.L4"
				( objectStatus "@baseboard_fab2_lib.baseboard_fab2(sch_1):page141_i109:l4" )
			)
			( pin "JA9G1.L5"
				( objectStatus "@baseboard_fab2_lib.baseboard_fab2(sch_1):page141_i109:l5" )
			)
			( pin "JA9G1.MH1"
				( objectStatus "@baseboard_fab2_lib.baseboard_fab2(sch_1):page141_i109:mh1" )
			)
			( pin "JA9G1.MH2"
				( objectStatus "@baseboard_fab2_lib.baseboard_fab2(sch_1):page141_i109:mh2" )
			)
			( pin "JA9G1.R12"
				( objectStatus "@baseboard_fab2_lib.baseboard_fab2(sch_1):page141_i109:trct1" )
			)
			( pin "JA9G1.R6"
				( objectStatus "@baseboard_fab2_lib.baseboard_fab2(sch_1):page141_i109:trct2" )
			)
			( pin "JA9G1.R1"
				( objectStatus "@baseboard_fab2_lib.baseboard_fab2(sch_1):page141_i109:trct3" )
			)
			( pin "JA9G1.R7"
				( objectStatus "@baseboard_fab2_lib.baseboard_fab2(sch_1):page141_i109:trct4" )
			)
			( pin "JA9G1.R10"
				( objectStatus "@baseboard_fab2_lib.baseboard_fab2(sch_1):page141_i109:trd1n" )
			)
			( pin "JA9G1.R11"
				( objectStatus "@baseboard_fab2_lib.baseboard_fab2(sch_1):page141_i109:trd1p" )
			)
			( pin "JA9G1.R5"
				( objectStatus "@baseboard_fab2_lib.baseboard_fab2(sch_1):page141_i109:trd2n" )
			)
			( pin "JA9G1.R4"
				( objectStatus "@baseboard_fab2_lib.baseboard_fab2(sch_1):page141_i109:trd2p" )
			)
			( pin "JA9G1.R2"
				( objectStatus "@baseboard_fab2_lib.baseboard_fab2(sch_1):page141_i109:trd3n" )
			)
			( pin "JA9G1.R3"
				( objectStatus "@baseboard_fab2_lib.baseboard_fab2(sch_1):page141_i109:trd3p" )
			)
			( pin "JA9G1.R9"
				( objectStatus "@baseboard_fab2_lib.baseboard_fab2(sch_1):page141_i109:trd4n" )
			)
			( pin "JA9G1.R8"
				( objectStatus "@baseboard_fab2_lib.baseboard_fab2(sch_1):page141_i109:trd4p" )
			)
			( pin "R1U51.1"
				( objectStatus "@baseboard_fab2_lib.baseboard_fab2(sch_1):page141_i112:a" )
			)
			( pin "R1U51.2"
				( objectStatus "@baseboard_fab2_lib.baseboard_fab2(sch_1):page141_i112:b" )
			)
			( pin "R1U3.1"
				( objectStatus "@baseboard_fab2_lib.baseboard_fab2(sch_1):page141_i114:a" )
			)
			( pin "R1U3.2"
				( objectStatus "@baseboard_fab2_lib.baseboard_fab2(sch_1):page141_i114:b" )
			)
			( pin "U8E4.2"
				( objectStatus "@baseboard_fab2_lib.baseboard_fab2(sch_1):page142_i1:a" )
			)
			( pin "U8E4.1"
				( objectStatus "@baseboard_fab2_lib.baseboard_fab2(sch_1):page142_i1:oe" )
			)
			( pin "U8E4.4"
				( objectStatus "@baseboard_fab2_lib.baseboard_fab2(sch_1):page142_i1:y" )
			)
			( pin "R8E17.1"
				( objectStatus "@baseboard_fab2_lib.baseboard_fab2(sch_1):page142_i2:a" )
			)
			( pin "R8E17.2"
				( objectStatus "@baseboard_fab2_lib.baseboard_fab2(sch_1):page142_i2:b" )
			)
			( pin "R8E23.1"
				( objectStatus "@baseboard_fab2_lib.baseboard_fab2(sch_1):page142_i3:a" )
			)
			( pin "R8E23.2"
				( objectStatus "@baseboard_fab2_lib.baseboard_fab2(sch_1):page142_i3:b" )
			)
			( pin "R8E29.1"
				( objectStatus "@baseboard_fab2_lib.baseboard_fab2(sch_1):page142_i18:a" )
			)
			( pin "R8E29.2"
				( objectStatus "@baseboard_fab2_lib.baseboard_fab2(sch_1):page142_i18:b" )
			)
			( pin "C8E5.1"
				( objectStatus "@baseboard_fab2_lib.baseboard_fab2(sch_1):page142_i20:a" )
			)
			( pin "C8E5.2"
				( objectStatus "@baseboard_fab2_lib.baseboard_fab2(sch_1):page142_i20:b" )
			)
			( pin "R8E30.1"
				( objectStatus "@baseboard_fab2_lib.baseboard_fab2(sch_1):page142_i23:a" )
			)
			( pin "R8E30.2"
				( objectStatus "@baseboard_fab2_lib.baseboard_fab2(sch_1):page142_i23:b" )
			)
			( pin "R8E36.1"
				( objectStatus "@baseboard_fab2_lib.baseboard_fab2(sch_1):page142_i28:a" )
			)
			( pin "R8E36.2"
				( objectStatus "@baseboard_fab2_lib.baseboard_fab2(sch_1):page142_i28:b" )
			)
			( pin "R8E26.1"
				( objectStatus "@baseboard_fab2_lib.baseboard_fab2(sch_1):page142_i30:a" )
			)
			( pin "R8E26.2"
				( objectStatus "@baseboard_fab2_lib.baseboard_fab2(sch_1):page142_i30:b" )
			)
			( pin "R8E28.1"
				( objectStatus "@baseboard_fab2_lib.baseboard_fab2(sch_1):page142_i31:a" )
			)
			( pin "R8E28.2"
				( objectStatus "@baseboard_fab2_lib.baseboard_fab2(sch_1):page142_i31:b" )
			)
			( pin "R8E27.1"
				( objectStatus "@baseboard_fab2_lib.baseboard_fab2(sch_1):page142_i32:a" )
			)
			( pin "R8E27.2"
				( objectStatus "@baseboard_fab2_lib.baseboard_fab2(sch_1):page142_i32:b" )
			)
			( pin "R8E21.1"
				( objectStatus "@baseboard_fab2_lib.baseboard_fab2(sch_1):page142_i33:a" )
			)
			( pin "R8E21.2"
				( objectStatus "@baseboard_fab2_lib.baseboard_fab2(sch_1):page142_i33:b" )
			)
			( pin "C25W24.1"
				( objectStatus "@baseboard_fab2_lib.baseboard_fab2(sch_1):page150_i73:a" )
			)
			( pin "C25W24.2"
				( objectStatus "@baseboard_fab2_lib.baseboard_fab2(sch_1):page150_i73:b" )
			)
			( pin "R25W36.1"
				( objectStatus "@baseboard_fab2_lib.baseboard_fab2(sch_1):page149_i195:\1\" )
			)
			( pin "R25W36.2"
				( objectStatus "@baseboard_fab2_lib.baseboard_fab2(sch_1):page149_i195:\2\" )
			)
			( pin "U25W4.W18"
				( objectStatus "@baseboard_fab2_lib.baseboard_fab2(sch_1):page145_i117:clkin" )
			)
			( pin "U25W4.B14"
				( objectStatus "@baseboard_fab2_lib.baseboard_fab2(sch_1):page145_i117:gpioa0_mac1link" )
			)
			( pin "U25W4.D14"
				( objectStatus "@baseboard_fab2_lib.baseboard_fab2(sch_1):page145_i117:gpioa1_mac2link" )
			)
			( pin "U25W4.D13"
				( objectStatus "@baseboard_fab2_lib.baseboard_fab2(sch_1):page145_i117:\gpioa2_timer3_spi1cs1#\" )
			)
			( pin "U25W4.E13"
				( objectStatus "@baseboard_fab2_lib.baseboard_fab2(sch_1):page145_i117:gpioa3_timer4" )
			)
			( pin "U25W4.C12"
				( objectStatus "@baseboard_fab2_lib.baseboard_fab2(sch_1):page145_i117:gpioc0_sd1clk_scl10" )
			)
			( pin "U25W4.A12"
				( objectStatus "@baseboard_fab2_lib.baseboard_fab2(sch_1):page145_i117:gpioc1_sd1cmd_sda10" )
			)
			( pin "U25W4.B12"
				( objectStatus "@baseboard_fab2_lib.baseboard_fab2(sch_1):page145_i117:gpioc2_sd1dat0_scl11" )
			)
			( pin "U25W4.D9"
				( objectStatus "@baseboard_fab2_lib.baseboard_fab2(sch_1):page145_i117:gpioc3_sd1dat1_sda11" )
			)
			( pin "U25W4.D10"
				( objectStatus "@baseboard_fab2_lib.baseboard_fab2(sch_1):page145_i117:gpioc4_sd1dat2_scl12" )
			)
			( pin "U25W4.E12"
				( objectStatus "@baseboard_fab2_lib.baseboard_fab2(sch_1):page145_i117:gpioc5_sd1dat3_sda12" )
			)
			( pin "U25W4.C11"
				( objectStatus "@baseboard_fab2_lib.baseboard_fab2(sch_1):page145_i117:\gpioc6_sd1cd#_scl13\" )
			)
			( pin "U25W4.B11"
				( objectStatus "@baseboard_fab2_lib.baseboard_fab2(sch_1):page145_i117:\gpioc7_sd1wp#_sda13\" )
			)
			( pin "U25W4.F19"
				( objectStatus "@baseboard_fab2_lib.baseboard_fab2(sch_1):page145_i117:gpiod0_sd2clk" )
			)
			( pin "U25W4.E21"
				( objectStatus "@baseboard_fab2_lib.baseboard_fab2(sch_1):page145_i117:gpiod1_sd2cmd" )
			)
			( pin "U25W4.F20"
				( objectStatus "@baseboard_fab2_lib.baseboard_fab2(sch_1):page145_i117:gpiod2_sd2dat0" )
			)
			( pin "U25W4.D20"
				( objectStatus "@baseboard_fab2_lib.baseboard_fab2(sch_1):page145_i117:gpiod3_sd2dat1" )
			)
			( pin "U25W4.D21"
				( objectStatus "@baseboard_fab2_lib.baseboard_fab2(sch_1):page145_i117:gpiod4_sd2dat2" )
			)
			( pin "U25W4.E20"
				( objectStatus "@baseboard_fab2_lib.baseboard_fab2(sch_1):page145_i117:gpiod5_sd2dat3" )
			)
			( pin "U25W4.G18"
				( objectStatus "@baseboard_fab2_lib.baseboard_fab2(sch_1):page145_i117:\gpiod6_sd2cd#\" )
			)
			( pin "U25W4.C21"
				( objectStatus "@baseboard_fab2_lib.baseboard_fab2(sch_1):page145_i117:\gpiod7_sd2wp#\" )
			)
			( pin "U25W4.B20"
				( objectStatus "@baseboard_fab2_lib.baseboard_fab2(sch_1):page145_i117:gpioe0_ncts3" )
			)
			( pin "U25W4.C20"
				( objectStatus "@baseboard_fab2_lib.baseboard_fab2(sch_1):page145_i117:gpioe1_ndcd3" )
			)
			( pin "U25W4.F18"
				( objectStatus "@baseboard_fab2_lib.baseboard_fab2(sch_1):page145_i117:gpioe2_ndsr3" )
			)
			( pin "U25W4.F17"
				( objectStatus "@baseboard_fab2_lib.baseboard_fab2(sch_1):page145_i117:gpioe3_nri3" )
			)
			( pin "U25W4.E18"
				( objectStatus "@baseboard_fab2_lib.baseboard_fab2(sch_1):page145_i117:gpioe4_ndtr3" )
			)
			( pin "U25W4.D19"
				( objectStatus "@baseboard_fab2_lib.baseboard_fab2(sch_1):page145_i117:gpioe5_nrts3" )
			)
			( pin "U25W4.A20"
				( objectStatus "@baseboard_fab2_lib.baseboard_fab2(sch_1):page145_i117:gpioe6_txd3" )
			)
			( pin "U25W4.B19"
				( objectStatus "@baseboard_fab2_lib.baseboard_fab2(sch_1):page145_i117:gpioe7_rxd3" )
			)
			( pin "U25W4.J19"
				( objectStatus "@baseboard_fab2_lib.baseboard_fab2(sch_1):page145_i117:gpiof0_ncts4_lhad0" )
			)
			( pin "U25W4.J18"
				( objectStatus "@baseboard_fab2_lib.baseboard_fab2(sch_1):page145_i117:gpiof1_ndcd4_lhad1" )
			)
			( pin "U25W4.B22"
				( objectStatus "@baseboard_fab2_lib.baseboard_fab2(sch_1):page145_i117:gpiof2_ndsr4_lhad2" )
			)
			( pin "U25W4.B21"
				( objectStatus "@baseboard_fab2_lib.baseboard_fab2(sch_1):page145_i117:gpiof3_nri4_lhad3" )
			)
			( pin "U25W4.A21"
				( objectStatus "@baseboard_fab2_lib.baseboard_fab2(sch_1):page145_i117:gpiof4_ndtr4_lhclk" )
			)
			( pin "U25W4.H19"
				( objectStatus "@baseboard_fab2_lib.baseboard_fab2(sch_1):page145_i117:\gpiof5_nrts4_lhframe#\" )
			)
			( pin "U25W4.G17"
				( objectStatus "@baseboard_fab2_lib.baseboard_fab2(sch_1):page145_i117:\gpiof6_txd4_lhsirq#\" )
			)
			( pin "U25W4.H18"
				( objectStatus "@baseboard_fab2_lib.baseboard_fab2(sch_1):page145_i117:\gpiof7_rxd4_lhrst#\" )
			)
			( pin "U25W4.E17"
				( objectStatus "@baseboard_fab2_lib.baseboard_fab2(sch_1):page145_i117:gpiog4_sgps2ck_salt1" )
			)
			( pin "U25W4.D16"
				( objectStatus "@baseboard_fab2_lib.baseboard_fab2(sch_1):page145_i117:gpiog5_sgps2ld_salt2" )
			)
			( pin "U25W4.D15"
				( objectStatus "@baseboard_fab2_lib.baseboard_fab2(sch_1):page145_i117:gpiog6_sgps2i0_salt3" )
			)
			( pin "U25W4.E14"
				( objectStatus "@baseboard_fab2_lib.baseboard_fab2(sch_1):page145_i117:gpiog7_sgps2i1_salt4" )
			)
			( pin "U25W4.T2"
				( objectStatus "@baseboard_fab2_lib.baseboard_fab2(sch_1):page145_i117:gpiol0_ncts1" )
			)
			( pin "U25W4.T1"
				( objectStatus "@baseboard_fab2_lib.baseboard_fab2(sch_1):page145_i117:gpiol1_ndcd1_vpide" )
			)
			( pin "U25W4.U1"
				( objectStatus "@baseboard_fab2_lib.baseboard_fab2(sch_1):page145_i117:gpiol2_ndsr1" )
			)
			( pin "U25W4.U2"
				( objectStatus "@baseboard_fab2_lib.baseboard_fab2(sch_1):page145_i117:gpiol3_nri1_vpihs" )
			)
			( pin "U25W4.P4"
				( objectStatus "@baseboard_fab2_lib.baseboard_fab2(sch_1):page145_i117:gpiol4_ndtr1_vpivs" )
			)
			( pin "U25W4.P3"
				( objectStatus "@baseboard_fab2_lib.baseboard_fab2(sch_1):page145_i117:gpiol5_nrts1_vpiclk" )
			)
			( pin "U25W4.V1"
				( objectStatus "@baseboard_fab2_lib.baseboard_fab2(sch_1):page145_i117:gpiol6_txd1" )
			)
			( pin "U25W4.W1"
				( objectStatus "@baseboard_fab2_lib.baseboard_fab2(sch_1):page145_i117:gpiol7_rxd1" )
			)
			( pin "U25W4.Y1"
				( objectStatus "@baseboard_fab2_lib.baseboard_fab2(sch_1):page145_i117:gpiom0_ncts2_vpib2" )
			)
			( pin "U25W4.AB2"
				( objectStatus "@baseboard_fab2_lib.baseboard_fab2(sch_1):page145_i117:gpiom1_ndcd2_vpib3" )
			)
			( pin "U25W4.AA1"
				( objectStatus "@baseboard_fab2_lib.baseboard_fab2(sch_1):page145_i117:gpiom2_ndsr2_vpib4" )
			)
			( pin "U25W4.Y2"
				( objectStatus "@baseboard_fab2_lib.baseboard_fab2(sch_1):page145_i117:gpiom3_nri2_vpib5" )
			)
			( pin "U25W4.AA2"
				( objectStatus "@baseboard_fab2_lib.baseboard_fab2(sch_1):page145_i117:gpiom4_ndtr2_vpib6" )
			)
			( pin "U25W4.P5"
				( objectStatus "@baseboard_fab2_lib.baseboard_fab2(sch_1):page145_i117:gpiom5_nrts2_vpib7" )
			)
			( pin "U25W4.R5"
				( objectStatus "@baseboard_fab2_lib.baseboard_fab2(sch_1):page145_i117:gpiom6_txd2_vpib8" )
			)
			( pin "U25W4.T5"
				( objectStatus "@baseboard_fab2_lib.baseboard_fab2(sch_1):page145_i117:gpiom7_rxd2_vpib9" )
			)
			( pin "U25W4.P21"
				( objectStatus "@baseboard_fab2_lib.baseboard_fab2(sch_1):page145_i117:\gpioy3_sioonctrl#\" )
			)
			( pin "U25W4.AB18"
				( objectStatus "@baseboard_fab2_lib.baseboard_fab2(sch_1):page145_i117:peci" )
			)
			( pin "U25W4.K22"
				( objectStatus "@baseboard_fab2_lib.baseboard_fab2(sch_1):page145_i117:perefclkn" )
			)
			( pin "U25W4.K21"
				( objectStatus "@baseboard_fab2_lib.baseboard_fab2(sch_1):page145_i117:perefclkp" )
			)
			( pin "U25W4.K20"
				( objectStatus "@baseboard_fab2_lib.baseboard_fab2(sch_1):page145_i117:perext" )
			)
			( pin "U25W4.L20"
				( objectStatus "@baseboard_fab2_lib.baseboard_fab2(sch_1):page145_i117:\perst#\" )
			)
			( pin "U25W4.M22"
				( objectStatus "@baseboard_fab2_lib.baseboard_fab2(sch_1):page145_i117:perxn" )
			)
			( pin "U25W4.M21"
				( objectStatus "@baseboard_fab2_lib.baseboard_fab2(sch_1):page145_i117:perxp" )
			)
			( pin "U25W4.L22"
				( objectStatus "@baseboard_fab2_lib.baseboard_fab2(sch_1):page145_i117:petxn" )
			)
			( pin "U25W4.L21"
				( objectStatus "@baseboard_fab2_lib.baseboard_fab2(sch_1):page145_i117:petxp" )
			)
			( pin "U25W4.K2"
				( objectStatus "@baseboard_fab2_lib.baseboard_fab2(sch_1):page145_i117:rxd5" )
			)
			( pin "U25W4.U18"
				( objectStatus "@baseboard_fab2_lib.baseboard_fab2(sch_1):page145_i117:\srst#\" )
			)
			( pin "U25W4.K1"
				( objectStatus "@baseboard_fab2_lib.baseboard_fab2(sch_1):page145_i117:txd5" )
			)
			( pin "FB2T3.1"
				( objectStatus "@baseboard_fab2_lib.baseboard_fab2(sch_1):page150_i76:\1\" )
			)
			( pin "FB2T3.2"
				( objectStatus "@baseboard_fab2_lib.baseboard_fab2(sch_1):page150_i76:\2\" )
			)
			( pin "C25W23.1"
				( objectStatus "@baseboard_fab2_lib.baseboard_fab2(sch_1):page150_i75:a" )
			)
			( pin "C25W23.2"
				( objectStatus "@baseboard_fab2_lib.baseboard_fab2(sch_1):page150_i75:b" )
			)
			( pin "C25W47.1"
				( objectStatus "@baseboard_fab2_lib.baseboard_fab2(sch_1):page150_i54:\1\" )
			)
			( pin "C25W47.2"
				( objectStatus "@baseboard_fab2_lib.baseboard_fab2(sch_1):page150_i54:\2\" )
			)
			( pin "C25W46.1"
				( objectStatus "@baseboard_fab2_lib.baseboard_fab2(sch_1):page150_i55:a" )
			)
			( pin "C25W46.2"
				( objectStatus "@baseboard_fab2_lib.baseboard_fab2(sch_1):page150_i55:b" )
			)
			( pin "R25W30.1"
				( objectStatus "@baseboard_fab2_lib.baseboard_fab2(sch_1):page149_i188:\1\" )
			)
			( pin "R25W30.2"
				( objectStatus "@baseboard_fab2_lib.baseboard_fab2(sch_1):page149_i188:\2\" )
			)
			( pin "R25W29.1"
				( objectStatus "@baseboard_fab2_lib.baseboard_fab2(sch_1):page149_i189:\1\" )
			)
			( pin "R25W29.2"
				( objectStatus "@baseboard_fab2_lib.baseboard_fab2(sch_1):page149_i189:\2\" )
			)
			( pin "R25W31.1"
				( objectStatus "@baseboard_fab2_lib.baseboard_fab2(sch_1):page149_i190:\1\" )
			)
			( pin "R25W31.2"
				( objectStatus "@baseboard_fab2_lib.baseboard_fab2(sch_1):page149_i190:\2\" )
			)
			( pin "R1T27.1"
				( objectStatus "@baseboard_fab2_lib.baseboard_fab2(sch_1):page143_i58:a" )
			)
			( pin "R1T27.2"
				( objectStatus "@baseboard_fab2_lib.baseboard_fab2(sch_1):page143_i58:b" )
			)
			( pin "R25W28.1"
				( objectStatus "@baseboard_fab2_lib.baseboard_fab2(sch_1):page149_i187:\1\" )
			)
			( pin "R25W28.2"
				( objectStatus "@baseboard_fab2_lib.baseboard_fab2(sch_1):page149_i187:\2\" )
			)
			( pin "R25W27.1"
				( objectStatus "@baseboard_fab2_lib.baseboard_fab2(sch_1):page149_i186:\1\" )
			)
			( pin "R25W27.2"
				( objectStatus "@baseboard_fab2_lib.baseboard_fab2(sch_1):page149_i186:\2\" )
			)
			( pin "C8W1.1"
				( objectStatus "@baseboard_fab2_lib.baseboard_fab2(sch_1):page249_i32:a" )
			)
			( pin "C8W1.2"
				( objectStatus "@baseboard_fab2_lib.baseboard_fab2(sch_1):page249_i32:b" )
			)
			( pin "R8B25.1"
				( objectStatus "@baseboard_fab2_lib.baseboard_fab2(sch_1):page149_i156:a" )
			)
			( pin "R8B25.2"
				( objectStatus "@baseboard_fab2_lib.baseboard_fab2(sch_1):page149_i156:b" )
			)
			( pin "C25W10.1"
				( objectStatus "@baseboard_fab2_lib.baseboard_fab2(sch_1):page149_i158:a" )
			)
			( pin "C25W10.2"
				( objectStatus "@baseboard_fab2_lib.baseboard_fab2(sch_1):page149_i158:b" )
			)
			( pin "R25W40.1"
				( objectStatus "@baseboard_fab2_lib.baseboard_fab2(sch_1):page149_i200:\1\" )
			)
			( pin "R25W40.2"
				( objectStatus "@baseboard_fab2_lib.baseboard_fab2(sch_1):page149_i200:\2\" )
			)
			( pin "R25W41.1"
				( objectStatus "@baseboard_fab2_lib.baseboard_fab2(sch_1):page149_i199:\1\" )
			)
			( pin "R25W41.2"
				( objectStatus "@baseboard_fab2_lib.baseboard_fab2(sch_1):page149_i199:\2\" )
			)
			( pin "R25W39.1"
				( objectStatus "@baseboard_fab2_lib.baseboard_fab2(sch_1):page149_i198:\1\" )
			)
			( pin "R25W39.2"
				( objectStatus "@baseboard_fab2_lib.baseboard_fab2(sch_1):page149_i198:\2\" )
			)
			( pin "R25W38.1"
				( objectStatus "@baseboard_fab2_lib.baseboard_fab2(sch_1):page149_i197:\1\" )
			)
			( pin "R25W38.2"
				( objectStatus "@baseboard_fab2_lib.baseboard_fab2(sch_1):page149_i197:\2\" )
			)
			( pin "R25W37.1"
				( objectStatus "@baseboard_fab2_lib.baseboard_fab2(sch_1):page149_i196:\1\" )
			)
			( pin "R25W37.2"
				( objectStatus "@baseboard_fab2_lib.baseboard_fab2(sch_1):page149_i196:\2\" )
			)
			( pin "C25W29.1"
				( objectStatus "@baseboard_fab2_lib.baseboard_fab2(sch_1):page150_i45:a" )
			)
			( pin "C25W29.2"
				( objectStatus "@baseboard_fab2_lib.baseboard_fab2(sch_1):page150_i45:b" )
			)
			( pin "C25W28.1"
				( objectStatus "@baseboard_fab2_lib.baseboard_fab2(sch_1):page150_i46:a" )
			)
			( pin "C25W28.2"
				( objectStatus "@baseboard_fab2_lib.baseboard_fab2(sch_1):page150_i46:b" )
			)
			( pin "C25W27.1"
				( objectStatus "@baseboard_fab2_lib.baseboard_fab2(sch_1):page150_i48:a" )
			)
			( pin "C25W27.2"
				( objectStatus "@baseboard_fab2_lib.baseboard_fab2(sch_1):page150_i48:b" )
			)
			( pin "C25W36.1"
				( objectStatus "@baseboard_fab2_lib.baseboard_fab2(sch_1):page150_i50:\1\" )
			)
			( pin "C25W36.2"
				( objectStatus "@baseboard_fab2_lib.baseboard_fab2(sch_1):page150_i50:\2\" )
			)
			( pin "C25W35.1"
				( objectStatus "@baseboard_fab2_lib.baseboard_fab2(sch_1):page150_i51:a" )
			)
			( pin "C25W35.2"
				( objectStatus "@baseboard_fab2_lib.baseboard_fab2(sch_1):page150_i51:b" )
			)
			( pin "C25W34.1"
				( objectStatus "@baseboard_fab2_lib.baseboard_fab2(sch_1):page150_i53:\1\" )
			)
			( pin "C25W34.2"
				( objectStatus "@baseboard_fab2_lib.baseboard_fab2(sch_1):page150_i53:\2\" )
			)
			( pin "R3W5.1"
				( objectStatus "@baseboard_fab2_lib.baseboard_fab2(sch_1):page249_i33:\1\" )
			)
			( pin "R3W5.2"
				( objectStatus "@baseboard_fab2_lib.baseboard_fab2(sch_1):page249_i33:\2\" )
			)
			( pin "R9A5.1"
				( objectStatus "@baseboard_fab2_lib.baseboard_fab2(sch_1):page155_i195:a" )
			)
			( pin "R9A5.2"
				( objectStatus "@baseboard_fab2_lib.baseboard_fab2(sch_1):page155_i195:b" )
			)
			( pin "C25W40.1"
				( objectStatus "@baseboard_fab2_lib.baseboard_fab2(sch_1):page150_i82:a" )
			)
			( pin "C25W40.2"
				( objectStatus "@baseboard_fab2_lib.baseboard_fab2(sch_1):page150_i82:b" )
			)
			( pin "R9F20.1"
				( objectStatus "@baseboard_fab2_lib.baseboard_fab2(sch_1):page145_i22:a" )
			)
			( pin "R9F20.2"
				( objectStatus "@baseboard_fab2_lib.baseboard_fab2(sch_1):page145_i22:b" )
			)
			( pin "R25W70.1"
				( objectStatus "@baseboard_fab2_lib.baseboard_fab2(sch_1):page146_i64:a" )
			)
			( pin "R25W70.2"
				( objectStatus "@baseboard_fab2_lib.baseboard_fab2(sch_1):page146_i64:b" )
			)
			( pin "R6W12.1"
				( objectStatus "@baseboard_fab2_lib.baseboard_fab2(sch_1):page247_i68:a" )
			)
			( pin "R6W12.2"
				( objectStatus "@baseboard_fab2_lib.baseboard_fab2(sch_1):page247_i68:b" )
			)
			( pin "R6W11.1"
				( objectStatus "@baseboard_fab2_lib.baseboard_fab2(sch_1):page247_i67:a" )
			)
			( pin "R6W11.2"
				( objectStatus "@baseboard_fab2_lib.baseboard_fab2(sch_1):page247_i67:b" )
			)
			( pin "C25W1.1"
				( objectStatus "@baseboard_fab2_lib.baseboard_fab2(sch_1):page149_i71:a" )
			)
			( pin "C25W1.2"
				( objectStatus "@baseboard_fab2_lib.baseboard_fab2(sch_1):page149_i71:b" )
			)
			( pin "C25W19.1"
				( objectStatus "@baseboard_fab2_lib.baseboard_fab2(sch_1):page149_i69:\1\" )
			)
			( pin "C25W19.2"
				( objectStatus "@baseboard_fab2_lib.baseboard_fab2(sch_1):page149_i69:\2\" )
			)
			( pin "C25W18.1"
				( objectStatus "@baseboard_fab2_lib.baseboard_fab2(sch_1):page149_i68:\1\" )
			)
			( pin "C25W18.2"
				( objectStatus "@baseboard_fab2_lib.baseboard_fab2(sch_1):page149_i68:\2\" )
			)
			( pin "C25W13.1"
				( objectStatus "@baseboard_fab2_lib.baseboard_fab2(sch_1):page149_i65:a" )
			)
			( pin "C25W13.2"
				( objectStatus "@baseboard_fab2_lib.baseboard_fab2(sch_1):page149_i65:b" )
			)
			( pin "R25W117.1"
				( objectStatus "@baseboard_fab2_lib.baseboard_fab2(sch_1):page149_i55:a" )
			)
			( pin "R25W117.2"
				( objectStatus "@baseboard_fab2_lib.baseboard_fab2(sch_1):page149_i55:b" )
			)
			( pin "C25W14.1"
				( objectStatus "@baseboard_fab2_lib.baseboard_fab2(sch_1):page149_i44:\1\" )
			)
			( pin "C25W14.2"
				( objectStatus "@baseboard_fab2_lib.baseboard_fab2(sch_1):page149_i44:\2\" )
			)
			( pin "C25W11.1"
				( objectStatus "@baseboard_fab2_lib.baseboard_fab2(sch_1):page149_i159:a" )
			)
			( pin "C25W11.2"
				( objectStatus "@baseboard_fab2_lib.baseboard_fab2(sch_1):page149_i159:b" )
			)
			( pin "U9G1.13"
				( objectStatus "@baseboard_fab2_lib.baseboard_fab2(sch_1):page152_i1:a0" )
			)
			( pin "U9G1.12"
				( objectStatus "@baseboard_fab2_lib.baseboard_fab2(sch_1):page152_i1:a1" )
			)
			( pin "U9G1.10"
				( objectStatus "@baseboard_fab2_lib.baseboard_fab2(sch_1):page152_i1:a2" )
			)
			( pin "U9G1.9"
				( objectStatus "@baseboard_fab2_lib.baseboard_fab2(sch_1):page152_i1:a3" )
			)
			( pin "U9G1.2"
				( objectStatus "@baseboard_fab2_lib.baseboard_fab2(sch_1):page152_i1:b0" )
			)
			( pin "U9G1.3"
				( objectStatus "@baseboard_fab2_lib.baseboard_fab2(sch_1):page152_i1:b1" )
			)
			( pin "U9G1.5"
				( objectStatus "@baseboard_fab2_lib.baseboard_fab2(sch_1):page152_i1:b2" )
			)
			( pin "U9G1.6"
				( objectStatus "@baseboard_fab2_lib.baseboard_fab2(sch_1):page152_i1:b3" )
			)
			( pin "U9G1.1"
				( objectStatus "@baseboard_fab2_lib.baseboard_fab2(sch_1):page152_i1:dir" )
			)
			( pin "U9G1.7"
				( objectStatus "@baseboard_fab2_lib.baseboard_fab2(sch_1):page152_i1:gnd(0)" )
			)
			( pin "U9G1.8"
				( objectStatus "@baseboard_fab2_lib.baseboard_fab2(sch_1):page152_i1:gnd(1)" )
			)
			( pin "U9G1.11"
				( objectStatus "@baseboard_fab2_lib.baseboard_fab2(sch_1):page152_i1:gnd(2)" )
			)
			( pin "U9G1.14"
				( objectStatus "@baseboard_fab2_lib.baseboard_fab2(sch_1):page152_i1:vcc" )
			)
			( pin "U9G1.4"
				( objectStatus "@baseboard_fab2_lib.baseboard_fab2(sch_1):page152_i1:vref" )
			)
			( pin "R1U30.1"
				( objectStatus "@baseboard_fab2_lib.baseboard_fab2(sch_1):page152_i2:a" )
			)
			( pin "R1U30.2"
				( objectStatus "@baseboard_fab2_lib.baseboard_fab2(sch_1):page152_i2:b" )
			)
			( pin "R1U46.1"
				( objectStatus "@baseboard_fab2_lib.baseboard_fab2(sch_1):page152_i6:a" )
			)
			( pin "R1U46.2"
				( objectStatus "@baseboard_fab2_lib.baseboard_fab2(sch_1):page152_i6:b" )
			)
			( pin "R9G31.1"
				( objectStatus "@baseboard_fab2_lib.baseboard_fab2(sch_1):page152_i14:a" )
			)
			( pin "R9G31.2"
				( objectStatus "@baseboard_fab2_lib.baseboard_fab2(sch_1):page152_i14:b" )
			)
			( pin "R1U36.1"
				( objectStatus "@baseboard_fab2_lib.baseboard_fab2(sch_1):page152_i15:a" )
			)
			( pin "R1U36.2"
				( objectStatus "@baseboard_fab2_lib.baseboard_fab2(sch_1):page152_i15:b" )
			)
			( pin "R1U34.1"
				( objectStatus "@baseboard_fab2_lib.baseboard_fab2(sch_1):page152_i16:a" )
			)
			( pin "R1U34.2"
				( objectStatus "@baseboard_fab2_lib.baseboard_fab2(sch_1):page152_i16:b" )
			)
			( pin "C1U19.1"
				( objectStatus "@baseboard_fab2_lib.baseboard_fab2(sch_1):page152_i18:a" )
			)
			( pin "C1U19.2"
				( objectStatus "@baseboard_fab2_lib.baseboard_fab2(sch_1):page152_i18:b" )
			)
			( pin "R1U43.1"
				( objectStatus "@baseboard_fab2_lib.baseboard_fab2(sch_1):page152_i25:a" )
			)
			( pin "R1U43.2"
				( objectStatus "@baseboard_fab2_lib.baseboard_fab2(sch_1):page152_i25:b" )
			)
			( pin "R1U37.1"
				( objectStatus "@baseboard_fab2_lib.baseboard_fab2(sch_1):page152_i26:a" )
			)
			( pin "R1U37.2"
				( objectStatus "@baseboard_fab2_lib.baseboard_fab2(sch_1):page152_i26:b" )
			)
			( pin "C1U22.1"
				( objectStatus "@baseboard_fab2_lib.baseboard_fab2(sch_1):page152_i27:a" )
			)
			( pin "C1U22.2"
				( objectStatus "@baseboard_fab2_lib.baseboard_fab2(sch_1):page152_i27:b" )
			)
			( pin "R9G34.1"
				( objectStatus "@baseboard_fab2_lib.baseboard_fab2(sch_1):page152_i45:a" )
			)
			( pin "R9G34.2"
				( objectStatus "@baseboard_fab2_lib.baseboard_fab2(sch_1):page152_i45:b" )
			)
			( pin "R9G27.1"
				( objectStatus "@baseboard_fab2_lib.baseboard_fab2(sch_1):page152_i47:a" )
			)
			( pin "R9G27.2"
				( objectStatus "@baseboard_fab2_lib.baseboard_fab2(sch_1):page152_i47:b" )
			)
			( pin "R1U58.1"
				( objectStatus "@baseboard_fab2_lib.baseboard_fab2(sch_1):page152_i49:a" )
			)
			( pin "R1U58.2"
				( objectStatus "@baseboard_fab2_lib.baseboard_fab2(sch_1):page152_i49:b" )
			)
			( pin "R1U56.1"
				( objectStatus "@baseboard_fab2_lib.baseboard_fab2(sch_1):page152_i50:a" )
			)
			( pin "R1U56.2"
				( objectStatus "@baseboard_fab2_lib.baseboard_fab2(sch_1):page152_i50:b" )
			)
			( pin "R2U51.1"
				( objectStatus "@baseboard_fab2_lib.baseboard_fab2(sch_1):page152_i51:a" )
			)
			( pin "R2U51.2"
				( objectStatus "@baseboard_fab2_lib.baseboard_fab2(sch_1):page152_i51:b" )
			)
			( pin "R2U40.1"
				( objectStatus "@baseboard_fab2_lib.baseboard_fab2(sch_1):page152_i53:a" )
			)
			( pin "R2U40.2"
				( objectStatus "@baseboard_fab2_lib.baseboard_fab2(sch_1):page152_i53:b" )
			)
			( pin "R2U41.1"
				( objectStatus "@baseboard_fab2_lib.baseboard_fab2(sch_1):page152_i54:a" )
			)
			( pin "R2U41.2"
				( objectStatus "@baseboard_fab2_lib.baseboard_fab2(sch_1):page152_i54:b" )
			)
			( pin "R1U41.1"
				( objectStatus "@baseboard_fab2_lib.baseboard_fab2(sch_1):page152_i56:a" )
			)
			( pin "R1U41.2"
				( objectStatus "@baseboard_fab2_lib.baseboard_fab2(sch_1):page152_i56:b" )
			)
			( pin "R1U35.1"
				( objectStatus "@baseboard_fab2_lib.baseboard_fab2(sch_1):page152_i57:a" )
			)
			( pin "R1U35.2"
				( objectStatus "@baseboard_fab2_lib.baseboard_fab2(sch_1):page152_i57:b" )
			)
			( pin "R4P17.1"
				( objectStatus "@baseboard_fab2_lib.baseboard_fab2(sch_1):page152_i58:a" )
			)
			( pin "R4P17.2"
				( objectStatus "@baseboard_fab2_lib.baseboard_fab2(sch_1):page152_i58:b" )
			)
			( pin "R4P20.1"
				( objectStatus "@baseboard_fab2_lib.baseboard_fab2(sch_1):page152_i59:a" )
			)
			( pin "R4P20.2"
				( objectStatus "@baseboard_fab2_lib.baseboard_fab2(sch_1):page152_i59:b" )
			)
			( pin "R7P5.1"
				( objectStatus "@baseboard_fab2_lib.baseboard_fab2(sch_1):page152_i61:a" )
			)
			( pin "R7P5.2"
				( objectStatus "@baseboard_fab2_lib.baseboard_fab2(sch_1):page152_i61:b" )
			)
			( pin "R7P21.1"
				( objectStatus "@baseboard_fab2_lib.baseboard_fab2(sch_1):page152_i62:a" )
			)
			( pin "R7P21.2"
				( objectStatus "@baseboard_fab2_lib.baseboard_fab2(sch_1):page152_i62:b" )
			)
			( pin "R1U53.1"
				( objectStatus "@baseboard_fab2_lib.baseboard_fab2(sch_1):page152_i64:a" )
			)
			( pin "R1U53.2"
				( objectStatus "@baseboard_fab2_lib.baseboard_fab2(sch_1):page152_i64:b" )
			)
			( pin "R1U60.1"
				( objectStatus "@baseboard_fab2_lib.baseboard_fab2(sch_1):page152_i65:a" )
			)
			( pin "R1U60.2"
				( objectStatus "@baseboard_fab2_lib.baseboard_fab2(sch_1):page152_i65:b" )
			)
			( pin "R2U49.1"
				( objectStatus "@baseboard_fab2_lib.baseboard_fab2(sch_1):page152_i66:a" )
			)
			( pin "R2U49.2"
				( objectStatus "@baseboard_fab2_lib.baseboard_fab2(sch_1):page152_i66:b" )
			)
			( pin "R1U55.1"
				( objectStatus "@baseboard_fab2_lib.baseboard_fab2(sch_1):page152_i67:a" )
			)
			( pin "R1U55.2"
				( objectStatus "@baseboard_fab2_lib.baseboard_fab2(sch_1):page152_i67:b" )
			)
			( pin "R1U62.1"
				( objectStatus "@baseboard_fab2_lib.baseboard_fab2(sch_1):page152_i68:a" )
			)
			( pin "R1U62.2"
				( objectStatus "@baseboard_fab2_lib.baseboard_fab2(sch_1):page152_i68:b" )
			)
			( pin "R1U57.1"
				( objectStatus "@baseboard_fab2_lib.baseboard_fab2(sch_1):page152_i69:a" )
			)
			( pin "R1U57.2"
				( objectStatus "@baseboard_fab2_lib.baseboard_fab2(sch_1):page152_i69:b" )
			)
			( pin "R1U61.1"
				( objectStatus "@baseboard_fab2_lib.baseboard_fab2(sch_1):page152_i70:a" )
			)
			( pin "R1U61.2"
				( objectStatus "@baseboard_fab2_lib.baseboard_fab2(sch_1):page152_i70:b" )
			)
			( pin "R9G28.1"
				( objectStatus "@baseboard_fab2_lib.baseboard_fab2(sch_1):page152_i71:a" )
			)
			( pin "R9G28.2"
				( objectStatus "@baseboard_fab2_lib.baseboard_fab2(sch_1):page152_i71:b" )
			)
			( pin "R9G32.1"
				( objectStatus "@baseboard_fab2_lib.baseboard_fab2(sch_1):page152_i72:a" )
			)
			( pin "R9G32.2"
				( objectStatus "@baseboard_fab2_lib.baseboard_fab2(sch_1):page152_i72:b" )
			)
			( pin "R9G33.1"
				( objectStatus "@baseboard_fab2_lib.baseboard_fab2(sch_1):page152_i73:a" )
			)
			( pin "R9G33.2"
				( objectStatus "@baseboard_fab2_lib.baseboard_fab2(sch_1):page152_i73:b" )
			)
			( pin "R1U59.1"
				( objectStatus "@baseboard_fab2_lib.baseboard_fab2(sch_1):page152_i74:a" )
			)
			( pin "R1U59.2"
				( objectStatus "@baseboard_fab2_lib.baseboard_fab2(sch_1):page152_i74:b" )
			)
			( pin "R2U47.1"
				( objectStatus "@baseboard_fab2_lib.baseboard_fab2(sch_1):page152_i79:a" )
			)
			( pin "R2U47.2"
				( objectStatus "@baseboard_fab2_lib.baseboard_fab2(sch_1):page152_i79:b" )
			)
			( pin "R9G29.1"
				( objectStatus "@baseboard_fab2_lib.baseboard_fab2(sch_1):page152_i92:a" )
			)
			( pin "R9G29.2"
				( objectStatus "@baseboard_fab2_lib.baseboard_fab2(sch_1):page152_i92:b" )
			)
			( pin "R1U54.1"
				( objectStatus "@baseboard_fab2_lib.baseboard_fab2(sch_1):page152_i93:a" )
			)
			( pin "R1U54.2"
				( objectStatus "@baseboard_fab2_lib.baseboard_fab2(sch_1):page152_i93:b" )
			)
			( pin "R2U46.1"
				( objectStatus "@baseboard_fab2_lib.baseboard_fab2(sch_1):page152_i94:a" )
			)
			( pin "R2U46.2"
				( objectStatus "@baseboard_fab2_lib.baseboard_fab2(sch_1):page152_i94:b" )
			)
			( pin "R3N30.1"
				( objectStatus "@baseboard_fab2_lib.baseboard_fab2(sch_1):page152_i95:a" )
			)
			( pin "R3N30.2"
				( objectStatus "@baseboard_fab2_lib.baseboard_fab2(sch_1):page152_i95:b" )
			)
			( pin "R9G30.1"
				( objectStatus "@baseboard_fab2_lib.baseboard_fab2(sch_1):page152_i98:a" )
			)
			( pin "R9G30.2"
				( objectStatus "@baseboard_fab2_lib.baseboard_fab2(sch_1):page152_i98:b" )
			)
			( pin "R3P63.1"
				( objectStatus "@baseboard_fab2_lib.baseboard_fab2(sch_1):page152_i100:a" )
			)
			( pin "R3P63.2"
				( objectStatus "@baseboard_fab2_lib.baseboard_fab2(sch_1):page152_i100:b" )
			)
			( pin "R2U45.1"
				( objectStatus "@baseboard_fab2_lib.baseboard_fab2(sch_1):page152_i102:a" )
			)
			( pin "R2U45.2"
				( objectStatus "@baseboard_fab2_lib.baseboard_fab2(sch_1):page152_i102:b" )
			)
			( pin "R7F6.1"
				( objectStatus "@baseboard_fab2_lib.baseboard_fab2(sch_1):page153_i90:a" )
			)
			( pin "R7F6.2"
				( objectStatus "@baseboard_fab2_lib.baseboard_fab2(sch_1):page153_i90:b" )
			)
			( pin "R7F5.1"
				( objectStatus "@baseboard_fab2_lib.baseboard_fab2(sch_1):page153_i94:a" )
			)
			( pin "R7F5.2"
				( objectStatus "@baseboard_fab2_lib.baseboard_fab2(sch_1):page153_i94:b" )
			)
			( pin "R7F4.1"
				( objectStatus "@baseboard_fab2_lib.baseboard_fab2(sch_1):page153_i98:a" )
			)
			( pin "R7F4.2"
				( objectStatus "@baseboard_fab2_lib.baseboard_fab2(sch_1):page153_i98:b" )
			)
			( pin "R7F37.1"
				( objectStatus "@baseboard_fab2_lib.baseboard_fab2(sch_1):page153_i108:a" )
			)
			( pin "R7F37.2"
				( objectStatus "@baseboard_fab2_lib.baseboard_fab2(sch_1):page153_i108:b" )
			)
			( pin "R7F3.1"
				( objectStatus "@baseboard_fab2_lib.baseboard_fab2(sch_1):page153_i109:a" )
			)
			( pin "R7F3.2"
				( objectStatus "@baseboard_fab2_lib.baseboard_fab2(sch_1):page153_i109:b" )
			)
			( pin "C7F2.1"
				( objectStatus "@baseboard_fab2_lib.baseboard_fab2(sch_1):page153_i130:a" )
			)
			( pin "C7F2.2"
				( objectStatus "@baseboard_fab2_lib.baseboard_fab2(sch_1):page153_i130:b" )
			)
			( pin "C7F1.1"
				( objectStatus "@baseboard_fab2_lib.baseboard_fab2(sch_1):page153_i131:a" )
			)
			( pin "C7F1.2"
				( objectStatus "@baseboard_fab2_lib.baseboard_fab2(sch_1):page153_i131:b" )
			)
			( pin "C3T5.1"
				( objectStatus "@baseboard_fab2_lib.baseboard_fab2(sch_1):page153_i136:a" )
			)
			( pin "C3T5.2"
				( objectStatus "@baseboard_fab2_lib.baseboard_fab2(sch_1):page153_i136:b" )
			)
			( pin "C3T4.1"
				( objectStatus "@baseboard_fab2_lib.baseboard_fab2(sch_1):page153_i138:a" )
			)
			( pin "C3T4.2"
				( objectStatus "@baseboard_fab2_lib.baseboard_fab2(sch_1):page153_i138:b" )
			)
			( pin "R7F32.1"
				( objectStatus "@baseboard_fab2_lib.baseboard_fab2(sch_1):page153_i140:a" )
			)
			( pin "R7F32.2"
				( objectStatus "@baseboard_fab2_lib.baseboard_fab2(sch_1):page153_i140:b" )
			)
			( pin "U7F1.16"
				( objectStatus "@baseboard_fab2_lib.baseboard_fab2(sch_1):page153_i146:clk" )
			)
			( pin "U7F1.7"
				( objectStatus "@baseboard_fab2_lib.baseboard_fab2(sch_1):page153_i146:cs_n" )
			)
			( pin "U7F1.15"
				( objectStatus "@baseboard_fab2_lib.baseboard_fab2(sch_1):page153_i146:di_io(0)" )
			)
			( pin "U7F1.8"
				( objectStatus "@baseboard_fab2_lib.baseboard_fab2(sch_1):page153_i146:do_io(1)" )
			)
			( pin "U7F1.10"
				( objectStatus "@baseboard_fab2_lib.baseboard_fab2(sch_1):page153_i146:gnd" )
			)
			( pin "U7F1.1"
				( objectStatus "@baseboard_fab2_lib.baseboard_fab2(sch_1):page153_i146:hold_n_io(3)" )
			)
			( pin "U7F1.14"
				( objectStatus "@baseboard_fab2_lib.baseboard_fab2(sch_1):page153_i146:nc(0)" )
			)
			( pin "U7F1.13"
				( objectStatus "@baseboard_fab2_lib.baseboard_fab2(sch_1):page153_i146:nc(1)" )
			)
			( pin "U7F1.12"
				( objectStatus "@baseboard_fab2_lib.baseboard_fab2(sch_1):page153_i146:nc(2)" )
			)
			( pin "U7F1.11"
				( objectStatus "@baseboard_fab2_lib.baseboard_fab2(sch_1):page153_i146:nc(3)" )
			)
			( pin "U7F1.6"
				( objectStatus "@baseboard_fab2_lib.baseboard_fab2(sch_1):page153_i146:nc(4)" )
			)
			( pin "U7F1.5"
				( objectStatus "@baseboard_fab2_lib.baseboard_fab2(sch_1):page153_i146:nc(5)" )
			)
			( pin "U7F1.4"
				( objectStatus "@baseboard_fab2_lib.baseboard_fab2(sch_1):page153_i146:nc(6)" )
			)
			( pin "U7F1.3"
				( objectStatus "@baseboard_fab2_lib.baseboard_fab2(sch_1):page153_i146:reset_n" )
			)
			( pin "U7F1.2"
				( objectStatus "@baseboard_fab2_lib.baseboard_fab2(sch_1):page153_i146:vcc" )
			)
			( pin "U7F1.9"
				( objectStatus "@baseboard_fab2_lib.baseboard_fab2(sch_1):page153_i146:wp_n_io(2)" )
			)
			( pin "R3T3.1"
				( objectStatus "@baseboard_fab2_lib.baseboard_fab2(sch_1):page153_i150:a" )
			)
			( pin "R3T3.2"
				( objectStatus "@baseboard_fab2_lib.baseboard_fab2(sch_1):page153_i150:b" )
			)
			( pin "R3T5.1"
				( objectStatus "@baseboard_fab2_lib.baseboard_fab2(sch_1):page153_i152:a" )
			)
			( pin "R3T5.2"
				( objectStatus "@baseboard_fab2_lib.baseboard_fab2(sch_1):page153_i152:b" )
			)
			( pin "R3T2.1"
				( objectStatus "@baseboard_fab2_lib.baseboard_fab2(sch_1):page153_i155:a" )
			)
			( pin "R3T2.2"
				( objectStatus "@baseboard_fab2_lib.baseboard_fab2(sch_1):page153_i155:b" )
			)
			( pin "R3U1.1"
				( objectStatus "@baseboard_fab2_lib.baseboard_fab2(sch_1):page153_i156:a" )
			)
			( pin "R3U1.2"
				( objectStatus "@baseboard_fab2_lib.baseboard_fab2(sch_1):page153_i156:b" )
			)
			( pin "R3T1.1"
				( objectStatus "@baseboard_fab2_lib.baseboard_fab2(sch_1):page153_i157:a" )
			)
			( pin "R3T1.2"
				( objectStatus "@baseboard_fab2_lib.baseboard_fab2(sch_1):page153_i157:b" )
			)
			( pin "U3T1.16"
				( objectStatus "@baseboard_fab2_lib.baseboard_fab2(sch_1):page153_i165:clk" )
			)
			( pin "U3T1.7"
				( objectStatus "@baseboard_fab2_lib.baseboard_fab2(sch_1):page153_i165:cs_n" )
			)
			( pin "U3T1.15"
				( objectStatus "@baseboard_fab2_lib.baseboard_fab2(sch_1):page153_i165:di_io(0)" )
			)
			( pin "U3T1.8"
				( objectStatus "@baseboard_fab2_lib.baseboard_fab2(sch_1):page153_i165:do_io(1)" )
			)
			( pin "U3T1.10"
				( objectStatus "@baseboard_fab2_lib.baseboard_fab2(sch_1):page153_i165:gnd" )
			)
			( pin "U3T1.1"
				( objectStatus "@baseboard_fab2_lib.baseboard_fab2(sch_1):page153_i165:hold_n_io(3)" )
			)
			( pin "U3T1.14"
				( objectStatus "@baseboard_fab2_lib.baseboard_fab2(sch_1):page153_i165:nc(0)" )
			)
			( pin "U3T1.13"
				( objectStatus "@baseboard_fab2_lib.baseboard_fab2(sch_1):page153_i165:nc(1)" )
			)
			( pin "U3T1.12"
				( objectStatus "@baseboard_fab2_lib.baseboard_fab2(sch_1):page153_i165:nc(2)" )
			)
			( pin "U3T1.11"
				( objectStatus "@baseboard_fab2_lib.baseboard_fab2(sch_1):page153_i165:nc(3)" )
			)
			( pin "U3T1.6"
				( objectStatus "@baseboard_fab2_lib.baseboard_fab2(sch_1):page153_i165:nc(4)" )
			)
			( pin "U3T1.5"
				( objectStatus "@baseboard_fab2_lib.baseboard_fab2(sch_1):page153_i165:nc(5)" )
			)
			( pin "U3T1.4"
				( objectStatus "@baseboard_fab2_lib.baseboard_fab2(sch_1):page153_i165:nc(6)" )
			)
			( pin "U3T1.3"
				( objectStatus "@baseboard_fab2_lib.baseboard_fab2(sch_1):page153_i165:reset_n" )
			)
			( pin "U3T1.2"
				( objectStatus "@baseboard_fab2_lib.baseboard_fab2(sch_1):page153_i165:vcc" )
			)
			( pin "U3T1.9"
				( objectStatus "@baseboard_fab2_lib.baseboard_fab2(sch_1):page153_i165:wp_n_io(2)" )
			)
			( pin "R8F8.1"
				( objectStatus "@baseboard_fab2_lib.baseboard_fab2(sch_1):page153_i166:a" )
			)
			( pin "R8F8.2"
				( objectStatus "@baseboard_fab2_lib.baseboard_fab2(sch_1):page153_i166:b" )
			)
			( pin "R8F7.1"
				( objectStatus "@baseboard_fab2_lib.baseboard_fab2(sch_1):page153_i167:a" )
			)
			( pin "R8F7.2"
				( objectStatus "@baseboard_fab2_lib.baseboard_fab2(sch_1):page153_i167:b" )
			)
			( pin "R7F28.1"
				( objectStatus "@baseboard_fab2_lib.baseboard_fab2(sch_1):page153_i168:a" )
			)
			( pin "R7F28.2"
				( objectStatus "@baseboard_fab2_lib.baseboard_fab2(sch_1):page153_i168:b" )
			)
			( pin "R7F30.1"
				( objectStatus "@baseboard_fab2_lib.baseboard_fab2(sch_1):page153_i170:a" )
			)
			( pin "R7F30.2"
				( objectStatus "@baseboard_fab2_lib.baseboard_fab2(sch_1):page153_i170:b" )
			)
			( pin "R3T4.1"
				( objectStatus "@baseboard_fab2_lib.baseboard_fab2(sch_1):page153_i174:a" )
			)
			( pin "R3T4.2"
				( objectStatus "@baseboard_fab2_lib.baseboard_fab2(sch_1):page153_i174:b" )
			)
			( pin "R3T12.1"
				( objectStatus "@baseboard_fab2_lib.baseboard_fab2(sch_1):page153_i178:a" )
			)
			( pin "R3T12.2"
				( objectStatus "@baseboard_fab2_lib.baseboard_fab2(sch_1):page153_i178:b" )
			)
			( pin "R3T9.1"
				( objectStatus "@baseboard_fab2_lib.baseboard_fab2(sch_1):page153_i179:a" )
			)
			( pin "R3T9.2"
				( objectStatus "@baseboard_fab2_lib.baseboard_fab2(sch_1):page153_i179:b" )
			)
			( pin "R7F29.1"
				( objectStatus "@baseboard_fab2_lib.baseboard_fab2(sch_1):page153_i181:a" )
			)
			( pin "R7F29.2"
				( objectStatus "@baseboard_fab2_lib.baseboard_fab2(sch_1):page153_i181:b" )
			)
			( pin "R3T10.1"
				( objectStatus "@baseboard_fab2_lib.baseboard_fab2(sch_1):page153_i184:a" )
			)
			( pin "R3T10.2"
				( objectStatus "@baseboard_fab2_lib.baseboard_fab2(sch_1):page153_i184:b" )
			)
			( pin "C8E18.1"
				( objectStatus "@baseboard_fab2_lib.baseboard_fab2(sch_1):page154_i14:a" )
			)
			( pin "C8E18.2"
				( objectStatus "@baseboard_fab2_lib.baseboard_fab2(sch_1):page154_i14:b" )
			)
			( pin "R2T9.1"
				( objectStatus "@baseboard_fab2_lib.baseboard_fab2(sch_1):page154_i62:a" )
			)
			( pin "R2T9.2"
				( objectStatus "@baseboard_fab2_lib.baseboard_fab2(sch_1):page154_i62:b" )
			)
			( pin "U8F1.15"
				( objectStatus "@baseboard_fab2_lib.baseboard_fab2(sch_1):page154_i74:en" )
			)
			( pin "U8F1.8"
				( objectStatus "@baseboard_fab2_lib.baseboard_fab2(sch_1):page154_i74:gnd" )
			)
			( pin "U8F1.2"
				( objectStatus "@baseboard_fab2_lib.baseboard_fab2(sch_1):page154_i74:ia0" )
			)
			( pin "U8F1.3"
				( objectStatus "@baseboard_fab2_lib.baseboard_fab2(sch_1):page154_i74:ia1" )
			)
			( pin "U8F1.5"
				( objectStatus "@baseboard_fab2_lib.baseboard_fab2(sch_1):page154_i74:ib0" )
			)
			( pin "U8F1.6"
				( objectStatus "@baseboard_fab2_lib.baseboard_fab2(sch_1):page154_i74:ib1" )
			)
			( pin "U8F1.11"
				( objectStatus "@baseboard_fab2_lib.baseboard_fab2(sch_1):page154_i74:ic0" )
			)
			( pin "U8F1.10"
				( objectStatus "@baseboard_fab2_lib.baseboard_fab2(sch_1):page154_i74:ic1" )
			)
			( pin "U8F1.14"
				( objectStatus "@baseboard_fab2_lib.baseboard_fab2(sch_1):page154_i74:id0" )
			)
			( pin "U8F1.13"
				( objectStatus "@baseboard_fab2_lib.baseboard_fab2(sch_1):page154_i74:id1" )
			)
			( pin "U8F1.1"
				( objectStatus "@baseboard_fab2_lib.baseboard_fab2(sch_1):page154_i74:s" )
			)
			( pin "U8F1.16"
				( objectStatus "@baseboard_fab2_lib.baseboard_fab2(sch_1):page154_i74:vcc" )
			)
			( pin "U8F1.4"
				( objectStatus "@baseboard_fab2_lib.baseboard_fab2(sch_1):page154_i74:ya" )
			)
			( pin "U8F1.7"
				( objectStatus "@baseboard_fab2_lib.baseboard_fab2(sch_1):page154_i74:yb" )
			)
			( pin "U8F1.9"
				( objectStatus "@baseboard_fab2_lib.baseboard_fab2(sch_1):page154_i74:yc" )
			)
			( pin "U8F1.12"
				( objectStatus "@baseboard_fab2_lib.baseboard_fab2(sch_1):page154_i74:yd" )
			)
			( pin "U2T1.15"
				( objectStatus "@baseboard_fab2_lib.baseboard_fab2(sch_1):page154_i75:en" )
			)
			( pin "U2T1.8"
				( objectStatus "@baseboard_fab2_lib.baseboard_fab2(sch_1):page154_i75:gnd" )
			)
			( pin "U2T1.2"
				( objectStatus "@baseboard_fab2_lib.baseboard_fab2(sch_1):page154_i75:ia0" )
			)
			( pin "U2T1.3"
				( objectStatus "@baseboard_fab2_lib.baseboard_fab2(sch_1):page154_i75:ia1" )
			)
			( pin "U2T1.5"
				( objectStatus "@baseboard_fab2_lib.baseboard_fab2(sch_1):page154_i75:ib0" )
			)
			( pin "U2T1.6"
				( objectStatus "@baseboard_fab2_lib.baseboard_fab2(sch_1):page154_i75:ib1" )
			)
			( pin "U2T1.11"
				( objectStatus "@baseboard_fab2_lib.baseboard_fab2(sch_1):page154_i75:ic0" )
			)
			( pin "U2T1.10"
				( objectStatus "@baseboard_fab2_lib.baseboard_fab2(sch_1):page154_i75:ic1" )
			)
			( pin "U2T1.14"
				( objectStatus "@baseboard_fab2_lib.baseboard_fab2(sch_1):page154_i75:id0" )
			)
			( pin "U2T1.13"
				( objectStatus "@baseboard_fab2_lib.baseboard_fab2(sch_1):page154_i75:id1" )
			)
			( pin "U2T1.1"
				( objectStatus "@baseboard_fab2_lib.baseboard_fab2(sch_1):page154_i75:s" )
			)
			( pin "U2T1.16"
				( objectStatus "@baseboard_fab2_lib.baseboard_fab2(sch_1):page154_i75:vcc" )
			)
			( pin "U2T1.4"
				( objectStatus "@baseboard_fab2_lib.baseboard_fab2(sch_1):page154_i75:ya" )
			)
			( pin "U2T1.7"
				( objectStatus "@baseboard_fab2_lib.baseboard_fab2(sch_1):page154_i75:yb" )
			)
			( pin "U2T1.9"
				( objectStatus "@baseboard_fab2_lib.baseboard_fab2(sch_1):page154_i75:yc" )
			)
			( pin "U2T1.12"
				( objectStatus "@baseboard_fab2_lib.baseboard_fab2(sch_1):page154_i75:yd" )
			)
			( pin "R2T2.1"
				( objectStatus "@baseboard_fab2_lib.baseboard_fab2(sch_1):page154_i92:a" )
			)
			( pin "R2T2.2"
				( objectStatus "@baseboard_fab2_lib.baseboard_fab2(sch_1):page154_i92:b" )
			)
			( pin "R2R12.1"
				( objectStatus "@baseboard_fab2_lib.baseboard_fab2(sch_1):page154_i93:a" )
			)
			( pin "R2R12.2"
				( objectStatus "@baseboard_fab2_lib.baseboard_fab2(sch_1):page154_i93:b" )
			)
			( pin "C2T1.1"
				( objectStatus "@baseboard_fab2_lib.baseboard_fab2(sch_1):page154_i94:a" )
			)
			( pin "C2T1.2"
				( objectStatus "@baseboard_fab2_lib.baseboard_fab2(sch_1):page154_i94:b" )
			)
			( pin "U2T3.1"
				( objectStatus "@baseboard_fab2_lib.baseboard_fab2(sch_1):page154_i99:a" )
			)
			( pin "U2T3.2"
				( objectStatus "@baseboard_fab2_lib.baseboard_fab2(sch_1):page154_i99:b" )
			)
			( pin "U2T3.4"
				( objectStatus "@baseboard_fab2_lib.baseboard_fab2(sch_1):page154_i99:y" )
			)
			( pin "U2T2.1"
				( objectStatus "@baseboard_fab2_lib.baseboard_fab2(sch_1):page154_i100:a" )
			)
			( pin "U2T2.2"
				( objectStatus "@baseboard_fab2_lib.baseboard_fab2(sch_1):page154_i100:b" )
			)
			( pin "U2T2.4"
				( objectStatus "@baseboard_fab2_lib.baseboard_fab2(sch_1):page154_i100:y" )
			)
			( pin "R2T13.1"
				( objectStatus "@baseboard_fab2_lib.baseboard_fab2(sch_1):page154_i101:a" )
			)
			( pin "R2T13.2"
				( objectStatus "@baseboard_fab2_lib.baseboard_fab2(sch_1):page154_i101:b" )
			)
			( pin "R2T11.1"
				( objectStatus "@baseboard_fab2_lib.baseboard_fab2(sch_1):page154_i105:a" )
			)
			( pin "R2T11.2"
				( objectStatus "@baseboard_fab2_lib.baseboard_fab2(sch_1):page154_i105:b" )
			)
			( pin "R2T8.1"
				( objectStatus "@baseboard_fab2_lib.baseboard_fab2(sch_1):page154_i106:a" )
			)
			( pin "R2T8.2"
				( objectStatus "@baseboard_fab2_lib.baseboard_fab2(sch_1):page154_i106:b" )
			)
			( pin "R8F6.1"
				( objectStatus "@baseboard_fab2_lib.baseboard_fab2(sch_1):page154_i119:a" )
			)
			( pin "R8F6.2"
				( objectStatus "@baseboard_fab2_lib.baseboard_fab2(sch_1):page154_i119:b" )
			)
			( pin "Q8F1.3"
				( objectStatus "@baseboard_fab2_lib.baseboard_fab2(sch_1):page154_i126:drn" )
			)
			( pin "Q8F1.1"
				( objectStatus "@baseboard_fab2_lib.baseboard_fab2(sch_1):page154_i126:gate" )
			)
			( pin "Q8F1.2"
				( objectStatus "@baseboard_fab2_lib.baseboard_fab2(sch_1):page154_i126:src" )
			)
			( pin "R2T6.1"
				( objectStatus "@baseboard_fab2_lib.baseboard_fab2(sch_1):page154_i127:a" )
			)
			( pin "R2T6.2"
				( objectStatus "@baseboard_fab2_lib.baseboard_fab2(sch_1):page154_i127:b" )
			)
			( pin "R1U6.1"
				( objectStatus "@baseboard_fab2_lib.baseboard_fab2(sch_1):page154_i128:a" )
			)
			( pin "R1U6.2"
				( objectStatus "@baseboard_fab2_lib.baseboard_fab2(sch_1):page154_i128:b" )
			)
			( pin "C2T12.1"
				( objectStatus "@baseboard_fab2_lib.baseboard_fab2(sch_1):page154_i132:a" )
			)
			( pin "C2T12.2"
				( objectStatus "@baseboard_fab2_lib.baseboard_fab2(sch_1):page154_i132:b" )
			)
			( pin "C2T8.1"
				( objectStatus "@baseboard_fab2_lib.baseboard_fab2(sch_1):page154_i135:a" )
			)
			( pin "C2T8.2"
				( objectStatus "@baseboard_fab2_lib.baseboard_fab2(sch_1):page154_i135:b" )
			)
			( pin "R9A8.1"
				( objectStatus "@baseboard_fab2_lib.baseboard_fab2(sch_1):page155_i53:a" )
			)
			( pin "R9A8.2"
				( objectStatus "@baseboard_fab2_lib.baseboard_fab2(sch_1):page155_i53:b" )
			)
			( pin "R1L32.1"
				( objectStatus "@baseboard_fab2_lib.baseboard_fab2(sch_1):page155_i65:a" )
			)
			( pin "R1L32.2"
				( objectStatus "@baseboard_fab2_lib.baseboard_fab2(sch_1):page155_i65:b" )
			)
			( pin "R1L30.1"
				( objectStatus "@baseboard_fab2_lib.baseboard_fab2(sch_1):page155_i66:a" )
			)
			( pin "R1L30.2"
				( objectStatus "@baseboard_fab2_lib.baseboard_fab2(sch_1):page155_i66:b" )
			)
			( pin "R1L25.1"
				( objectStatus "@baseboard_fab2_lib.baseboard_fab2(sch_1):page155_i67:a" )
			)
			( pin "R1L25.2"
				( objectStatus "@baseboard_fab2_lib.baseboard_fab2(sch_1):page155_i67:b" )
			)
			( pin "R1L24.1"
				( objectStatus "@baseboard_fab2_lib.baseboard_fab2(sch_1):page155_i68:a" )
			)
			( pin "R1L24.2"
				( objectStatus "@baseboard_fab2_lib.baseboard_fab2(sch_1):page155_i68:b" )
			)
			( pin "R1L20.1"
				( objectStatus "@baseboard_fab2_lib.baseboard_fab2(sch_1):page155_i73:a" )
			)
			( pin "R1L20.2"
				( objectStatus "@baseboard_fab2_lib.baseboard_fab2(sch_1):page155_i73:b" )
			)
			( pin "R1L18.1"
				( objectStatus "@baseboard_fab2_lib.baseboard_fab2(sch_1):page155_i74:a" )
			)
			( pin "R1L18.2"
				( objectStatus "@baseboard_fab2_lib.baseboard_fab2(sch_1):page155_i74:b" )
			)
			( pin "R1L14.1"
				( objectStatus "@baseboard_fab2_lib.baseboard_fab2(sch_1):page155_i75:a" )
			)
			( pin "R1L14.2"
				( objectStatus "@baseboard_fab2_lib.baseboard_fab2(sch_1):page155_i75:b" )
			)
			( pin "R1L11.1"
				( objectStatus "@baseboard_fab2_lib.baseboard_fab2(sch_1):page155_i76:a" )
			)
			( pin "R1L11.2"
				( objectStatus "@baseboard_fab2_lib.baseboard_fab2(sch_1):page155_i76:b" )
			)
			( pin "R9A7.1"
				( objectStatus "@baseboard_fab2_lib.baseboard_fab2(sch_1):page155_i80:a" )
			)
			( pin "R9A7.2"
				( objectStatus "@baseboard_fab2_lib.baseboard_fab2(sch_1):page155_i80:b" )
			)
			( pin "C9A1.1"
				( objectStatus "@baseboard_fab2_lib.baseboard_fab2(sch_1):page155_i127:a" )
			)
			( pin "C9A1.2"
				( objectStatus "@baseboard_fab2_lib.baseboard_fab2(sch_1):page155_i127:b" )
			)
			( pin "F1L1.1"
				( objectStatus "@baseboard_fab2_lib.baseboard_fab2(sch_1):page155_i129:a(0)" )
			)
			( pin "F1L1.2"
				( objectStatus "@baseboard_fab2_lib.baseboard_fab2(sch_1):page155_i129:b(0)" )
			)
			( pin "R1L9.1"
				( objectStatus "@baseboard_fab2_lib.baseboard_fab2(sch_1):page155_i130:a" )
			)
			( pin "R1L9.2"
				( objectStatus "@baseboard_fab2_lib.baseboard_fab2(sch_1):page155_i130:b" )
			)
			( pin "U6W10.1"
				( objectStatus "@baseboard_fab2_lib.baseboard_fab2(sch_1):page176_i122:a(0)" )
			)
			( pin "U6W10.2"
				( objectStatus "@baseboard_fab2_lib.baseboard_fab2(sch_1):page176_i122:b(0)" )
			)
			( pin "U6W10.4"
				( objectStatus "@baseboard_fab2_lib.baseboard_fab2(sch_1):page176_i122:y(0)" )
			)
			( pin "J9A2.1"
				( objectStatus "@baseboard_fab2_lib.baseboard_fab2(sch_1):page155_i171:io1" )
			)
			( pin "J9A2.2"
				( objectStatus "@baseboard_fab2_lib.baseboard_fab2(sch_1):page155_i171:io2" )
			)
			( pin "J9A2.3"
				( objectStatus "@baseboard_fab2_lib.baseboard_fab2(sch_1):page155_i171:io3" )
			)
			( pin "J9A2.4"
				( objectStatus "@baseboard_fab2_lib.baseboard_fab2(sch_1):page155_i171:io4" )
			)
			( pin "J9A2.5"
				( objectStatus "@baseboard_fab2_lib.baseboard_fab2(sch_1):page155_i171:io5" )
			)
			( pin "J9A2.6"
				( objectStatus "@baseboard_fab2_lib.baseboard_fab2(sch_1):page155_i171:io6" )
			)
			( pin "J9A2.7"
				( objectStatus "@baseboard_fab2_lib.baseboard_fab2(sch_1):page155_i171:io7" )
			)
			( pin "J9A2.8"
				( objectStatus "@baseboard_fab2_lib.baseboard_fab2(sch_1):page155_i171:io8" )
			)
			( pin "J9A2.9"
				( objectStatus "@baseboard_fab2_lib.baseboard_fab2(sch_1):page155_i171:io9" )
			)
			( pin "J9A2.10"
				( objectStatus "@baseboard_fab2_lib.baseboard_fab2(sch_1):page155_i171:io10" )
			)
			( pin "J9A2.11"
				( objectStatus "@baseboard_fab2_lib.baseboard_fab2(sch_1):page155_i171:io11" )
			)
			( pin "J9A2.12"
				( objectStatus "@baseboard_fab2_lib.baseboard_fab2(sch_1):page155_i171:io12" )
			)
			( pin "J9A2.13"
				( objectStatus "@baseboard_fab2_lib.baseboard_fab2(sch_1):page155_i171:io13" )
			)
			( pin "J9A2.14"
				( objectStatus "@baseboard_fab2_lib.baseboard_fab2(sch_1):page155_i171:io14" )
			)
			( pin "U9A1.2"
				( objectStatus "@baseboard_fab2_lib.baseboard_fab2(sch_1):page155_i178:a" )
			)
			( pin "U9A1.4"
				( objectStatus "@baseboard_fab2_lib.baseboard_fab2(sch_1):page155_i178:y" )
			)
			( pin "C1T56.1"
				( objectStatus "@baseboard_fab2_lib.baseboard_fab2(sch_1):page155_i184:a" )
			)
			( pin "C1T56.2"
				( objectStatus "@baseboard_fab2_lib.baseboard_fab2(sch_1):page155_i184:b" )
			)
			( pin "R1L2.1"
				( objectStatus "@baseboard_fab2_lib.baseboard_fab2(sch_1):page155_i186:a" )
			)
			( pin "R1L2.2"
				( objectStatus "@baseboard_fab2_lib.baseboard_fab2(sch_1):page155_i186:b" )
			)
			( pin "Q1L2.3"
				( objectStatus "@baseboard_fab2_lib.baseboard_fab2(sch_1):page155_i187:drain(0)" )
			)
			( pin "Q1L2.5"
				( objectStatus "@baseboard_fab2_lib.baseboard_fab2(sch_1):page155_i187:gate(0)" )
			)
			( pin "Q1L2.4"
				( objectStatus "@baseboard_fab2_lib.baseboard_fab2(sch_1):page155_i187:source(0)" )
			)
			( pin "Q1L2.6"
				( objectStatus "@baseboard_fab2_lib.baseboard_fab2(sch_1):page155_i188:drain(0)" )
			)
			( pin "Q1L2.2"
				( objectStatus "@baseboard_fab2_lib.baseboard_fab2(sch_1):page155_i188:gate(0)" )
			)
			( pin "Q1L2.1"
				( objectStatus "@baseboard_fab2_lib.baseboard_fab2(sch_1):page155_i188:source(0)" )
			)
			( pin "R9A6.1"
				( objectStatus "@baseboard_fab2_lib.baseboard_fab2(sch_1):page155_i191:a" )
			)
			( pin "R9A6.2"
				( objectStatus "@baseboard_fab2_lib.baseboard_fab2(sch_1):page155_i191:b" )
			)
			( pin "U8F3.1"
				( objectStatus "@baseboard_fab2_lib.baseboard_fab2(sch_1):page156_i201:\1a\" )
			)
			( pin "U8F3.6"
				( objectStatus "@baseboard_fab2_lib.baseboard_fab2(sch_1):page156_i201:\1y\" )
			)
			( pin "U8F3.3"
				( objectStatus "@baseboard_fab2_lib.baseboard_fab2(sch_1):page156_i201:\2a\" )
			)
			( pin "U8F3.4"
				( objectStatus "@baseboard_fab2_lib.baseboard_fab2(sch_1):page156_i201:\2y\" )
			)
			( pin "R2T34.1"
				( objectStatus "@baseboard_fab2_lib.baseboard_fab2(sch_1):page156_i206:a" )
			)
			( pin "R2T34.2"
				( objectStatus "@baseboard_fab2_lib.baseboard_fab2(sch_1):page156_i206:b" )
			)
			( pin "R2T35.1"
				( objectStatus "@baseboard_fab2_lib.baseboard_fab2(sch_1):page156_i207:a" )
			)
			( pin "R2T35.2"
				( objectStatus "@baseboard_fab2_lib.baseboard_fab2(sch_1):page156_i207:b" )
			)
			( pin "R2T22.1"
				( objectStatus "@baseboard_fab2_lib.baseboard_fab2(sch_1):page156_i210:a" )
			)
			( pin "R2T22.2"
				( objectStatus "@baseboard_fab2_lib.baseboard_fab2(sch_1):page156_i210:b" )
			)
			( pin "R8F26.1"
				( objectStatus "@baseboard_fab2_lib.baseboard_fab2(sch_1):page156_i211:a" )
			)
			( pin "R8F26.2"
				( objectStatus "@baseboard_fab2_lib.baseboard_fab2(sch_1):page156_i211:b" )
			)
			( pin "R8E24.1"
				( objectStatus "@baseboard_fab2_lib.baseboard_fab2(sch_1):page156_i214:a" )
			)
			( pin "R8E24.2"
				( objectStatus "@baseboard_fab2_lib.baseboard_fab2(sch_1):page156_i214:b" )
			)
			( pin "R8E22.1"
				( objectStatus "@baseboard_fab2_lib.baseboard_fab2(sch_1):page156_i215:a" )
			)
			( pin "R8E22.2"
				( objectStatus "@baseboard_fab2_lib.baseboard_fab2(sch_1):page156_i215:b" )
			)
			( pin "R2U2.1"
				( objectStatus "@baseboard_fab2_lib.baseboard_fab2(sch_1):page156_i265:a" )
			)
			( pin "R2U2.2"
				( objectStatus "@baseboard_fab2_lib.baseboard_fab2(sch_1):page156_i265:b" )
			)
			( pin "R8G2.1"
				( objectStatus "@baseboard_fab2_lib.baseboard_fab2(sch_1):page156_i267:a" )
			)
			( pin "R8G2.2"
				( objectStatus "@baseboard_fab2_lib.baseboard_fab2(sch_1):page156_i267:b" )
			)
			( pin "U8G1.1"
				( objectStatus "@baseboard_fab2_lib.baseboard_fab2(sch_1):page156_i269:\1a\" )
			)
			( pin "U8G1.6"
				( objectStatus "@baseboard_fab2_lib.baseboard_fab2(sch_1):page156_i269:\1y\" )
			)
			( pin "U8G1.3"
				( objectStatus "@baseboard_fab2_lib.baseboard_fab2(sch_1):page156_i269:\2a\" )
			)
			( pin "U8G1.4"
				( objectStatus "@baseboard_fab2_lib.baseboard_fab2(sch_1):page156_i269:\2y\" )
			)
			( pin "C2T35.1"
				( objectStatus "@baseboard_fab2_lib.baseboard_fab2(sch_1):page156_i273:a" )
			)
			( pin "C2T35.2"
				( objectStatus "@baseboard_fab2_lib.baseboard_fab2(sch_1):page156_i273:b" )
			)
			( pin "C8F16.1"
				( objectStatus "@baseboard_fab2_lib.baseboard_fab2(sch_1):page156_i275:a" )
			)
			( pin "C8F16.2"
				( objectStatus "@baseboard_fab2_lib.baseboard_fab2(sch_1):page156_i275:b" )
			)
			( pin "R8E11.1"
				( objectStatus "@baseboard_fab2_lib.baseboard_fab2(sch_1):page156_i279:a" )
			)
			( pin "R8E11.2"
				( objectStatus "@baseboard_fab2_lib.baseboard_fab2(sch_1):page156_i279:b" )
			)
			( pin "J9B2.1"
				( objectStatus "@baseboard_fab2_lib.baseboard_fab2(sch_1):page156_i281:io1" )
			)
			( pin "J9B2.2"
				( objectStatus "@baseboard_fab2_lib.baseboard_fab2(sch_1):page156_i281:io2" )
			)
			( pin "J9B2.3"
				( objectStatus "@baseboard_fab2_lib.baseboard_fab2(sch_1):page156_i281:io3" )
			)
			( pin "J8C1.1"
				( objectStatus "@baseboard_fab2_lib.baseboard_fab2(sch_1):page156_i285:io1" )
			)
			( pin "J8C1.2"
				( objectStatus "@baseboard_fab2_lib.baseboard_fab2(sch_1):page156_i285:io2" )
			)
			( pin "J8C1.3"
				( objectStatus "@baseboard_fab2_lib.baseboard_fab2(sch_1):page156_i285:io3" )
			)
			( pin "R2T18.1"
				( objectStatus "@baseboard_fab2_lib.baseboard_fab2(sch_1):page156_i288:a" )
			)
			( pin "R2T18.2"
				( objectStatus "@baseboard_fab2_lib.baseboard_fab2(sch_1):page156_i288:b" )
			)
			( pin "R2T28.1"
				( objectStatus "@baseboard_fab2_lib.baseboard_fab2(sch_1):page156_i289:a" )
			)
			( pin "R2T28.2"
				( objectStatus "@baseboard_fab2_lib.baseboard_fab2(sch_1):page156_i289:b" )
			)
			( pin "R6D16.1"
				( objectStatus "@baseboard_fab2_lib.baseboard_fab2(sch_1):page156_i299:a" )
			)
			( pin "R6D16.2"
				( objectStatus "@baseboard_fab2_lib.baseboard_fab2(sch_1):page156_i299:b" )
			)
			( pin "R3D31.1"
				( objectStatus "@baseboard_fab2_lib.baseboard_fab2(sch_1):page156_i300:a" )
			)
			( pin "R3D31.2"
				( objectStatus "@baseboard_fab2_lib.baseboard_fab2(sch_1):page156_i300:b" )
			)
			( pin "R6N14.1"
				( objectStatus "@baseboard_fab2_lib.baseboard_fab2(sch_1):page156_i302:a" )
			)
			( pin "R6N14.2"
				( objectStatus "@baseboard_fab2_lib.baseboard_fab2(sch_1):page156_i302:b" )
			)
			( pin "R6N13.1"
				( objectStatus "@baseboard_fab2_lib.baseboard_fab2(sch_1):page156_i303:a" )
			)
			( pin "R6N13.2"
				( objectStatus "@baseboard_fab2_lib.baseboard_fab2(sch_1):page156_i303:b" )
			)
			( pin "R6N15.1"
				( objectStatus "@baseboard_fab2_lib.baseboard_fab2(sch_1):page156_i304:a" )
			)
			( pin "R6N15.2"
				( objectStatus "@baseboard_fab2_lib.baseboard_fab2(sch_1):page156_i304:b" )
			)
			( pin "R1C32.1"
				( objectStatus "@baseboard_fab2_lib.baseboard_fab2(sch_1):page156_i312:a" )
			)
			( pin "R1C32.2"
				( objectStatus "@baseboard_fab2_lib.baseboard_fab2(sch_1):page156_i312:b" )
			)
			( pin "R1C33.1"
				( objectStatus "@baseboard_fab2_lib.baseboard_fab2(sch_1):page156_i313:a" )
			)
			( pin "R1C33.2"
				( objectStatus "@baseboard_fab2_lib.baseboard_fab2(sch_1):page156_i313:b" )
			)
			( pin "R1C34.1"
				( objectStatus "@baseboard_fab2_lib.baseboard_fab2(sch_1):page156_i320:a" )
			)
			( pin "R1C34.2"
				( objectStatus "@baseboard_fab2_lib.baseboard_fab2(sch_1):page156_i320:b" )
			)
			( pin "R9M21.1"
				( objectStatus "@baseboard_fab2_lib.baseboard_fab2(sch_1):page156_i321:a" )
			)
			( pin "R9M21.2"
				( objectStatus "@baseboard_fab2_lib.baseboard_fab2(sch_1):page156_i321:b" )
			)
			( pin "R4A8.1"
				( objectStatus "@baseboard_fab2_lib.baseboard_fab2(sch_1):page156_i322:a" )
			)
			( pin "R4A8.2"
				( objectStatus "@baseboard_fab2_lib.baseboard_fab2(sch_1):page156_i322:b" )
			)
			( pin "R9M20.1"
				( objectStatus "@baseboard_fab2_lib.baseboard_fab2(sch_1):page156_i323:a" )
			)
			( pin "R9M20.2"
				( objectStatus "@baseboard_fab2_lib.baseboard_fab2(sch_1):page156_i323:b" )
			)
			( pin "R4A9.1"
				( objectStatus "@baseboard_fab2_lib.baseboard_fab2(sch_1):page156_i324:a" )
			)
			( pin "R4A9.2"
				( objectStatus "@baseboard_fab2_lib.baseboard_fab2(sch_1):page156_i324:b" )
			)
			( pin "R3P54.1"
				( objectStatus "@baseboard_fab2_lib.baseboard_fab2(sch_1):page156_i331:a" )
			)
			( pin "R3P54.2"
				( objectStatus "@baseboard_fab2_lib.baseboard_fab2(sch_1):page156_i331:b" )
			)
			( pin "R3P56.1"
				( objectStatus "@baseboard_fab2_lib.baseboard_fab2(sch_1):page156_i333:a" )
			)
			( pin "R3P56.2"
				( objectStatus "@baseboard_fab2_lib.baseboard_fab2(sch_1):page156_i333:b" )
			)
			( pin "R1C35.1"
				( objectStatus "@baseboard_fab2_lib.baseboard_fab2(sch_1):page156_i336:a" )
			)
			( pin "R1C35.2"
				( objectStatus "@baseboard_fab2_lib.baseboard_fab2(sch_1):page156_i336:b" )
			)
			( pin "R1C36.1"
				( objectStatus "@baseboard_fab2_lib.baseboard_fab2(sch_1):page156_i337:a" )
			)
			( pin "R1C36.2"
				( objectStatus "@baseboard_fab2_lib.baseboard_fab2(sch_1):page156_i337:b" )
			)
			( pin "R2N27.1"
				( objectStatus "@baseboard_fab2_lib.baseboard_fab2(sch_1):page157_i97:a" )
			)
			( pin "R2N27.2"
				( objectStatus "@baseboard_fab2_lib.baseboard_fab2(sch_1):page157_i97:b" )
			)
			( pin "R8F23.1"
				( objectStatus "@baseboard_fab2_lib.baseboard_fab2(sch_1):page157_i296:a" )
			)
			( pin "R8F23.2"
				( objectStatus "@baseboard_fab2_lib.baseboard_fab2(sch_1):page157_i296:b" )
			)
			( pin "R2T29.1"
				( objectStatus "@baseboard_fab2_lib.baseboard_fab2(sch_1):page157_i298:a" )
			)
			( pin "R2T29.2"
				( objectStatus "@baseboard_fab2_lib.baseboard_fab2(sch_1):page157_i298:b" )
			)
			( pin "R2N25.1"
				( objectStatus "@baseboard_fab2_lib.baseboard_fab2(sch_1):page157_i302:a" )
			)
			( pin "R2N25.2"
				( objectStatus "@baseboard_fab2_lib.baseboard_fab2(sch_1):page157_i302:b" )
			)
			( pin "R8F24.1"
				( objectStatus "@baseboard_fab2_lib.baseboard_fab2(sch_1):page157_i316:a" )
			)
			( pin "R8F24.2"
				( objectStatus "@baseboard_fab2_lib.baseboard_fab2(sch_1):page157_i316:b" )
			)
			( pin "R2T5.1"
				( objectStatus "@baseboard_fab2_lib.baseboard_fab2(sch_1):page157_i326:a" )
			)
			( pin "R2T5.2"
				( objectStatus "@baseboard_fab2_lib.baseboard_fab2(sch_1):page157_i326:b" )
			)
			( pin "R2T7.1"
				( objectStatus "@baseboard_fab2_lib.baseboard_fab2(sch_1):page157_i327:a" )
			)
			( pin "R2T7.2"
				( objectStatus "@baseboard_fab2_lib.baseboard_fab2(sch_1):page157_i327:b" )
			)
			( pin "Q2T1.1"
				( objectStatus "@baseboard_fab2_lib.baseboard_fab2(sch_1):page157_i330:b" )
			)
			( pin "Q2T1.3"
				( objectStatus "@baseboard_fab2_lib.baseboard_fab2(sch_1):page157_i330:c" )
			)
			( pin "Q2T1.2"
				( objectStatus "@baseboard_fab2_lib.baseboard_fab2(sch_1):page157_i330:e" )
			)
			( pin "R8D25.1"
				( objectStatus "@baseboard_fab2_lib.baseboard_fab2(sch_1):page157_i335:a" )
			)
			( pin "R8D25.2"
				( objectStatus "@baseboard_fab2_lib.baseboard_fab2(sch_1):page157_i335:b" )
			)
			( pin "Q2T2.3"
				( objectStatus "@baseboard_fab2_lib.baseboard_fab2(sch_1):page157_i340:drn" )
			)
			( pin "Q2T2.1"
				( objectStatus "@baseboard_fab2_lib.baseboard_fab2(sch_1):page157_i340:gate" )
			)
			( pin "Q2T2.2"
				( objectStatus "@baseboard_fab2_lib.baseboard_fab2(sch_1):page157_i340:src" )
			)
			( pin "R3N12.1"
				( objectStatus "@baseboard_fab2_lib.baseboard_fab2(sch_1):page157_i342:a" )
			)
			( pin "R3N12.2"
				( objectStatus "@baseboard_fab2_lib.baseboard_fab2(sch_1):page157_i342:b" )
			)
			( pin "R3N11.1"
				( objectStatus "@baseboard_fab2_lib.baseboard_fab2(sch_1):page157_i344:a" )
			)
			( pin "R3N11.2"
				( objectStatus "@baseboard_fab2_lib.baseboard_fab2(sch_1):page157_i344:b" )
			)
			( pin "R2M2.1"
				( objectStatus "@baseboard_fab2_lib.baseboard_fab2(sch_1):page157_i346:a" )
			)
			( pin "R2M2.2"
				( objectStatus "@baseboard_fab2_lib.baseboard_fab2(sch_1):page157_i346:b" )
			)
			( pin "R2M5.1"
				( objectStatus "@baseboard_fab2_lib.baseboard_fab2(sch_1):page157_i348:a" )
			)
			( pin "R2M5.2"
				( objectStatus "@baseboard_fab2_lib.baseboard_fab2(sch_1):page157_i348:b" )
			)
			( pin "S8E1.1"
				( objectStatus "@baseboard_fab2_lib.baseboard_fab2(sch_1):page157_i351:a" )
			)
			( pin "S8E1.2"
				( objectStatus "@baseboard_fab2_lib.baseboard_fab2(sch_1):page157_i351:b" )
			)
			( pin "R2R9.1"
				( objectStatus "@baseboard_fab2_lib.baseboard_fab2(sch_1):page157_i352:a" )
			)
			( pin "R2R9.2"
				( objectStatus "@baseboard_fab2_lib.baseboard_fab2(sch_1):page157_i352:b" )
			)
			( pin "C2R12.1"
				( objectStatus "@baseboard_fab2_lib.baseboard_fab2(sch_1):page157_i353:a" )
			)
			( pin "C2R12.2"
				( objectStatus "@baseboard_fab2_lib.baseboard_fab2(sch_1):page157_i353:b" )
			)
			( pin "U2R1.3"
				( objectStatus "@baseboard_fab2_lib.baseboard_fab2(sch_1):page157_i356:a(0)" )
			)
			( pin "U2R1.4"
				( objectStatus "@baseboard_fab2_lib.baseboard_fab2(sch_1):page157_i356:y(0)" )
			)
			( pin "U2R1.1"
				( objectStatus "@baseboard_fab2_lib.baseboard_fab2(sch_1):page157_i357:a(0)" )
			)
			( pin "U2R1.6"
				( objectStatus "@baseboard_fab2_lib.baseboard_fab2(sch_1):page157_i357:y(0)" )
			)
			( pin "R2R10.1"
				( objectStatus "@baseboard_fab2_lib.baseboard_fab2(sch_1):page157_i358:a" )
			)
			( pin "R2R10.2"
				( objectStatus "@baseboard_fab2_lib.baseboard_fab2(sch_1):page157_i358:b" )
			)
			( pin "R8E19.1"
				( objectStatus "@baseboard_fab2_lib.baseboard_fab2(sch_1):page157_i361:a" )
			)
			( pin "R8E19.2"
				( objectStatus "@baseboard_fab2_lib.baseboard_fab2(sch_1):page157_i361:b" )
			)
			( pin "R2U4.1"
				( objectStatus "@baseboard_fab2_lib.baseboard_fab2(sch_1):page157_i367:a" )
			)
			( pin "R2U4.2"
				( objectStatus "@baseboard_fab2_lib.baseboard_fab2(sch_1):page157_i367:b" )
			)
			( pin "R4R1.1"
				( objectStatus "@baseboard_fab2_lib.baseboard_fab2(sch_1):page157_i368:a" )
			)
			( pin "R4R1.2"
				( objectStatus "@baseboard_fab2_lib.baseboard_fab2(sch_1):page157_i368:b" )
			)
			( pin "C2T3.1"
				( objectStatus "@baseboard_fab2_lib.baseboard_fab2(sch_1):page157_i370:a" )
			)
			( pin "C2T3.2"
				( objectStatus "@baseboard_fab2_lib.baseboard_fab2(sch_1):page157_i370:b" )
			)
			( pin "U8D2.2"
				( objectStatus "@baseboard_fab2_lib.baseboard_fab2(sch_1):page157_i374:a" )
			)
			( pin "U8D2.4"
				( objectStatus "@baseboard_fab2_lib.baseboard_fab2(sch_1):page157_i374:y" )
			)
			( pin "C8D1.1"
				( objectStatus "@baseboard_fab2_lib.baseboard_fab2(sch_1):page157_i376:a" )
			)
			( pin "C8D1.2"
				( objectStatus "@baseboard_fab2_lib.baseboard_fab2(sch_1):page157_i376:b" )
			)
			( pin "R9E14.1"
				( objectStatus "@baseboard_fab2_lib.baseboard_fab2(sch_1):page157_i379:a" )
			)
			( pin "R9E14.2"
				( objectStatus "@baseboard_fab2_lib.baseboard_fab2(sch_1):page157_i379:b" )
			)
			( pin "R1L7.1"
				( objectStatus "@baseboard_fab2_lib.baseboard_fab2(sch_1):page157_i382:a" )
			)
			( pin "R1L7.2"
				( objectStatus "@baseboard_fab2_lib.baseboard_fab2(sch_1):page157_i382:b" )
			)
			( pin "R8E32.1"
				( objectStatus "@baseboard_fab2_lib.baseboard_fab2(sch_1):page157_i385:a" )
			)
			( pin "R8E32.2"
				( objectStatus "@baseboard_fab2_lib.baseboard_fab2(sch_1):page157_i385:b" )
			)
			( pin "R8D22.1"
				( objectStatus "@baseboard_fab2_lib.baseboard_fab2(sch_1):page157_i386:a" )
			)
			( pin "R8D22.2"
				( objectStatus "@baseboard_fab2_lib.baseboard_fab2(sch_1):page157_i386:b" )
			)
			( pin "R8D36.1"
				( objectStatus "@baseboard_fab2_lib.baseboard_fab2(sch_1):page157_i388:a" )
			)
			( pin "R8D36.2"
				( objectStatus "@baseboard_fab2_lib.baseboard_fab2(sch_1):page157_i388:b" )
			)
			( pin "C1T10.1"
				( objectStatus "@baseboard_fab2_lib.baseboard_fab2(sch_1):page158_i70:a" )
			)
			( pin "C1T10.2"
				( objectStatus "@baseboard_fab2_lib.baseboard_fab2(sch_1):page158_i70:b" )
			)
			( pin "U9F2.7"
				( objectStatus "@baseboard_fab2_lib.baseboard_fab2(sch_1):page158_i74:a" )
			)
			( pin "U9F2.1"
				( objectStatus "@baseboard_fab2_lib.baseboard_fab2(sch_1):page158_i74:b0" )
			)
			( pin "U9F2.2"
				( objectStatus "@baseboard_fab2_lib.baseboard_fab2(sch_1):page158_i74:b1" )
			)
			( pin "U9F2.3"
				( objectStatus "@baseboard_fab2_lib.baseboard_fab2(sch_1):page158_i74:b2" )
			)
			( pin "U9F2.4"
				( objectStatus "@baseboard_fab2_lib.baseboard_fab2(sch_1):page158_i74:gnd" )
			)
			( pin "U9F2.6"
				( objectStatus "@baseboard_fab2_lib.baseboard_fab2(sch_1):page158_i74:s1" )
			)
			( pin "U9F2.5"
				( objectStatus "@baseboard_fab2_lib.baseboard_fab2(sch_1):page158_i74:s2" )
			)
			( pin "U9F2.8"
				( objectStatus "@baseboard_fab2_lib.baseboard_fab2(sch_1):page158_i74:vcc" )
			)
			( pin "U9F1.7"
				( objectStatus "@baseboard_fab2_lib.baseboard_fab2(sch_1):page158_i75:a" )
			)
			( pin "U9F1.1"
				( objectStatus "@baseboard_fab2_lib.baseboard_fab2(sch_1):page158_i75:b0" )
			)
			( pin "U9F1.2"
				( objectStatus "@baseboard_fab2_lib.baseboard_fab2(sch_1):page158_i75:b1" )
			)
			( pin "U9F1.3"
				( objectStatus "@baseboard_fab2_lib.baseboard_fab2(sch_1):page158_i75:b2" )
			)
			( pin "U9F1.4"
				( objectStatus "@baseboard_fab2_lib.baseboard_fab2(sch_1):page158_i75:gnd" )
			)
			( pin "U9F1.6"
				( objectStatus "@baseboard_fab2_lib.baseboard_fab2(sch_1):page158_i75:s1" )
			)
			( pin "U9F1.5"
				( objectStatus "@baseboard_fab2_lib.baseboard_fab2(sch_1):page158_i75:s2" )
			)
			( pin "U9F1.8"
				( objectStatus "@baseboard_fab2_lib.baseboard_fab2(sch_1):page158_i75:vcc" )
			)
			( pin "R9F25.1"
				( objectStatus "@baseboard_fab2_lib.baseboard_fab2(sch_1):page158_i86:a" )
			)
			( pin "R9F25.2"
				( objectStatus "@baseboard_fab2_lib.baseboard_fab2(sch_1):page158_i86:b" )
			)
			( pin "R9F27.1"
				( objectStatus "@baseboard_fab2_lib.baseboard_fab2(sch_1):page158_i91:a" )
			)
			( pin "R9F27.2"
				( objectStatus "@baseboard_fab2_lib.baseboard_fab2(sch_1):page158_i91:b" )
			)
			( pin "C1T11.1"
				( objectStatus "@baseboard_fab2_lib.baseboard_fab2(sch_1):page158_i97:a" )
			)
			( pin "C1T11.2"
				( objectStatus "@baseboard_fab2_lib.baseboard_fab2(sch_1):page158_i97:b" )
			)
			( pin "R9F26.1"
				( objectStatus "@baseboard_fab2_lib.baseboard_fab2(sch_1):page158_i99:a" )
			)
			( pin "R9F26.2"
				( objectStatus "@baseboard_fab2_lib.baseboard_fab2(sch_1):page158_i99:b" )
			)
			( pin "R9F24.1"
				( objectStatus "@baseboard_fab2_lib.baseboard_fab2(sch_1):page158_i100:a" )
			)
			( pin "R9F24.2"
				( objectStatus "@baseboard_fab2_lib.baseboard_fab2(sch_1):page158_i100:b" )
			)
			( pin "DS9A4.1"
				( objectStatus "@baseboard_fab2_lib.baseboard_fab2(sch_1):page158_i130:a" )
			)
			( pin "DS9A4.2"
				( objectStatus "@baseboard_fab2_lib.baseboard_fab2(sch_1):page158_i130:c" )
			)
			( pin "R1L43.1"
				( objectStatus "@baseboard_fab2_lib.baseboard_fab2(sch_1):page158_i131:a" )
			)
			( pin "R1L43.2"
				( objectStatus "@baseboard_fab2_lib.baseboard_fab2(sch_1):page158_i131:b" )
			)
			( pin "DS9A7.1"
				( objectStatus "@baseboard_fab2_lib.baseboard_fab2(sch_1):page158_i134:a" )
			)
			( pin "DS9A7.2"
				( objectStatus "@baseboard_fab2_lib.baseboard_fab2(sch_1):page158_i134:c" )
			)
			( pin "R1L44.1"
				( objectStatus "@baseboard_fab2_lib.baseboard_fab2(sch_1):page158_i136:a" )
			)
			( pin "R1L44.2"
				( objectStatus "@baseboard_fab2_lib.baseboard_fab2(sch_1):page158_i136:b" )
			)
			( pin "R9F31.1"
				( objectStatus "@baseboard_fab2_lib.baseboard_fab2(sch_1):page239_i98:\1\" )
			)
			( pin "R9F31.2"
				( objectStatus "@baseboard_fab2_lib.baseboard_fab2(sch_1):page239_i98:\2\" )
			)
			( pin "R9F67.1"
				( objectStatus "@baseboard_fab2_lib.baseboard_fab2(sch_1):page181_i279:a" )
			)
			( pin "R9F67.2"
				( objectStatus "@baseboard_fab2_lib.baseboard_fab2(sch_1):page181_i279:b" )
			)
			( pin "R8G3.1"
				( objectStatus "@baseboard_fab2_lib.baseboard_fab2(sch_1):page159_i210:a" )
			)
			( pin "R8G3.2"
				( objectStatus "@baseboard_fab2_lib.baseboard_fab2(sch_1):page159_i210:b" )
			)
			( pin "R8G6.1"
				( objectStatus "@baseboard_fab2_lib.baseboard_fab2(sch_1):page159_i212:a" )
			)
			( pin "R8G6.2"
				( objectStatus "@baseboard_fab2_lib.baseboard_fab2(sch_1):page159_i212:b" )
			)
			( pin "R2U5.1"
				( objectStatus "@baseboard_fab2_lib.baseboard_fab2(sch_1):page159_i214:a" )
			)
			( pin "R2U5.2"
				( objectStatus "@baseboard_fab2_lib.baseboard_fab2(sch_1):page159_i214:b" )
			)
			( pin "R2U13.1"
				( objectStatus "@baseboard_fab2_lib.baseboard_fab2(sch_1):page159_i216:a" )
			)
			( pin "R2U13.2"
				( objectStatus "@baseboard_fab2_lib.baseboard_fab2(sch_1):page159_i216:b" )
			)
			( pin "R2U1.1"
				( objectStatus "@baseboard_fab2_lib.baseboard_fab2(sch_1):page159_i218:a" )
			)
			( pin "R2U1.2"
				( objectStatus "@baseboard_fab2_lib.baseboard_fab2(sch_1):page159_i218:b" )
			)
			( pin "R2T49.1"
				( objectStatus "@baseboard_fab2_lib.baseboard_fab2(sch_1):page159_i219:a" )
			)
			( pin "R2T49.2"
				( objectStatus "@baseboard_fab2_lib.baseboard_fab2(sch_1):page159_i219:b" )
			)
			( pin "R2U7.1"
				( objectStatus "@baseboard_fab2_lib.baseboard_fab2(sch_1):page159_i220:a" )
			)
			( pin "R2U7.2"
				( objectStatus "@baseboard_fab2_lib.baseboard_fab2(sch_1):page159_i220:b" )
			)
			( pin "R2U10.1"
				( objectStatus "@baseboard_fab2_lib.baseboard_fab2(sch_1):page159_i221:a" )
			)
			( pin "R2U10.2"
				( objectStatus "@baseboard_fab2_lib.baseboard_fab2(sch_1):page159_i221:b" )
			)
			( pin "R1U11.1"
				( objectStatus "@baseboard_fab2_lib.baseboard_fab2(sch_1):page159_i222:a" )
			)
			( pin "R1U11.2"
				( objectStatus "@baseboard_fab2_lib.baseboard_fab2(sch_1):page159_i222:b" )
			)
			( pin "R1U8.1"
				( objectStatus "@baseboard_fab2_lib.baseboard_fab2(sch_1):page159_i223:a" )
			)
			( pin "R1U8.2"
				( objectStatus "@baseboard_fab2_lib.baseboard_fab2(sch_1):page159_i223:b" )
			)
			( pin "R9G12.1"
				( objectStatus "@baseboard_fab2_lib.baseboard_fab2(sch_1):page159_i224:a" )
			)
			( pin "R9G12.2"
				( objectStatus "@baseboard_fab2_lib.baseboard_fab2(sch_1):page159_i224:b" )
			)
			( pin "R1U20.1"
				( objectStatus "@baseboard_fab2_lib.baseboard_fab2(sch_1):page159_i225:a" )
			)
			( pin "R1U20.2"
				( objectStatus "@baseboard_fab2_lib.baseboard_fab2(sch_1):page159_i225:b" )
			)
			( pin "R1U19.1"
				( objectStatus "@baseboard_fab2_lib.baseboard_fab2(sch_1):page159_i226:a" )
			)
			( pin "R1U19.2"
				( objectStatus "@baseboard_fab2_lib.baseboard_fab2(sch_1):page159_i226:b" )
			)
			( pin "R9G13.1"
				( objectStatus "@baseboard_fab2_lib.baseboard_fab2(sch_1):page159_i227:a" )
			)
			( pin "R9G13.2"
				( objectStatus "@baseboard_fab2_lib.baseboard_fab2(sch_1):page159_i227:b" )
			)
			( pin "R8G5.1"
				( objectStatus "@baseboard_fab2_lib.baseboard_fab2(sch_1):page159_i228:a" )
			)
			( pin "R8G5.2"
				( objectStatus "@baseboard_fab2_lib.baseboard_fab2(sch_1):page159_i228:b" )
			)
			( pin "R8G4.1"
				( objectStatus "@baseboard_fab2_lib.baseboard_fab2(sch_1):page159_i229:a" )
			)
			( pin "R8G4.2"
				( objectStatus "@baseboard_fab2_lib.baseboard_fab2(sch_1):page159_i229:b" )
			)
			( pin "R2U34.1"
				( objectStatus "@baseboard_fab2_lib.baseboard_fab2(sch_1):page159_i230:a" )
			)
			( pin "R2U34.2"
				( objectStatus "@baseboard_fab2_lib.baseboard_fab2(sch_1):page159_i230:b" )
			)
			( pin "R2U33.1"
				( objectStatus "@baseboard_fab2_lib.baseboard_fab2(sch_1):page159_i231:a" )
			)
			( pin "R2U33.2"
				( objectStatus "@baseboard_fab2_lib.baseboard_fab2(sch_1):page159_i231:b" )
			)
			( pin "R1U9.1"
				( objectStatus "@baseboard_fab2_lib.baseboard_fab2(sch_1):page159_i232:a" )
			)
			( pin "R1U9.2"
				( objectStatus "@baseboard_fab2_lib.baseboard_fab2(sch_1):page159_i232:b" )
			)
			( pin "R1U10.1"
				( objectStatus "@baseboard_fab2_lib.baseboard_fab2(sch_1):page159_i233:a" )
			)
			( pin "R1U10.2"
				( objectStatus "@baseboard_fab2_lib.baseboard_fab2(sch_1):page159_i233:b" )
			)
			( pin "R1T8.1"
				( objectStatus "@baseboard_fab2_lib.baseboard_fab2(sch_1):page160_i4:a" )
			)
			( pin "R1T8.2"
				( objectStatus "@baseboard_fab2_lib.baseboard_fab2(sch_1):page160_i4:b" )
			)
			( pin "R1T3.1"
				( objectStatus "@baseboard_fab2_lib.baseboard_fab2(sch_1):page160_i46:a" )
			)
			( pin "R1T3.2"
				( objectStatus "@baseboard_fab2_lib.baseboard_fab2(sch_1):page160_i46:b" )
			)
			( pin "R1T2.1"
				( objectStatus "@baseboard_fab2_lib.baseboard_fab2(sch_1):page160_i49:a" )
			)
			( pin "R1T2.2"
				( objectStatus "@baseboard_fab2_lib.baseboard_fab2(sch_1):page160_i49:b" )
			)
			( pin "R1T7.1"
				( objectStatus "@baseboard_fab2_lib.baseboard_fab2(sch_1):page160_i50:a" )
			)
			( pin "R1T7.2"
				( objectStatus "@baseboard_fab2_lib.baseboard_fab2(sch_1):page160_i50:b" )
			)
			( pin "R9F23.1"
				( objectStatus "@baseboard_fab2_lib.baseboard_fab2(sch_1):page160_i51:a" )
			)
			( pin "R9F23.2"
				( objectStatus "@baseboard_fab2_lib.baseboard_fab2(sch_1):page160_i51:b" )
			)
			( pin "R9F22.1"
				( objectStatus "@baseboard_fab2_lib.baseboard_fab2(sch_1):page160_i52:a" )
			)
			( pin "R9F22.2"
				( objectStatus "@baseboard_fab2_lib.baseboard_fab2(sch_1):page160_i52:b" )
			)
			( pin "J1F2.1"
				( objectStatus "@baseboard_fab2_lib.baseboard_fab2(sch_1):page161_i1:io1" )
			)
			( pin "J1F2.2"
				( objectStatus "@baseboard_fab2_lib.baseboard_fab2(sch_1):page161_i1:io2" )
			)
			( pin "J1F2.3"
				( objectStatus "@baseboard_fab2_lib.baseboard_fab2(sch_1):page161_i1:io3" )
			)
			( pin "J1F2.4"
				( objectStatus "@baseboard_fab2_lib.baseboard_fab2(sch_1):page161_i1:io4" )
			)
			( pin "J1F2.5"
				( objectStatus "@baseboard_fab2_lib.baseboard_fab2(sch_1):page161_i1:io5" )
			)
			( pin "J1F2.6"
				( objectStatus "@baseboard_fab2_lib.baseboard_fab2(sch_1):page161_i1:io6" )
			)
			( pin "C1E21.1"
				( objectStatus "@baseboard_fab2_lib.baseboard_fab2(sch_1):page161_i3:a" )
			)
			( pin "C1E21.2"
				( objectStatus "@baseboard_fab2_lib.baseboard_fab2(sch_1):page161_i3:b" )
			)
			( pin "C1E20.1"
				( objectStatus "@baseboard_fab2_lib.baseboard_fab2(sch_1):page161_i4:a" )
			)
			( pin "C1E20.2"
				( objectStatus "@baseboard_fab2_lib.baseboard_fab2(sch_1):page161_i4:b" )
			)
			( pin "C9M5.1"
				( objectStatus "@baseboard_fab2_lib.baseboard_fab2(sch_1):page161_i26:a" )
			)
			( pin "C9M5.2"
				( objectStatus "@baseboard_fab2_lib.baseboard_fab2(sch_1):page161_i26:b" )
			)
			( pin "C9M4.1"
				( objectStatus "@baseboard_fab2_lib.baseboard_fab2(sch_1):page161_i27:a" )
			)
			( pin "C9M4.2"
				( objectStatus "@baseboard_fab2_lib.baseboard_fab2(sch_1):page161_i27:b" )
			)
			( pin "J1B2.1"
				( objectStatus "@baseboard_fab2_lib.baseboard_fab2(sch_1):page161_i32:io1" )
			)
			( pin "J1B2.2"
				( objectStatus "@baseboard_fab2_lib.baseboard_fab2(sch_1):page161_i32:io2" )
			)
			( pin "J1B2.3"
				( objectStatus "@baseboard_fab2_lib.baseboard_fab2(sch_1):page161_i32:io3" )
			)
			( pin "J1B2.4"
				( objectStatus "@baseboard_fab2_lib.baseboard_fab2(sch_1):page161_i32:io4" )
			)
			( pin "J1B2.5"
				( objectStatus "@baseboard_fab2_lib.baseboard_fab2(sch_1):page161_i32:io5" )
			)
			( pin "J1B2.6"
				( objectStatus "@baseboard_fab2_lib.baseboard_fab2(sch_1):page161_i32:io6" )
			)
			( pin "CR1F1.2"
				( objectStatus "@baseboard_fab2_lib.baseboard_fab2(sch_1):page161_i42:a" )
			)
			( pin "CR1F1.1"
				( objectStatus "@baseboard_fab2_lib.baseboard_fab2(sch_1):page161_i42:c" )
			)
			( pin "R1F2.1"
				( objectStatus "@baseboard_fab2_lib.baseboard_fab2(sch_1):page161_i43:a" )
			)
			( pin "R1F2.2"
				( objectStatus "@baseboard_fab2_lib.baseboard_fab2(sch_1):page161_i43:b" )
			)
			( pin "R1F1.1"
				( objectStatus "@baseboard_fab2_lib.baseboard_fab2(sch_1):page161_i45:a" )
			)
			( pin "R1F1.2"
				( objectStatus "@baseboard_fab2_lib.baseboard_fab2(sch_1):page161_i45:b" )
			)
			( pin "C1F9.1"
				( objectStatus "@baseboard_fab2_lib.baseboard_fab2(sch_1):page161_i46:a" )
			)
			( pin "C1F9.2"
				( objectStatus "@baseboard_fab2_lib.baseboard_fab2(sch_1):page161_i46:b" )
			)
			( pin "CR1E1.2"
				( objectStatus "@baseboard_fab2_lib.baseboard_fab2(sch_1):page161_i50:a" )
			)
			( pin "CR1E1.1"
				( objectStatus "@baseboard_fab2_lib.baseboard_fab2(sch_1):page161_i50:c" )
			)
			( pin "R1E12.1"
				( objectStatus "@baseboard_fab2_lib.baseboard_fab2(sch_1):page161_i51:a" )
			)
			( pin "R1E12.2"
				( objectStatus "@baseboard_fab2_lib.baseboard_fab2(sch_1):page161_i51:b" )
			)
			( pin "CR1B2.2"
				( objectStatus "@baseboard_fab2_lib.baseboard_fab2(sch_1):page161_i62:a" )
			)
			( pin "CR1B2.1"
				( objectStatus "@baseboard_fab2_lib.baseboard_fab2(sch_1):page161_i62:c" )
			)
			( pin "CR1B1.2"
				( objectStatus "@baseboard_fab2_lib.baseboard_fab2(sch_1):page161_i64:a" )
			)
			( pin "CR1B1.1"
				( objectStatus "@baseboard_fab2_lib.baseboard_fab2(sch_1):page161_i64:c" )
			)
			( pin "R7F33.1"
				( objectStatus "@baseboard_fab2_lib.baseboard_fab2(sch_1):page161_i65:a" )
			)
			( pin "R7F33.2"
				( objectStatus "@baseboard_fab2_lib.baseboard_fab2(sch_1):page161_i65:b" )
			)
			( pin "R1B22.1"
				( objectStatus "@baseboard_fab2_lib.baseboard_fab2(sch_1):page161_i67:a" )
			)
			( pin "R1B22.2"
				( objectStatus "@baseboard_fab2_lib.baseboard_fab2(sch_1):page161_i67:b" )
			)
			( pin "C1B15.1"
				( objectStatus "@baseboard_fab2_lib.baseboard_fab2(sch_1):page161_i68:a" )
			)
			( pin "C1B15.2"
				( objectStatus "@baseboard_fab2_lib.baseboard_fab2(sch_1):page161_i68:b" )
			)
			( pin "R1B21.1"
				( objectStatus "@baseboard_fab2_lib.baseboard_fab2(sch_1):page161_i70:a" )
			)
			( pin "R1B21.2"
				( objectStatus "@baseboard_fab2_lib.baseboard_fab2(sch_1):page161_i70:b" )
			)
			( pin "U8G2.2"
				( objectStatus "@baseboard_fab2_lib.baseboard_fab2(sch_1):page161_i88:a" )
			)
			( pin "U8G2.4"
				( objectStatus "@baseboard_fab2_lib.baseboard_fab2(sch_1):page161_i88:y" )
			)
			( pin "C2U27.1"
				( objectStatus "@baseboard_fab2_lib.baseboard_fab2(sch_1):page161_i90:a" )
			)
			( pin "C2U27.2"
				( objectStatus "@baseboard_fab2_lib.baseboard_fab2(sch_1):page161_i90:b" )
			)
			( pin "U8G3.2"
				( objectStatus "@baseboard_fab2_lib.baseboard_fab2(sch_1):page161_i92:a" )
			)
			( pin "U8G3.4"
				( objectStatus "@baseboard_fab2_lib.baseboard_fab2(sch_1):page161_i92:y" )
			)
			( pin "C2U28.1"
				( objectStatus "@baseboard_fab2_lib.baseboard_fab2(sch_1):page161_i93:a" )
			)
			( pin "C2U28.2"
				( objectStatus "@baseboard_fab2_lib.baseboard_fab2(sch_1):page161_i93:b" )
			)
			( pin "R2U42.1"
				( objectStatus "@baseboard_fab2_lib.baseboard_fab2(sch_1):page161_i99:a" )
			)
			( pin "R2U42.2"
				( objectStatus "@baseboard_fab2_lib.baseboard_fab2(sch_1):page161_i99:b" )
			)
			( pin "R2U44.1"
				( objectStatus "@baseboard_fab2_lib.baseboard_fab2(sch_1):page161_i102:a" )
			)
			( pin "R2U44.2"
				( objectStatus "@baseboard_fab2_lib.baseboard_fab2(sch_1):page161_i102:b" )
			)
			( pin "C1E22.1"
				( objectStatus "@baseboard_fab2_lib.baseboard_fab2(sch_1):page161_i113:a" )
			)
			( pin "C1E22.2"
				( objectStatus "@baseboard_fab2_lib.baseboard_fab2(sch_1):page161_i113:b" )
			)
			( pin "R1E11.1"
				( objectStatus "@baseboard_fab2_lib.baseboard_fab2(sch_1):page161_i120:a" )
			)
			( pin "R1E11.2"
				( objectStatus "@baseboard_fab2_lib.baseboard_fab2(sch_1):page161_i120:b" )
			)
			( pin "U1E2.1"
				( objectStatus "@baseboard_fab2_lib.baseboard_fab2(sch_1):page161_i121:a(0)" )
			)
			( pin "U1E2.2"
				( objectStatus "@baseboard_fab2_lib.baseboard_fab2(sch_1):page161_i121:b(0)" )
			)
			( pin "U1E2.4"
				( objectStatus "@baseboard_fab2_lib.baseboard_fab2(sch_1):page161_i121:y(0)" )
			)
			( pin "CR1B3.2"
				( objectStatus "@baseboard_fab2_lib.baseboard_fab2(sch_1):page161_i123:a" )
			)
			( pin "CR1B3.1"
				( objectStatus "@baseboard_fab2_lib.baseboard_fab2(sch_1):page161_i123:c" )
			)
			( pin "R1B23.1"
				( objectStatus "@baseboard_fab2_lib.baseboard_fab2(sch_1):page161_i124:a" )
			)
			( pin "R1B23.2"
				( objectStatus "@baseboard_fab2_lib.baseboard_fab2(sch_1):page161_i124:b" )
			)
			( pin "R1B24.1"
				( objectStatus "@baseboard_fab2_lib.baseboard_fab2(sch_1):page161_i126:a" )
			)
			( pin "R1B24.2"
				( objectStatus "@baseboard_fab2_lib.baseboard_fab2(sch_1):page161_i126:b" )
			)
			( pin "C1B17.1"
				( objectStatus "@baseboard_fab2_lib.baseboard_fab2(sch_1):page161_i128:a" )
			)
			( pin "C1B17.2"
				( objectStatus "@baseboard_fab2_lib.baseboard_fab2(sch_1):page161_i128:b" )
			)
			( pin "CR1F2.2"
				( objectStatus "@baseboard_fab2_lib.baseboard_fab2(sch_1):page161_i133:a" )
			)
			( pin "CR1F2.1"
				( objectStatus "@baseboard_fab2_lib.baseboard_fab2(sch_1):page161_i133:c" )
			)
			( pin "R9T7.1"
				( objectStatus "@baseboard_fab2_lib.baseboard_fab2(sch_1):page161_i134:a" )
			)
			( pin "R9T7.2"
				( objectStatus "@baseboard_fab2_lib.baseboard_fab2(sch_1):page161_i134:b" )
			)
			( pin "R9T5.1"
				( objectStatus "@baseboard_fab2_lib.baseboard_fab2(sch_1):page161_i135:a" )
			)
			( pin "R9T5.2"
				( objectStatus "@baseboard_fab2_lib.baseboard_fab2(sch_1):page161_i135:b" )
			)
			( pin "C9T1.1"
				( objectStatus "@baseboard_fab2_lib.baseboard_fab2(sch_1):page161_i137:a" )
			)
			( pin "C9T1.2"
				( objectStatus "@baseboard_fab2_lib.baseboard_fab2(sch_1):page161_i137:b" )
			)
			( pin "R8F16.1"
				( objectStatus "@baseboard_fab2_lib.baseboard_fab2(sch_1):page162_i8:a" )
			)
			( pin "R8F16.2"
				( objectStatus "@baseboard_fab2_lib.baseboard_fab2(sch_1):page162_i8:b" )
			)
			( pin "R8F14.1"
				( objectStatus "@baseboard_fab2_lib.baseboard_fab2(sch_1):page162_i9:a" )
			)
			( pin "R8F14.2"
				( objectStatus "@baseboard_fab2_lib.baseboard_fab2(sch_1):page162_i9:b" )
			)
			( pin "R8F12.1"
				( objectStatus "@baseboard_fab2_lib.baseboard_fab2(sch_1):page162_i13:a" )
			)
			( pin "R8F12.2"
				( objectStatus "@baseboard_fab2_lib.baseboard_fab2(sch_1):page162_i13:b" )
			)
			( pin "R8F34.1"
				( objectStatus "@baseboard_fab2_lib.baseboard_fab2(sch_1):page162_i22:a" )
			)
			( pin "R8F34.2"
				( objectStatus "@baseboard_fab2_lib.baseboard_fab2(sch_1):page162_i22:b" )
			)
			( pin "R8F13.1"
				( objectStatus "@baseboard_fab2_lib.baseboard_fab2(sch_1):page162_i23:a" )
			)
			( pin "R8F13.2"
				( objectStatus "@baseboard_fab2_lib.baseboard_fab2(sch_1):page162_i23:b" )
			)
			( pin "R8F35.1"
				( objectStatus "@baseboard_fab2_lib.baseboard_fab2(sch_1):page162_i24:a" )
			)
			( pin "R8F35.2"
				( objectStatus "@baseboard_fab2_lib.baseboard_fab2(sch_1):page162_i24:b" )
			)
			( pin "C8F5.1"
				( objectStatus "@baseboard_fab2_lib.baseboard_fab2(sch_1):page162_i28:a" )
			)
			( pin "C8F5.2"
				( objectStatus "@baseboard_fab2_lib.baseboard_fab2(sch_1):page162_i28:b" )
			)
			( pin "C8F4.1"
				( objectStatus "@baseboard_fab2_lib.baseboard_fab2(sch_1):page162_i30:a" )
			)
			( pin "C8F4.2"
				( objectStatus "@baseboard_fab2_lib.baseboard_fab2(sch_1):page162_i30:b" )
			)
			( pin "U8F2.16"
				( objectStatus "@baseboard_fab2_lib.baseboard_fab2(sch_1):page162_i32:clk" )
			)
			( pin "U8F2.7"
				( objectStatus "@baseboard_fab2_lib.baseboard_fab2(sch_1):page162_i32:cs_n" )
			)
			( pin "U8F2.15"
				( objectStatus "@baseboard_fab2_lib.baseboard_fab2(sch_1):page162_i32:di_io(0)" )
			)
			( pin "U8F2.8"
				( objectStatus "@baseboard_fab2_lib.baseboard_fab2(sch_1):page162_i32:do_io(1)" )
			)
			( pin "U8F2.10"
				( objectStatus "@baseboard_fab2_lib.baseboard_fab2(sch_1):page162_i32:gnd" )
			)
			( pin "U8F2.1"
				( objectStatus "@baseboard_fab2_lib.baseboard_fab2(sch_1):page162_i32:hold_n_io(3)" )
			)
			( pin "U8F2.4"
				( objectStatus "@baseboard_fab2_lib.baseboard_fab2(sch_1):page162_i32:nc(0)" )
			)
			( pin "U8F2.5"
				( objectStatus "@baseboard_fab2_lib.baseboard_fab2(sch_1):page162_i32:nc(1)" )
			)
			( pin "U8F2.6"
				( objectStatus "@baseboard_fab2_lib.baseboard_fab2(sch_1):page162_i32:nc(2)" )
			)
			( pin "U8F2.11"
				( objectStatus "@baseboard_fab2_lib.baseboard_fab2(sch_1):page162_i32:nc(3)" )
			)
			( pin "U8F2.12"
				( objectStatus "@baseboard_fab2_lib.baseboard_fab2(sch_1):page162_i32:nc(4)" )
			)
			( pin "U8F2.13"
				( objectStatus "@baseboard_fab2_lib.baseboard_fab2(sch_1):page162_i32:nc(5)" )
			)
			( pin "U8F2.14"
				( objectStatus "@baseboard_fab2_lib.baseboard_fab2(sch_1):page162_i32:nc(6)" )
			)
			( pin "U8F2.3"
				( objectStatus "@baseboard_fab2_lib.baseboard_fab2(sch_1):page162_i32:reset_n" )
			)
			( pin "U8F2.2"
				( objectStatus "@baseboard_fab2_lib.baseboard_fab2(sch_1):page162_i32:vcc" )
			)
			( pin "U8F2.9"
				( objectStatus "@baseboard_fab2_lib.baseboard_fab2(sch_1):page162_i32:wp_n_io(2)" )
			)
			( pin "U1B2.5"
				( objectStatus "@baseboard_fab2_lib.baseboard_fab2(sch_1):page163_i1:en" )
			)
			( pin "U1B2.2"
				( objectStatus "@baseboard_fab2_lib.baseboard_fab2(sch_1):page163_i1:scla" )
			)
			( pin "U1B2.7"
				( objectStatus "@baseboard_fab2_lib.baseboard_fab2(sch_1):page163_i1:sclb" )
			)
			( pin "U1B2.3"
				( objectStatus "@baseboard_fab2_lib.baseboard_fab2(sch_1):page163_i1:sdaa" )
			)
			( pin "U1B2.6"
				( objectStatus "@baseboard_fab2_lib.baseboard_fab2(sch_1):page163_i1:sdab" )
			)
			( pin "U1B2.1"
				( objectStatus "@baseboard_fab2_lib.baseboard_fab2(sch_1):page163_i1:vcca" )
			)
			( pin "U1B2.8"
				( objectStatus "@baseboard_fab2_lib.baseboard_fab2(sch_1):page163_i1:vccb" )
			)
			( pin "R6N8.1"
				( objectStatus "@baseboard_fab2_lib.baseboard_fab2(sch_1):page163_i2:a" )
			)
			( pin "R6N8.2"
				( objectStatus "@baseboard_fab2_lib.baseboard_fab2(sch_1):page163_i2:b" )
			)
			( pin "R6N9.1"
				( objectStatus "@baseboard_fab2_lib.baseboard_fab2(sch_1):page163_i3:a" )
			)
			( pin "R6N9.2"
				( objectStatus "@baseboard_fab2_lib.baseboard_fab2(sch_1):page163_i3:b" )
			)
			( pin "R9M18.1"
				( objectStatus "@baseboard_fab2_lib.baseboard_fab2(sch_1):page163_i6:a" )
			)
			( pin "R9M18.2"
				( objectStatus "@baseboard_fab2_lib.baseboard_fab2(sch_1):page163_i6:b" )
			)
			( pin "R9M19.1"
				( objectStatus "@baseboard_fab2_lib.baseboard_fab2(sch_1):page163_i7:a" )
			)
			( pin "R9M19.2"
				( objectStatus "@baseboard_fab2_lib.baseboard_fab2(sch_1):page163_i7:b" )
			)
			( pin "C9M8.1"
				( objectStatus "@baseboard_fab2_lib.baseboard_fab2(sch_1):page163_i10:a" )
			)
			( pin "C9M8.2"
				( objectStatus "@baseboard_fab2_lib.baseboard_fab2(sch_1):page163_i10:b" )
			)
			( pin "C9M7.1"
				( objectStatus "@baseboard_fab2_lib.baseboard_fab2(sch_1):page163_i12:a" )
			)
			( pin "C9M7.2"
				( objectStatus "@baseboard_fab2_lib.baseboard_fab2(sch_1):page163_i12:b" )
			)
			( pin "R9M17.1"
				( objectStatus "@baseboard_fab2_lib.baseboard_fab2(sch_1):page163_i15:a" )
			)
			( pin "R9M17.2"
				( objectStatus "@baseboard_fab2_lib.baseboard_fab2(sch_1):page163_i15:b" )
			)
			( pin "R9M16.1"
				( objectStatus "@baseboard_fab2_lib.baseboard_fab2(sch_1):page163_i16:a" )
			)
			( pin "R9M16.2"
				( objectStatus "@baseboard_fab2_lib.baseboard_fab2(sch_1):page163_i16:b" )
			)
			( pin "R9M14.1"
				( objectStatus "@baseboard_fab2_lib.baseboard_fab2(sch_1):page163_i20:a" )
			)
			( pin "R9M14.2"
				( objectStatus "@baseboard_fab2_lib.baseboard_fab2(sch_1):page163_i20:b" )
			)
			( pin "R9M13.1"
				( objectStatus "@baseboard_fab2_lib.baseboard_fab2(sch_1):page163_i21:a" )
			)
			( pin "R9M13.2"
				( objectStatus "@baseboard_fab2_lib.baseboard_fab2(sch_1):page163_i21:b" )
			)
			( pin "R9M12.1"
				( objectStatus "@baseboard_fab2_lib.baseboard_fab2(sch_1):page163_i24:a" )
			)
			( pin "R9M12.2"
				( objectStatus "@baseboard_fab2_lib.baseboard_fab2(sch_1):page163_i24:b" )
			)
			( pin "R9M15.1"
				( objectStatus "@baseboard_fab2_lib.baseboard_fab2(sch_1):page163_i25:a" )
			)
			( pin "R9M15.2"
				( objectStatus "@baseboard_fab2_lib.baseboard_fab2(sch_1):page163_i25:b" )
			)
			( pin "R1T10.1"
				( objectStatus "@baseboard_fab2_lib.baseboard_fab2(sch_1):page164_i5:a" )
			)
			( pin "R1T10.2"
				( objectStatus "@baseboard_fab2_lib.baseboard_fab2(sch_1):page164_i5:b" )
			)
			( pin "R1T12.1"
				( objectStatus "@baseboard_fab2_lib.baseboard_fab2(sch_1):page164_i6:a" )
			)
			( pin "R1T12.2"
				( objectStatus "@baseboard_fab2_lib.baseboard_fab2(sch_1):page164_i6:b" )
			)
			( pin "R1T11.1"
				( objectStatus "@baseboard_fab2_lib.baseboard_fab2(sch_1):page164_i7:a" )
			)
			( pin "R1T11.2"
				( objectStatus "@baseboard_fab2_lib.baseboard_fab2(sch_1):page164_i7:b" )
			)
			( pin "R1T5.1"
				( objectStatus "@baseboard_fab2_lib.baseboard_fab2(sch_1):page164_i11:a" )
			)
			( pin "R1T5.2"
				( objectStatus "@baseboard_fab2_lib.baseboard_fab2(sch_1):page164_i11:b" )
			)
			( pin "R1T6.1"
				( objectStatus "@baseboard_fab2_lib.baseboard_fab2(sch_1):page164_i13:a" )
			)
			( pin "R1T6.2"
				( objectStatus "@baseboard_fab2_lib.baseboard_fab2(sch_1):page164_i13:b" )
			)
			( pin "R1T4.1"
				( objectStatus "@baseboard_fab2_lib.baseboard_fab2(sch_1):page164_i14:a" )
			)
			( pin "R1T4.2"
				( objectStatus "@baseboard_fab2_lib.baseboard_fab2(sch_1):page164_i14:b" )
			)
			( pin "R1U18.1"
				( objectStatus "@baseboard_fab2_lib.baseboard_fab2(sch_1):page164_i19:a" )
			)
			( pin "R1U18.2"
				( objectStatus "@baseboard_fab2_lib.baseboard_fab2(sch_1):page164_i19:b" )
			)
			( pin "R1U16.1"
				( objectStatus "@baseboard_fab2_lib.baseboard_fab2(sch_1):page164_i20:a" )
			)
			( pin "R1U16.2"
				( objectStatus "@baseboard_fab2_lib.baseboard_fab2(sch_1):page164_i20:b" )
			)
			( pin "R1U17.1"
				( objectStatus "@baseboard_fab2_lib.baseboard_fab2(sch_1):page164_i21:a" )
			)
			( pin "R1U17.2"
				( objectStatus "@baseboard_fab2_lib.baseboard_fab2(sch_1):page164_i21:b" )
			)
			( pin "R1U15.1"
				( objectStatus "@baseboard_fab2_lib.baseboard_fab2(sch_1):page164_i22:a" )
			)
			( pin "R1U15.2"
				( objectStatus "@baseboard_fab2_lib.baseboard_fab2(sch_1):page164_i22:b" )
			)
			( pin "R1U21.1"
				( objectStatus "@baseboard_fab2_lib.baseboard_fab2(sch_1):page164_i24:a" )
			)
			( pin "R1U21.2"
				( objectStatus "@baseboard_fab2_lib.baseboard_fab2(sch_1):page164_i24:b" )
			)
			( pin "R1U24.1"
				( objectStatus "@baseboard_fab2_lib.baseboard_fab2(sch_1):page164_i25:a" )
			)
			( pin "R1U24.2"
				( objectStatus "@baseboard_fab2_lib.baseboard_fab2(sch_1):page164_i25:b" )
			)
			( pin "R1U22.1"
				( objectStatus "@baseboard_fab2_lib.baseboard_fab2(sch_1):page164_i27:a" )
			)
			( pin "R1U22.2"
				( objectStatus "@baseboard_fab2_lib.baseboard_fab2(sch_1):page164_i27:b" )
			)
			( pin "R1U23.1"
				( objectStatus "@baseboard_fab2_lib.baseboard_fab2(sch_1):page164_i28:a" )
			)
			( pin "R1U23.2"
				( objectStatus "@baseboard_fab2_lib.baseboard_fab2(sch_1):page164_i28:b" )
			)
			( pin "R2N17.1"
				( objectStatus "@baseboard_fab2_lib.baseboard_fab2(sch_1):page164_i29:a" )
			)
			( pin "R2N17.2"
				( objectStatus "@baseboard_fab2_lib.baseboard_fab2(sch_1):page164_i29:b" )
			)
			( pin "R2N18.1"
				( objectStatus "@baseboard_fab2_lib.baseboard_fab2(sch_1):page164_i32:a" )
			)
			( pin "R2N18.2"
				( objectStatus "@baseboard_fab2_lib.baseboard_fab2(sch_1):page164_i32:b" )
			)
			( pin "EU9G1.7"
				( objectStatus "@baseboard_fab2_lib.baseboard_fab2(sch_1):page165_i52:a0" )
			)
			( pin "EU9G1.8"
				( objectStatus "@baseboard_fab2_lib.baseboard_fab2(sch_1):page165_i52:a1" )
			)
			( pin "EU9G1.4"
				( objectStatus "@baseboard_fab2_lib.baseboard_fab2(sch_1):page165_i52:gnd" )
			)
			( pin "EU9G1.16"
				( objectStatus "@baseboard_fab2_lib.baseboard_fab2(sch_1):page165_i52:in0" )
			)
			( pin "EU9G1.15"
				( objectStatus "@baseboard_fab2_lib.baseboard_fab2(sch_1):page165_i52:in1" )
			)
			( pin "EU9G1.14"
				( objectStatus "@baseboard_fab2_lib.baseboard_fab2(sch_1):page165_i52:in2" )
			)
			( pin "EU9G1.13"
				( objectStatus "@baseboard_fab2_lib.baseboard_fab2(sch_1):page165_i52:in3" )
			)
			( pin "EU9G1.12"
				( objectStatus "@baseboard_fab2_lib.baseboard_fab2(sch_1):page165_i52:in4" )
			)
			( pin "EU9G1.11"
				( objectStatus "@baseboard_fab2_lib.baseboard_fab2(sch_1):page165_i52:in5" )
			)
			( pin "EU9G1.10"
				( objectStatus "@baseboard_fab2_lib.baseboard_fab2(sch_1):page165_i52:in6" )
			)
			( pin "EU9G1.9"
				( objectStatus "@baseboard_fab2_lib.baseboard_fab2(sch_1):page165_i52:in7" )
			)
			( pin "EU9G1.6"
				( objectStatus "@baseboard_fab2_lib.baseboard_fab2(sch_1):page165_i52:int_n" )
			)
			( pin "EU9G1.3"
				( objectStatus "@baseboard_fab2_lib.baseboard_fab2(sch_1):page165_i52:scl" )
			)
			( pin "EU9G1.2"
				( objectStatus "@baseboard_fab2_lib.baseboard_fab2(sch_1):page165_i52:sda" )
			)
			( pin "EU9G1.5"
				( objectStatus "@baseboard_fab2_lib.baseboard_fab2(sch_1):page165_i52:vp" )
			)
			( pin "EU9G1.1"
				( objectStatus "@baseboard_fab2_lib.baseboard_fab2(sch_1):page165_i52:vref" )
			)
			( pin "R1U45.1"
				( objectStatus "@baseboard_fab2_lib.baseboard_fab2(sch_1):page165_i55:a" )
			)
			( pin "R1U45.2"
				( objectStatus "@baseboard_fab2_lib.baseboard_fab2(sch_1):page165_i55:b" )
			)
			( pin "R1U48.1"
				( objectStatus "@baseboard_fab2_lib.baseboard_fab2(sch_1):page165_i56:a" )
			)
			( pin "R1U48.2"
				( objectStatus "@baseboard_fab2_lib.baseboard_fab2(sch_1):page165_i56:b" )
			)
			( pin "R9G23.1"
				( objectStatus "@baseboard_fab2_lib.baseboard_fab2(sch_1):page165_i57:a" )
			)
			( pin "R9G23.2"
				( objectStatus "@baseboard_fab2_lib.baseboard_fab2(sch_1):page165_i57:b" )
			)
			( pin "R9G25.1"
				( objectStatus "@baseboard_fab2_lib.baseboard_fab2(sch_1):page165_i58:a" )
			)
			( pin "R9G25.2"
				( objectStatus "@baseboard_fab2_lib.baseboard_fab2(sch_1):page165_i58:b" )
			)
			( pin "C9G19.1"
				( objectStatus "@baseboard_fab2_lib.baseboard_fab2(sch_1):page165_i61:a" )
			)
			( pin "C9G19.2"
				( objectStatus "@baseboard_fab2_lib.baseboard_fab2(sch_1):page165_i61:b" )
			)
			( pin "C1U20.1"
				( objectStatus "@baseboard_fab2_lib.baseboard_fab2(sch_1):page165_i67:a" )
			)
			( pin "C1U20.2"
				( objectStatus "@baseboard_fab2_lib.baseboard_fab2(sch_1):page165_i67:b" )
			)
			( pin "R9G21.1"
				( objectStatus "@baseboard_fab2_lib.baseboard_fab2(sch_1):page165_i69:a" )
			)
			( pin "R9G21.2"
				( objectStatus "@baseboard_fab2_lib.baseboard_fab2(sch_1):page165_i69:b" )
			)
			( pin "FB1U2.1"
				( objectStatus "@baseboard_fab2_lib.baseboard_fab2(sch_1):page165_i79:a" )
			)
			( pin "FB1U2.2"
				( objectStatus "@baseboard_fab2_lib.baseboard_fab2(sch_1):page165_i79:b" )
			)
			( pin "R1U40.1"
				( objectStatus "@baseboard_fab2_lib.baseboard_fab2(sch_1):page165_i81:a" )
			)
			( pin "R1U40.2"
				( objectStatus "@baseboard_fab2_lib.baseboard_fab2(sch_1):page165_i81:b" )
			)
			( pin "R7C18.1"
				( objectStatus "@baseboard_fab2_lib.baseboard_fab2(sch_1):page166_i11:a" )
			)
			( pin "R7C18.2"
				( objectStatus "@baseboard_fab2_lib.baseboard_fab2(sch_1):page166_i11:b" )
			)
			( pin "R7C22.1"
				( objectStatus "@baseboard_fab2_lib.baseboard_fab2(sch_1):page166_i14:a" )
			)
			( pin "R7C22.2"
				( objectStatus "@baseboard_fab2_lib.baseboard_fab2(sch_1):page166_i14:b" )
			)
			( pin "R7C19.1"
				( objectStatus "@baseboard_fab2_lib.baseboard_fab2(sch_1):page166_i15:a" )
			)
			( pin "R7C19.2"
				( objectStatus "@baseboard_fab2_lib.baseboard_fab2(sch_1):page166_i15:b" )
			)
			( pin "R7C17.1"
				( objectStatus "@baseboard_fab2_lib.baseboard_fab2(sch_1):page166_i28:a" )
			)
			( pin "R7C17.2"
				( objectStatus "@baseboard_fab2_lib.baseboard_fab2(sch_1):page166_i28:b" )
			)
			( pin "R7D15.1"
				( objectStatus "@baseboard_fab2_lib.baseboard_fab2(sch_1):page166_i32:a" )
			)
			( pin "R7D15.2"
				( objectStatus "@baseboard_fab2_lib.baseboard_fab2(sch_1):page166_i32:b" )
			)
			( pin "U9B4.4"
				( objectStatus "@baseboard_fab2_lib.baseboard_fab2(sch_1):page167_i1:a(0)" )
			)
			( pin "U9B4.3"
				( objectStatus "@baseboard_fab2_lib.baseboard_fab2(sch_1):page167_i1:a(1)" )
			)
			( pin "U9B4.2"
				( objectStatus "@baseboard_fab2_lib.baseboard_fab2(sch_1):page167_i1:dxn" )
			)
			( pin "U9B4.1"
				( objectStatus "@baseboard_fab2_lib.baseboard_fab2(sch_1):page167_i1:dxp" )
			)
			( pin "U9B4.5"
				( objectStatus "@baseboard_fab2_lib.baseboard_fab2(sch_1):page167_i1:gnd" )
			)
			( pin "U9B4.7"
				( objectStatus "@baseboard_fab2_lib.baseboard_fab2(sch_1):page167_i1:scl" )
			)
			( pin "U9B4.6"
				( objectStatus "@baseboard_fab2_lib.baseboard_fab2(sch_1):page167_i1:sda" )
			)
			( pin "U9B4.8"
				( objectStatus "@baseboard_fab2_lib.baseboard_fab2(sch_1):page167_i1:vp" )
			)
			( pin "Q9B1.1"
				( objectStatus "@baseboard_fab2_lib.baseboard_fab2(sch_1):page167_i3:b" )
			)
			( pin "Q9B1.3"
				( objectStatus "@baseboard_fab2_lib.baseboard_fab2(sch_1):page167_i3:c" )
			)
			( pin "Q9B1.2"
				( objectStatus "@baseboard_fab2_lib.baseboard_fab2(sch_1):page167_i3:e" )
			)
			( pin "R9B5.1"
				( objectStatus "@baseboard_fab2_lib.baseboard_fab2(sch_1):page167_i5:a" )
			)
			( pin "R9B5.2"
				( objectStatus "@baseboard_fab2_lib.baseboard_fab2(sch_1):page167_i5:b" )
			)
			( pin "R9B4.1"
				( objectStatus "@baseboard_fab2_lib.baseboard_fab2(sch_1):page167_i6:a" )
			)
			( pin "R9B4.2"
				( objectStatus "@baseboard_fab2_lib.baseboard_fab2(sch_1):page167_i6:b" )
			)
			( pin "C1M4.1"
				( objectStatus "@baseboard_fab2_lib.baseboard_fab2(sch_1):page167_i7:a" )
			)
			( pin "C1M4.2"
				( objectStatus "@baseboard_fab2_lib.baseboard_fab2(sch_1):page167_i7:b" )
			)
			( pin "R1M9.1"
				( objectStatus "@baseboard_fab2_lib.baseboard_fab2(sch_1):page167_i8:a" )
			)
			( pin "R1M9.2"
				( objectStatus "@baseboard_fab2_lib.baseboard_fab2(sch_1):page167_i8:b" )
			)
			( pin "R9B8.1"
				( objectStatus "@baseboard_fab2_lib.baseboard_fab2(sch_1):page167_i10:a" )
			)
			( pin "R9B8.2"
				( objectStatus "@baseboard_fab2_lib.baseboard_fab2(sch_1):page167_i10:b" )
			)
			( pin "C1E19.1"
				( objectStatus "@baseboard_fab2_lib.baseboard_fab2(sch_1):page167_i24:a" )
			)
			( pin "C1E19.2"
				( objectStatus "@baseboard_fab2_lib.baseboard_fab2(sch_1):page167_i24:b" )
			)
			( pin "R9R5.1"
				( objectStatus "@baseboard_fab2_lib.baseboard_fab2(sch_1):page167_i25:a" )
			)
			( pin "R9R5.2"
				( objectStatus "@baseboard_fab2_lib.baseboard_fab2(sch_1):page167_i25:b" )
			)
			( pin "R9R6.1"
				( objectStatus "@baseboard_fab2_lib.baseboard_fab2(sch_1):page167_i26:a" )
			)
			( pin "R9R6.2"
				( objectStatus "@baseboard_fab2_lib.baseboard_fab2(sch_1):page167_i26:b" )
			)
			( pin "Q1E1.1"
				( objectStatus "@baseboard_fab2_lib.baseboard_fab2(sch_1):page167_i27:b" )
			)
			( pin "Q1E1.3"
				( objectStatus "@baseboard_fab2_lib.baseboard_fab2(sch_1):page167_i27:c" )
			)
			( pin "Q1E1.2"
				( objectStatus "@baseboard_fab2_lib.baseboard_fab2(sch_1):page167_i27:e" )
			)
			( pin "U1E1.4"
				( objectStatus "@baseboard_fab2_lib.baseboard_fab2(sch_1):page167_i30:a(0)" )
			)
			( pin "U1E1.3"
				( objectStatus "@baseboard_fab2_lib.baseboard_fab2(sch_1):page167_i30:a(1)" )
			)
			( pin "U1E1.2"
				( objectStatus "@baseboard_fab2_lib.baseboard_fab2(sch_1):page167_i30:dxn" )
			)
			( pin "U1E1.1"
				( objectStatus "@baseboard_fab2_lib.baseboard_fab2(sch_1):page167_i30:dxp" )
			)
			( pin "U1E1.5"
				( objectStatus "@baseboard_fab2_lib.baseboard_fab2(sch_1):page167_i30:gnd" )
			)
			( pin "U1E1.7"
				( objectStatus "@baseboard_fab2_lib.baseboard_fab2(sch_1):page167_i30:scl" )
			)
			( pin "U1E1.6"
				( objectStatus "@baseboard_fab2_lib.baseboard_fab2(sch_1):page167_i30:sda" )
			)
			( pin "U1E1.8"
				( objectStatus "@baseboard_fab2_lib.baseboard_fab2(sch_1):page167_i30:vp" )
			)
			( pin "R1E9.1"
				( objectStatus "@baseboard_fab2_lib.baseboard_fab2(sch_1):page167_i34:a" )
			)
			( pin "R1E9.2"
				( objectStatus "@baseboard_fab2_lib.baseboard_fab2(sch_1):page167_i34:b" )
			)
			( pin "R9B6.1"
				( objectStatus "@baseboard_fab2_lib.baseboard_fab2(sch_1):page167_i35:a" )
			)
			( pin "R9B6.2"
				( objectStatus "@baseboard_fab2_lib.baseboard_fab2(sch_1):page167_i35:b" )
			)
			( pin "R1E10.1"
				( objectStatus "@baseboard_fab2_lib.baseboard_fab2(sch_1):page167_i38:a" )
			)
			( pin "R1E10.2"
				( objectStatus "@baseboard_fab2_lib.baseboard_fab2(sch_1):page167_i38:b" )
			)
			( pin "C9B7.1"
				( objectStatus "@baseboard_fab2_lib.baseboard_fab2(sch_1):page167_i39:a" )
			)
			( pin "C9B7.2"
				( objectStatus "@baseboard_fab2_lib.baseboard_fab2(sch_1):page167_i39:b" )
			)
			( pin "C9R14.1"
				( objectStatus "@baseboard_fab2_lib.baseboard_fab2(sch_1):page167_i41:a" )
			)
			( pin "C9R14.2"
				( objectStatus "@baseboard_fab2_lib.baseboard_fab2(sch_1):page167_i41:b" )
			)
			( pin "C9R13.1"
				( objectStatus "@baseboard_fab2_lib.baseboard_fab2(sch_1):page167_i42:a" )
			)
			( pin "C9R13.2"
				( objectStatus "@baseboard_fab2_lib.baseboard_fab2(sch_1):page167_i42:b" )
			)
			( pin "U8D4.1"
				( objectStatus "@baseboard_fab2_lib.baseboard_fab2(sch_1):page167_i49:a0" )
			)
			( pin "U8D4.2"
				( objectStatus "@baseboard_fab2_lib.baseboard_fab2(sch_1):page167_i49:a1" )
			)
			( pin "U8D4.3"
				( objectStatus "@baseboard_fab2_lib.baseboard_fab2(sch_1):page167_i49:a2" )
			)
			( pin "U8D4.6"
				( objectStatus "@baseboard_fab2_lib.baseboard_fab2(sch_1):page167_i49:scl" )
			)
			( pin "U8D4.5"
				( objectStatus "@baseboard_fab2_lib.baseboard_fab2(sch_1):page167_i49:sda" )
			)
			( pin "U8D4.7"
				( objectStatus "@baseboard_fab2_lib.baseboard_fab2(sch_1):page167_i49:wp" )
			)
			( pin "R8D27.1"
				( objectStatus "@baseboard_fab2_lib.baseboard_fab2(sch_1):page167_i50:a" )
			)
			( pin "R8D27.2"
				( objectStatus "@baseboard_fab2_lib.baseboard_fab2(sch_1):page167_i50:b" )
			)
			( pin "R9G15.1"
				( objectStatus "@baseboard_fab2_lib.baseboard_fab2(sch_1):page167_i58:a" )
			)
			( pin "R9G15.2"
				( objectStatus "@baseboard_fab2_lib.baseboard_fab2(sch_1):page167_i58:b" )
			)
			( pin "R8D28.1"
				( objectStatus "@baseboard_fab2_lib.baseboard_fab2(sch_1):page167_i70:a" )
			)
			( pin "R8D28.2"
				( objectStatus "@baseboard_fab2_lib.baseboard_fab2(sch_1):page167_i70:b" )
			)
			( pin "R1M8.1"
				( objectStatus "@baseboard_fab2_lib.baseboard_fab2(sch_1):page167_i74:a" )
			)
			( pin "R1M8.2"
				( objectStatus "@baseboard_fab2_lib.baseboard_fab2(sch_1):page167_i74:b" )
			)
			( pin "R9R7.1"
				( objectStatus "@baseboard_fab2_lib.baseboard_fab2(sch_1):page167_i75:a" )
			)
			( pin "R9R7.2"
				( objectStatus "@baseboard_fab2_lib.baseboard_fab2(sch_1):page167_i75:b" )
			)
			( pin "R9R8.1"
				( objectStatus "@baseboard_fab2_lib.baseboard_fab2(sch_1):page167_i76:a" )
			)
			( pin "R9R8.2"
				( objectStatus "@baseboard_fab2_lib.baseboard_fab2(sch_1):page167_i76:b" )
			)
			( pin "R9G14.1"
				( objectStatus "@baseboard_fab2_lib.baseboard_fab2(sch_1):page167_i77:a" )
			)
			( pin "R9G14.2"
				( objectStatus "@baseboard_fab2_lib.baseboard_fab2(sch_1):page167_i77:b" )
			)
			( pin "R1U31.1"
				( objectStatus "@baseboard_fab2_lib.baseboard_fab2(sch_1):page167_i78:a" )
			)
			( pin "R1U31.2"
				( objectStatus "@baseboard_fab2_lib.baseboard_fab2(sch_1):page167_i78:b" )
			)
			( pin "R1U25.1"
				( objectStatus "@baseboard_fab2_lib.baseboard_fab2(sch_1):page167_i79:a" )
			)
			( pin "R1U25.2"
				( objectStatus "@baseboard_fab2_lib.baseboard_fab2(sch_1):page167_i79:b" )
			)
			( pin "R2U38.1"
				( objectStatus "@baseboard_fab2_lib.baseboard_fab2(sch_1):page167_i80:a" )
			)
			( pin "R2U38.2"
				( objectStatus "@baseboard_fab2_lib.baseboard_fab2(sch_1):page167_i80:b" )
			)
			( pin "R2U39.1"
				( objectStatus "@baseboard_fab2_lib.baseboard_fab2(sch_1):page167_i83:a" )
			)
			( pin "R2U39.2"
				( objectStatus "@baseboard_fab2_lib.baseboard_fab2(sch_1):page167_i83:b" )
			)
			( pin "R8D24.1"
				( objectStatus "@baseboard_fab2_lib.baseboard_fab2(sch_1):page167_i84:a" )
			)
			( pin "R8D24.2"
				( objectStatus "@baseboard_fab2_lib.baseboard_fab2(sch_1):page167_i84:b" )
			)
			( pin "R8D23.1"
				( objectStatus "@baseboard_fab2_lib.baseboard_fab2(sch_1):page167_i85:a" )
			)
			( pin "R8D23.2"
				( objectStatus "@baseboard_fab2_lib.baseboard_fab2(sch_1):page167_i85:b" )
			)
			( pin "CR1L1.2"
				( objectStatus "@baseboard_fab2_lib.baseboard_fab2(sch_1):page168_i2:a" )
			)
			( pin "CR1L1.1"
				( objectStatus "@baseboard_fab2_lib.baseboard_fab2(sch_1):page168_i2:c" )
			)
			( pin "CR1L2.2"
				( objectStatus "@baseboard_fab2_lib.baseboard_fab2(sch_1):page168_i3:a" )
			)
			( pin "CR1L2.1"
				( objectStatus "@baseboard_fab2_lib.baseboard_fab2(sch_1):page168_i3:c" )
			)
			( pin "CR1L3.2"
				( objectStatus "@baseboard_fab2_lib.baseboard_fab2(sch_1):page168_i4:a" )
			)
			( pin "CR1L3.1"
				( objectStatus "@baseboard_fab2_lib.baseboard_fab2(sch_1):page168_i4:c" )
			)
			( pin "CR1L4.2"
				( objectStatus "@baseboard_fab2_lib.baseboard_fab2(sch_1):page168_i5:a" )
			)
			( pin "CR1L4.1"
				( objectStatus "@baseboard_fab2_lib.baseboard_fab2(sch_1):page168_i5:c" )
			)
			( pin "R1L6.1"
				( objectStatus "@baseboard_fab2_lib.baseboard_fab2(sch_1):page168_i6:a" )
			)
			( pin "R1L6.2"
				( objectStatus "@baseboard_fab2_lib.baseboard_fab2(sch_1):page168_i6:b" )
			)
			( pin "R6W17.1"
				( objectStatus "@baseboard_fab2_lib.baseboard_fab2(sch_1):page144_i89:a" )
			)
			( pin "R6W17.2"
				( objectStatus "@baseboard_fab2_lib.baseboard_fab2(sch_1):page144_i89:b" )
			)
			( pin "Q1L3.1"
				( objectStatus "@baseboard_fab2_lib.baseboard_fab2(sch_1):page168_i8:b" )
			)
			( pin "Q1L3.3"
				( objectStatus "@baseboard_fab2_lib.baseboard_fab2(sch_1):page168_i8:c" )
			)
			( pin "Q1L3.2"
				( objectStatus "@baseboard_fab2_lib.baseboard_fab2(sch_1):page168_i8:e" )
			)
			( pin "R6W18.1"
				( objectStatus "@baseboard_fab2_lib.baseboard_fab2(sch_1):page144_i90:a" )
			)
			( pin "R6W18.2"
				( objectStatus "@baseboard_fab2_lib.baseboard_fab2(sch_1):page144_i90:b" )
			)
			( pin "R1L36.1"
				( objectStatus "@baseboard_fab2_lib.baseboard_fab2(sch_1):page168_i11:a" )
			)
			( pin "R1L36.2"
				( objectStatus "@baseboard_fab2_lib.baseboard_fab2(sch_1):page168_i11:b" )
			)
			( pin "Q1L4.3"
				( objectStatus "@baseboard_fab2_lib.baseboard_fab2(sch_1):page168_i18:drain(0)" )
			)
			( pin "Q1L4.5"
				( objectStatus "@baseboard_fab2_lib.baseboard_fab2(sch_1):page168_i18:gate(0)" )
			)
			( pin "Q1L4.4"
				( objectStatus "@baseboard_fab2_lib.baseboard_fab2(sch_1):page168_i18:source(0)" )
			)
			( pin "Q1L4.6"
				( objectStatus "@baseboard_fab2_lib.baseboard_fab2(sch_1):page168_i19:drain(0)" )
			)
			( pin "Q1L4.2"
				( objectStatus "@baseboard_fab2_lib.baseboard_fab2(sch_1):page168_i19:gate(0)" )
			)
			( pin "Q1L4.1"
				( objectStatus "@baseboard_fab2_lib.baseboard_fab2(sch_1):page168_i19:source(0)" )
			)
			( pin "R1L38.1"
				( objectStatus "@baseboard_fab2_lib.baseboard_fab2(sch_1):page168_i22:a" )
			)
			( pin "R1L38.2"
				( objectStatus "@baseboard_fab2_lib.baseboard_fab2(sch_1):page168_i22:b" )
			)
			( pin "C1U21.1"
				( objectStatus "@baseboard_fab2_lib.baseboard_fab2(sch_1):page169_i56:a" )
			)
			( pin "C1U21.2"
				( objectStatus "@baseboard_fab2_lib.baseboard_fab2(sch_1):page169_i56:b" )
			)
			( pin "FB1U3.1"
				( objectStatus "@baseboard_fab2_lib.baseboard_fab2(sch_1):page169_i57:a" )
			)
			( pin "FB1U3.2"
				( objectStatus "@baseboard_fab2_lib.baseboard_fab2(sch_1):page169_i57:b" )
			)
			( pin "C9G21.1"
				( objectStatus "@baseboard_fab2_lib.baseboard_fab2(sch_1):page169_i68:a" )
			)
			( pin "C9G21.2"
				( objectStatus "@baseboard_fab2_lib.baseboard_fab2(sch_1):page169_i68:b" )
			)
			( pin "C9G17.1"
				( objectStatus "@baseboard_fab2_lib.baseboard_fab2(sch_1):page169_i80:a" )
			)
			( pin "C9G17.2"
				( objectStatus "@baseboard_fab2_lib.baseboard_fab2(sch_1):page169_i80:b" )
			)
			( pin "R1U32.1"
				( objectStatus "@baseboard_fab2_lib.baseboard_fab2(sch_1):page169_i82:a" )
			)
			( pin "R1U32.2"
				( objectStatus "@baseboard_fab2_lib.baseboard_fab2(sch_1):page169_i82:b" )
			)
			( pin "R1U33.1"
				( objectStatus "@baseboard_fab2_lib.baseboard_fab2(sch_1):page169_i83:a" )
			)
			( pin "R1U33.2"
				( objectStatus "@baseboard_fab2_lib.baseboard_fab2(sch_1):page169_i83:b" )
			)
			( pin "C9G20.1"
				( objectStatus "@baseboard_fab2_lib.baseboard_fab2(sch_1):page169_i86:a" )
			)
			( pin "C9G20.2"
				( objectStatus "@baseboard_fab2_lib.baseboard_fab2(sch_1):page169_i86:b" )
			)
			( pin "R1U39.1"
				( objectStatus "@baseboard_fab2_lib.baseboard_fab2(sch_1):page169_i88:a" )
			)
			( pin "R1U39.2"
				( objectStatus "@baseboard_fab2_lib.baseboard_fab2(sch_1):page169_i88:b" )
			)
			( pin "R9G26.1"
				( objectStatus "@baseboard_fab2_lib.baseboard_fab2(sch_1):page169_i106:a" )
			)
			( pin "R9G26.2"
				( objectStatus "@baseboard_fab2_lib.baseboard_fab2(sch_1):page169_i106:b" )
			)
			( pin "C9G22.1"
				( objectStatus "@baseboard_fab2_lib.baseboard_fab2(sch_1):page169_i108:a" )
			)
			( pin "C9G22.2"
				( objectStatus "@baseboard_fab2_lib.baseboard_fab2(sch_1):page169_i108:b" )
			)
			( pin "R1U38.1"
				( objectStatus "@baseboard_fab2_lib.baseboard_fab2(sch_1):page169_i114:a" )
			)
			( pin "R1U38.2"
				( objectStatus "@baseboard_fab2_lib.baseboard_fab2(sch_1):page169_i114:b" )
			)
			( pin "R1U47.1"
				( objectStatus "@baseboard_fab2_lib.baseboard_fab2(sch_1):page169_i115:a" )
			)
			( pin "R1U47.2"
				( objectStatus "@baseboard_fab2_lib.baseboard_fab2(sch_1):page169_i115:b" )
			)
			( pin "R1U44.1"
				( objectStatus "@baseboard_fab2_lib.baseboard_fab2(sch_1):page169_i116:a" )
			)
			( pin "R1U44.2"
				( objectStatus "@baseboard_fab2_lib.baseboard_fab2(sch_1):page169_i116:b" )
			)
			( pin "R1U50.1"
				( objectStatus "@baseboard_fab2_lib.baseboard_fab2(sch_1):page169_i126:a" )
			)
			( pin "R1U50.2"
				( objectStatus "@baseboard_fab2_lib.baseboard_fab2(sch_1):page169_i126:b" )
			)
			( pin "C9G15.1"
				( objectStatus "@baseboard_fab2_lib.baseboard_fab2(sch_1):page169_i139:a" )
			)
			( pin "C9G15.2"
				( objectStatus "@baseboard_fab2_lib.baseboard_fab2(sch_1):page169_i139:b" )
			)
			( pin "R1U29.1"
				( objectStatus "@baseboard_fab2_lib.baseboard_fab2(sch_1):page169_i141:a" )
			)
			( pin "R1U29.2"
				( objectStatus "@baseboard_fab2_lib.baseboard_fab2(sch_1):page169_i141:b" )
			)
			( pin "R1U28.1"
				( objectStatus "@baseboard_fab2_lib.baseboard_fab2(sch_1):page169_i142:a" )
			)
			( pin "R1U28.2"
				( objectStatus "@baseboard_fab2_lib.baseboard_fab2(sch_1):page169_i142:b" )
			)
			( pin "C9G14.1"
				( objectStatus "@baseboard_fab2_lib.baseboard_fab2(sch_1):page169_i146:a" )
			)
			( pin "C9G14.2"
				( objectStatus "@baseboard_fab2_lib.baseboard_fab2(sch_1):page169_i146:b" )
			)
			( pin "R1U26.1"
				( objectStatus "@baseboard_fab2_lib.baseboard_fab2(sch_1):page169_i148:a" )
			)
			( pin "R1U26.2"
				( objectStatus "@baseboard_fab2_lib.baseboard_fab2(sch_1):page169_i148:b" )
			)
			( pin "R1U27.1"
				( objectStatus "@baseboard_fab2_lib.baseboard_fab2(sch_1):page169_i149:a" )
			)
			( pin "R1U27.2"
				( objectStatus "@baseboard_fab2_lib.baseboard_fab2(sch_1):page169_i149:b" )
			)
			( pin "C9G18.1"
				( objectStatus "@baseboard_fab2_lib.baseboard_fab2(sch_1):page169_i153:a" )
			)
			( pin "C9G18.2"
				( objectStatus "@baseboard_fab2_lib.baseboard_fab2(sch_1):page169_i153:b" )
			)
			( pin "FB1U4.1"
				( objectStatus "@baseboard_fab2_lib.baseboard_fab2(sch_1):page169_i155:a" )
			)
			( pin "FB1U4.2"
				( objectStatus "@baseboard_fab2_lib.baseboard_fab2(sch_1):page169_i155:b" )
			)
			( pin "Q9G1.3"
				( objectStatus "@baseboard_fab2_lib.baseboard_fab2(sch_1):page169_i157:drain(0)" )
			)
			( pin "Q9G1.5"
				( objectStatus "@baseboard_fab2_lib.baseboard_fab2(sch_1):page169_i157:gate(0)" )
			)
			( pin "Q9G1.4"
				( objectStatus "@baseboard_fab2_lib.baseboard_fab2(sch_1):page169_i157:source(0)" )
			)
			( pin "Q9G1.6"
				( objectStatus "@baseboard_fab2_lib.baseboard_fab2(sch_1):page169_i162:drain(0)" )
			)
			( pin "Q9G1.2"
				( objectStatus "@baseboard_fab2_lib.baseboard_fab2(sch_1):page169_i162:gate(0)" )
			)
			( pin "Q9G1.1"
				( objectStatus "@baseboard_fab2_lib.baseboard_fab2(sch_1):page169_i162:source(0)" )
			)
			( pin "R1U49.1"
				( objectStatus "@baseboard_fab2_lib.baseboard_fab2(sch_1):page169_i163:a" )
			)
			( pin "R1U49.2"
				( objectStatus "@baseboard_fab2_lib.baseboard_fab2(sch_1):page169_i163:b" )
			)
			( pin "R9G35.1"
				( objectStatus "@baseboard_fab2_lib.baseboard_fab2(sch_1):page169_i164:a" )
			)
			( pin "R9G35.2"
				( objectStatus "@baseboard_fab2_lib.baseboard_fab2(sch_1):page169_i164:b" )
			)
			( pin "R2P3.1"
				( objectStatus "@baseboard_fab2_lib.baseboard_fab2(sch_1):page170_i2:a" )
			)
			( pin "R2P3.2"
				( objectStatus "@baseboard_fab2_lib.baseboard_fab2(sch_1):page170_i2:b" )
			)
			( pin "U8D3.2"
				( objectStatus "@baseboard_fab2_lib.baseboard_fab2(sch_1):page170_i4:a" )
			)
			( pin "U8D3.4"
				( objectStatus "@baseboard_fab2_lib.baseboard_fab2(sch_1):page170_i4:y" )
			)
			( pin "C2P1.1"
				( objectStatus "@baseboard_fab2_lib.baseboard_fab2(sch_1):page170_i8:a" )
			)
			( pin "C2P1.2"
				( objectStatus "@baseboard_fab2_lib.baseboard_fab2(sch_1):page170_i8:b" )
			)
			( pin "U8E1.1"
				( objectStatus "@baseboard_fab2_lib.baseboard_fab2(sch_1):page170_i10:a(0)" )
			)
			( pin "U8E1.2"
				( objectStatus "@baseboard_fab2_lib.baseboard_fab2(sch_1):page170_i10:b(0)" )
			)
			( pin "U8E1.3"
				( objectStatus "@baseboard_fab2_lib.baseboard_fab2(sch_1):page170_i10:y(0)" )
			)
			( pin "U8E1.4"
				( objectStatus "@baseboard_fab2_lib.baseboard_fab2(sch_1):page170_i11:a(0)" )
			)
			( pin "U8E1.5"
				( objectStatus "@baseboard_fab2_lib.baseboard_fab2(sch_1):page170_i11:b(0)" )
			)
			( pin "U8E1.6"
				( objectStatus "@baseboard_fab2_lib.baseboard_fab2(sch_1):page170_i11:y(0)" )
			)
			( pin "U8E1.12"
				( objectStatus "@baseboard_fab2_lib.baseboard_fab2(sch_1):page170_i12:a(0)" )
			)
			( pin "U8E1.13"
				( objectStatus "@baseboard_fab2_lib.baseboard_fab2(sch_1):page170_i12:b(0)" )
			)
			( pin "U8E1.11"
				( objectStatus "@baseboard_fab2_lib.baseboard_fab2(sch_1):page170_i12:y(0)" )
			)
			( pin "U1R2.2"
				( objectStatus "@baseboard_fab2_lib.baseboard_fab2(sch_1):page170_i20:a" )
			)
			( pin "U1R2.1"
				( objectStatus "@baseboard_fab2_lib.baseboard_fab2(sch_1):page170_i20:oe" )
			)
			( pin "U1R2.4"
				( objectStatus "@baseboard_fab2_lib.baseboard_fab2(sch_1):page170_i20:y" )
			)
			( pin "C1R27.1"
				( objectStatus "@baseboard_fab2_lib.baseboard_fab2(sch_1):page170_i30:a" )
			)
			( pin "C1R27.2"
				( objectStatus "@baseboard_fab2_lib.baseboard_fab2(sch_1):page170_i30:b" )
			)
			( pin "C8D2.1"
				( objectStatus "@baseboard_fab2_lib.baseboard_fab2(sch_1):page170_i33:a" )
			)
			( pin "C8D2.2"
				( objectStatus "@baseboard_fab2_lib.baseboard_fab2(sch_1):page170_i33:b" )
			)
			( pin "U8D5.2"
				( objectStatus "@baseboard_fab2_lib.baseboard_fab2(sch_1):page170_i38:a" )
			)
			( pin "U8D5.1"
				( objectStatus "@baseboard_fab2_lib.baseboard_fab2(sch_1):page170_i38:oe" )
			)
			( pin "U8D5.4"
				( objectStatus "@baseboard_fab2_lib.baseboard_fab2(sch_1):page170_i38:y" )
			)
			( pin "C8E2.1"
				( objectStatus "@baseboard_fab2_lib.baseboard_fab2(sch_1):page170_i40:a" )
			)
			( pin "C8E2.2"
				( objectStatus "@baseboard_fab2_lib.baseboard_fab2(sch_1):page170_i40:b" )
			)
			( pin "C8D3.1"
				( objectStatus "@baseboard_fab2_lib.baseboard_fab2(sch_1):page170_i42:a" )
			)
			( pin "C8D3.2"
				( objectStatus "@baseboard_fab2_lib.baseboard_fab2(sch_1):page170_i42:b" )
			)
			( pin "U1R1.2"
				( objectStatus "@baseboard_fab2_lib.baseboard_fab2(sch_1):page170_i46:a" )
			)
			( pin "U1R1.4"
				( objectStatus "@baseboard_fab2_lib.baseboard_fab2(sch_1):page170_i46:y" )
			)
			( pin "C1R28.1"
				( objectStatus "@baseboard_fab2_lib.baseboard_fab2(sch_1):page170_i49:a" )
			)
			( pin "C1R28.2"
				( objectStatus "@baseboard_fab2_lib.baseboard_fab2(sch_1):page170_i49:b" )
			)
			( pin "R1R8.1"
				( objectStatus "@baseboard_fab2_lib.baseboard_fab2(sch_1):page170_i51:a" )
			)
			( pin "R1R8.2"
				( objectStatus "@baseboard_fab2_lib.baseboard_fab2(sch_1):page170_i51:b" )
			)
			( pin "R2P8.1"
				( objectStatus "@baseboard_fab2_lib.baseboard_fab2(sch_1):page170_i52:a" )
			)
			( pin "R2P8.2"
				( objectStatus "@baseboard_fab2_lib.baseboard_fab2(sch_1):page170_i52:b" )
			)
			( pin "R2T3.1"
				( objectStatus "@baseboard_fab2_lib.baseboard_fab2(sch_1):page170_i54:a" )
			)
			( pin "R2T3.2"
				( objectStatus "@baseboard_fab2_lib.baseboard_fab2(sch_1):page170_i54:b" )
			)
			( pin "R2P5.1"
				( objectStatus "@baseboard_fab2_lib.baseboard_fab2(sch_1):page170_i56:a" )
			)
			( pin "R2P5.2"
				( objectStatus "@baseboard_fab2_lib.baseboard_fab2(sch_1):page170_i56:b" )
			)
			( pin "Q2P1.3"
				( objectStatus "@baseboard_fab2_lib.baseboard_fab2(sch_1):page170_i58:drn" )
			)
			( pin "Q2P1.1"
				( objectStatus "@baseboard_fab2_lib.baseboard_fab2(sch_1):page170_i58:gate" )
			)
			( pin "Q2P1.2"
				( objectStatus "@baseboard_fab2_lib.baseboard_fab2(sch_1):page170_i58:src" )
			)
			( pin "R2P13.1"
				( objectStatus "@baseboard_fab2_lib.baseboard_fab2(sch_1):page170_i61:a" )
			)
			( pin "R2P13.2"
				( objectStatus "@baseboard_fab2_lib.baseboard_fab2(sch_1):page170_i61:b" )
			)
			( pin "R2P11.1"
				( objectStatus "@baseboard_fab2_lib.baseboard_fab2(sch_1):page170_i63:a" )
			)
			( pin "R2P11.2"
				( objectStatus "@baseboard_fab2_lib.baseboard_fab2(sch_1):page170_i63:b" )
			)
			( pin "R9F3.1"
				( objectStatus "@baseboard_fab2_lib.baseboard_fab2(sch_1):page170_i65:a" )
			)
			( pin "R9F3.2"
				( objectStatus "@baseboard_fab2_lib.baseboard_fab2(sch_1):page170_i65:b" )
			)
			( pin "Q8F2.3"
				( objectStatus "@baseboard_fab2_lib.baseboard_fab2(sch_1):page170_i67:drn" )
			)
			( pin "Q8F2.1"
				( objectStatus "@baseboard_fab2_lib.baseboard_fab2(sch_1):page170_i67:gate" )
			)
			( pin "Q8F2.2"
				( objectStatus "@baseboard_fab2_lib.baseboard_fab2(sch_1):page170_i67:src" )
			)
			( pin "R8D26.1"
				( objectStatus "@baseboard_fab2_lib.baseboard_fab2(sch_1):page170_i71:a" )
			)
			( pin "R8D26.2"
				( objectStatus "@baseboard_fab2_lib.baseboard_fab2(sch_1):page170_i71:b" )
			)
			( pin "R1R5.1"
				( objectStatus "@baseboard_fab2_lib.baseboard_fab2(sch_1):page170_i73:a" )
			)
			( pin "R1R5.2"
				( objectStatus "@baseboard_fab2_lib.baseboard_fab2(sch_1):page170_i73:b" )
			)
			( pin "R2P4.1"
				( objectStatus "@baseboard_fab2_lib.baseboard_fab2(sch_1):page170_i74:a" )
			)
			( pin "R2P4.2"
				( objectStatus "@baseboard_fab2_lib.baseboard_fab2(sch_1):page170_i74:b" )
			)
			( pin "C2L49.1"
				( objectStatus "@baseboard_fab2_lib.baseboard_fab2(sch_1):page172_i5:a" )
			)
			( pin "C2L49.2"
				( objectStatus "@baseboard_fab2_lib.baseboard_fab2(sch_1):page172_i5:b" )
			)
			( pin "C2L52.1"
				( objectStatus "@baseboard_fab2_lib.baseboard_fab2(sch_1):page172_i6:a" )
			)
			( pin "C2L52.2"
				( objectStatus "@baseboard_fab2_lib.baseboard_fab2(sch_1):page172_i6:b" )
			)
			( pin "C2L50.1"
				( objectStatus "@baseboard_fab2_lib.baseboard_fab2(sch_1):page172_i7:a" )
			)
			( pin "C2L50.2"
				( objectStatus "@baseboard_fab2_lib.baseboard_fab2(sch_1):page172_i7:b" )
			)
			( pin "C2L51.1"
				( objectStatus "@baseboard_fab2_lib.baseboard_fab2(sch_1):page172_i8:a" )
			)
			( pin "C2L51.2"
				( objectStatus "@baseboard_fab2_lib.baseboard_fab2(sch_1):page172_i8:b" )
			)
			( pin "J8A3.7"
				( objectStatus "@baseboard_fab2_lib.baseboard_fab2(sch_1):page172_i17:gnd(0)" )
			)
			( pin "J8A3.4"
				( objectStatus "@baseboard_fab2_lib.baseboard_fab2(sch_1):page172_i17:gnd(1)" )
			)
			( pin "J8A3.1"
				( objectStatus "@baseboard_fab2_lib.baseboard_fab2(sch_1):page172_i17:gnd(2)" )
			)
			( pin "J8A3.MH1"
				( objectStatus "@baseboard_fab2_lib.baseboard_fab2(sch_1):page172_i17:mh1" )
			)
			( pin "J8A3.MH2"
				( objectStatus "@baseboard_fab2_lib.baseboard_fab2(sch_1):page172_i17:mh2" )
			)
			( pin "J8A3.5"
				( objectStatus "@baseboard_fab2_lib.baseboard_fab2(sch_1):page172_i17:sata_rxn" )
			)
			( pin "J8A3.6"
				( objectStatus "@baseboard_fab2_lib.baseboard_fab2(sch_1):page172_i17:sata_rxp" )
			)
			( pin "J8A3.3"
				( objectStatus "@baseboard_fab2_lib.baseboard_fab2(sch_1):page172_i17:sata_txn" )
			)
			( pin "J8A3.2"
				( objectStatus "@baseboard_fab2_lib.baseboard_fab2(sch_1):page172_i17:sata_txp" )
			)
			( pin "J8A4.1"
				( objectStatus "@baseboard_fab2_lib.baseboard_fab2(sch_1):page172_i25:io1" )
			)
			( pin "J8A4.2"
				( objectStatus "@baseboard_fab2_lib.baseboard_fab2(sch_1):page172_i25:io2" )
			)
			( pin "J8A4.3"
				( objectStatus "@baseboard_fab2_lib.baseboard_fab2(sch_1):page172_i25:io3" )
			)
			( pin "J8A4.4"
				( objectStatus "@baseboard_fab2_lib.baseboard_fab2(sch_1):page172_i25:io4" )
			)
			( pin "C9B2.1"
				( objectStatus "@baseboard_fab2_lib.baseboard_fab2(sch_1):page172_i36:a" )
			)
			( pin "C9B2.2"
				( objectStatus "@baseboard_fab2_lib.baseboard_fab2(sch_1):page172_i36:b" )
			)
			( pin "F9B1.1"
				( objectStatus "@baseboard_fab2_lib.baseboard_fab2(sch_1):page172_i38:a(0)" )
			)
			( pin "F9B1.2"
				( objectStatus "@baseboard_fab2_lib.baseboard_fab2(sch_1):page172_i38:b(0)" )
			)
			( pin "C9B1.1"
				( objectStatus "@baseboard_fab2_lib.baseboard_fab2(sch_1):page172_i39:a" )
			)
			( pin "C9B1.2"
				( objectStatus "@baseboard_fab2_lib.baseboard_fab2(sch_1):page172_i39:b" )
			)
			( pin "F8B1.1"
				( objectStatus "@baseboard_fab2_lib.baseboard_fab2(sch_1):page172_i41:a(0)" )
			)
			( pin "F8B1.2"
				( objectStatus "@baseboard_fab2_lib.baseboard_fab2(sch_1):page172_i41:b(0)" )
			)
			( pin "J2M1.7"
				( objectStatus "@baseboard_fab2_lib.baseboard_fab2(sch_1):page172_i52:gnd(0)" )
			)
			( pin "J2M1.4"
				( objectStatus "@baseboard_fab2_lib.baseboard_fab2(sch_1):page172_i52:gnd(1)" )
			)
			( pin "J2M1.1"
				( objectStatus "@baseboard_fab2_lib.baseboard_fab2(sch_1):page172_i52:gnd(2)" )
			)
			( pin "J2M1.MH1"
				( objectStatus "@baseboard_fab2_lib.baseboard_fab2(sch_1):page172_i52:mh1" )
			)
			( pin "J2M1.MH2"
				( objectStatus "@baseboard_fab2_lib.baseboard_fab2(sch_1):page172_i52:mh2" )
			)
			( pin "J2M1.5"
				( objectStatus "@baseboard_fab2_lib.baseboard_fab2(sch_1):page172_i52:sata_rxn" )
			)
			( pin "J2M1.6"
				( objectStatus "@baseboard_fab2_lib.baseboard_fab2(sch_1):page172_i52:sata_rxp" )
			)
			( pin "J2M1.3"
				( objectStatus "@baseboard_fab2_lib.baseboard_fab2(sch_1):page172_i52:sata_txn" )
			)
			( pin "J2M1.2"
				( objectStatus "@baseboard_fab2_lib.baseboard_fab2(sch_1):page172_i52:sata_txp" )
			)
			( pin "J2L1.1"
				( objectStatus "@baseboard_fab2_lib.baseboard_fab2(sch_1):page172_i53:io1" )
			)
			( pin "J2L1.2"
				( objectStatus "@baseboard_fab2_lib.baseboard_fab2(sch_1):page172_i53:io2" )
			)
			( pin "J2L1.3"
				( objectStatus "@baseboard_fab2_lib.baseboard_fab2(sch_1):page172_i53:io3" )
			)
			( pin "J2L1.4"
				( objectStatus "@baseboard_fab2_lib.baseboard_fab2(sch_1):page172_i53:io4" )
			)
			( pin "J8A1.2D9"
				( objectStatus "@baseboard_fab2_lib.baseboard_fab2(sch_1):page173_i163:gnd(0)" )
			)
			( pin "J8A1.2D6"
				( objectStatus "@baseboard_fab2_lib.baseboard_fab2(sch_1):page173_i163:gnd(1)" )
			)
			( pin "J8A1.2D3"
				( objectStatus "@baseboard_fab2_lib.baseboard_fab2(sch_1):page173_i163:gnd(2)" )
			)
			( pin "J8A1.2C9"
				( objectStatus "@baseboard_fab2_lib.baseboard_fab2(sch_1):page173_i163:gnd(3)" )
			)
			( pin "J8A1.2C6"
				( objectStatus "@baseboard_fab2_lib.baseboard_fab2(sch_1):page173_i163:gnd(4)" )
			)
			( pin "J8A1.2C3"
				( objectStatus "@baseboard_fab2_lib.baseboard_fab2(sch_1):page173_i163:gnd(5)" )
			)
			( pin "J8A1.2B9"
				( objectStatus "@baseboard_fab2_lib.baseboard_fab2(sch_1):page173_i163:gnd(6)" )
			)
			( pin "J8A1.2B6"
				( objectStatus "@baseboard_fab2_lib.baseboard_fab2(sch_1):page173_i163:gnd(7)" )
			)
			( pin "J8A1.2B3"
				( objectStatus "@baseboard_fab2_lib.baseboard_fab2(sch_1):page173_i163:gnd(8)" )
			)
			( pin "J8A1.2A9"
				( objectStatus "@baseboard_fab2_lib.baseboard_fab2(sch_1):page173_i163:gnd(9)" )
			)
			( pin "J8A1.2A6"
				( objectStatus "@baseboard_fab2_lib.baseboard_fab2(sch_1):page173_i163:gnd(10)" )
			)
			( pin "J8A1.2A3"
				( objectStatus "@baseboard_fab2_lib.baseboard_fab2(sch_1):page173_i163:gnd(11)" )
			)
			( pin "J8A1.1D9"
				( objectStatus "@baseboard_fab2_lib.baseboard_fab2(sch_1):page173_i163:gnd(12)" )
			)
			( pin "J8A1.1D6"
				( objectStatus "@baseboard_fab2_lib.baseboard_fab2(sch_1):page173_i163:gnd(13)" )
			)
			( pin "J8A1.1D3"
				( objectStatus "@baseboard_fab2_lib.baseboard_fab2(sch_1):page173_i163:gnd(14)" )
			)
			( pin "J8A1.1C9"
				( objectStatus "@baseboard_fab2_lib.baseboard_fab2(sch_1):page173_i163:gnd(15)" )
			)
			( pin "J8A1.1C6"
				( objectStatus "@baseboard_fab2_lib.baseboard_fab2(sch_1):page173_i163:gnd(16)" )
			)
			( pin "J8A1.1C3"
				( objectStatus "@baseboard_fab2_lib.baseboard_fab2(sch_1):page173_i163:gnd(17)" )
			)
			( pin "J8A1.1B9"
				( objectStatus "@baseboard_fab2_lib.baseboard_fab2(sch_1):page173_i163:gnd(18)" )
			)
			( pin "J8A1.1B6"
				( objectStatus "@baseboard_fab2_lib.baseboard_fab2(sch_1):page173_i163:gnd(19)" )
			)
			( pin "J8A1.1B3"
				( objectStatus "@baseboard_fab2_lib.baseboard_fab2(sch_1):page173_i163:gnd(20)" )
			)
			( pin "J8A1.1A9"
				( objectStatus "@baseboard_fab2_lib.baseboard_fab2(sch_1):page173_i163:gnd(21)" )
			)
			( pin "J8A1.1A6"
				( objectStatus "@baseboard_fab2_lib.baseboard_fab2(sch_1):page173_i163:gnd(22)" )
			)
			( pin "J8A1.1A3"
				( objectStatus "@baseboard_fab2_lib.baseboard_fab2(sch_1):page173_i163:gnd(23)" )
			)
			( pin "J8A1.1B5"
				( objectStatus "@baseboard_fab2_lib.baseboard_fab2(sch_1):page173_i163:rxa0_dn" )
			)
			( pin "J8A1.1B4"
				( objectStatus "@baseboard_fab2_lib.baseboard_fab2(sch_1):page173_i163:rxa0_dp" )
			)
			( pin "J8A1.1A5"
				( objectStatus "@baseboard_fab2_lib.baseboard_fab2(sch_1):page173_i163:rxa1_dn" )
			)
			( pin "J8A1.1A4"
				( objectStatus "@baseboard_fab2_lib.baseboard_fab2(sch_1):page173_i163:rxa1_dp" )
			)
			( pin "J8A1.1B8"
				( objectStatus "@baseboard_fab2_lib.baseboard_fab2(sch_1):page173_i163:rxa2_dn" )
			)
			( pin "J8A1.1B7"
				( objectStatus "@baseboard_fab2_lib.baseboard_fab2(sch_1):page173_i163:rxa2_dp" )
			)
			( pin "J8A1.1A8"
				( objectStatus "@baseboard_fab2_lib.baseboard_fab2(sch_1):page173_i163:rxa3_dn" )
			)
			( pin "J8A1.1A7"
				( objectStatus "@baseboard_fab2_lib.baseboard_fab2(sch_1):page173_i163:rxa3_dp" )
			)
			( pin "J8A1.2B5"
				( objectStatus "@baseboard_fab2_lib.baseboard_fab2(sch_1):page173_i163:rxb0_dn" )
			)
			( pin "J8A1.2B4"
				( objectStatus "@baseboard_fab2_lib.baseboard_fab2(sch_1):page173_i163:rxb0_dp" )
			)
			( pin "J8A1.2A5"
				( objectStatus "@baseboard_fab2_lib.baseboard_fab2(sch_1):page173_i163:rxb1_dn" )
			)
			( pin "J8A1.2A4"
				( objectStatus "@baseboard_fab2_lib.baseboard_fab2(sch_1):page173_i163:rxb1_dp" )
			)
			( pin "J8A1.2B8"
				( objectStatus "@baseboard_fab2_lib.baseboard_fab2(sch_1):page173_i163:rxb2_dn" )
			)
			( pin "J8A1.2B7"
				( objectStatus "@baseboard_fab2_lib.baseboard_fab2(sch_1):page173_i163:rxb2_dp" )
			)
			( pin "J8A1.2A8"
				( objectStatus "@baseboard_fab2_lib.baseboard_fab2(sch_1):page173_i163:rxb3_dn" )
			)
			( pin "J8A1.2A7"
				( objectStatus "@baseboard_fab2_lib.baseboard_fab2(sch_1):page173_i163:rxb3_dp" )
			)
			( pin "J8A1.1A2"
				( objectStatus "@baseboard_fab2_lib.baseboard_fab2(sch_1):page173_i163:sidebanda_0" )
			)
			( pin "J8A1.1B2"
				( objectStatus "@baseboard_fab2_lib.baseboard_fab2(sch_1):page173_i163:sidebanda_1" )
			)
			( pin "J8A1.1C2"
				( objectStatus "@baseboard_fab2_lib.baseboard_fab2(sch_1):page173_i163:sidebanda_2" )
			)
			( pin "J8A1.1B1"
				( objectStatus "@baseboard_fab2_lib.baseboard_fab2(sch_1):page173_i163:sidebanda_3" )
			)
			( pin "J8A1.1C1"
				( objectStatus "@baseboard_fab2_lib.baseboard_fab2(sch_1):page173_i163:sidebanda_4" )
			)
			( pin "J8A1.1D1"
				( objectStatus "@baseboard_fab2_lib.baseboard_fab2(sch_1):page173_i163:sidebanda_5" )
			)
			( pin "J8A1.1D2"
				( objectStatus "@baseboard_fab2_lib.baseboard_fab2(sch_1):page173_i163:sidebanda_6" )
			)
			( pin "J8A1.1A1"
				( objectStatus "@baseboard_fab2_lib.baseboard_fab2(sch_1):page173_i163:sidebanda_7" )
			)
			( pin "J8A1.2A2"
				( objectStatus "@baseboard_fab2_lib.baseboard_fab2(sch_1):page173_i163:sidebandb_0" )
			)
			( pin "J8A1.2B2"
				( objectStatus "@baseboard_fab2_lib.baseboard_fab2(sch_1):page173_i163:sidebandb_1" )
			)
			( pin "J8A1.2C2"
				( objectStatus "@baseboard_fab2_lib.baseboard_fab2(sch_1):page173_i163:sidebandb_2" )
			)
			( pin "J8A1.2B1"
				( objectStatus "@baseboard_fab2_lib.baseboard_fab2(sch_1):page173_i163:sidebandb_3" )
			)
			( pin "J8A1.2C1"
				( objectStatus "@baseboard_fab2_lib.baseboard_fab2(sch_1):page173_i163:sidebandb_4" )
			)
			( pin "J8A1.2D1"
				( objectStatus "@baseboard_fab2_lib.baseboard_fab2(sch_1):page173_i163:sidebandb_5" )
			)
			( pin "J8A1.2D2"
				( objectStatus "@baseboard_fab2_lib.baseboard_fab2(sch_1):page173_i163:sidebandb_6" )
			)
			( pin "J8A1.2A1"
				( objectStatus "@baseboard_fab2_lib.baseboard_fab2(sch_1):page173_i163:sidebandb_7" )
			)
			( pin "J8A1.1D5"
				( objectStatus "@baseboard_fab2_lib.baseboard_fab2(sch_1):page173_i163:txa0_dn" )
			)
			( pin "J8A1.1D4"
				( objectStatus "@baseboard_fab2_lib.baseboard_fab2(sch_1):page173_i163:txa0_dp" )
			)
			( pin "J8A1.1C5"
				( objectStatus "@baseboard_fab2_lib.baseboard_fab2(sch_1):page173_i163:txa1_dn" )
			)
			( pin "J8A1.1C4"
				( objectStatus "@baseboard_fab2_lib.baseboard_fab2(sch_1):page173_i163:txa1_dp" )
			)
			( pin "J8A1.1D8"
				( objectStatus "@baseboard_fab2_lib.baseboard_fab2(sch_1):page173_i163:txa2_dn" )
			)
			( pin "J8A1.1D7"
				( objectStatus "@baseboard_fab2_lib.baseboard_fab2(sch_1):page173_i163:txa2_dp" )
			)
			( pin "J8A1.1C8"
				( objectStatus "@baseboard_fab2_lib.baseboard_fab2(sch_1):page173_i163:txa3_dn" )
			)
			( pin "J8A1.1C7"
				( objectStatus "@baseboard_fab2_lib.baseboard_fab2(sch_1):page173_i163:txa3_dp" )
			)
			( pin "J8A1.2D5"
				( objectStatus "@baseboard_fab2_lib.baseboard_fab2(sch_1):page173_i163:txb0_dn" )
			)
			( pin "J8A1.2D4"
				( objectStatus "@baseboard_fab2_lib.baseboard_fab2(sch_1):page173_i163:txb0_dp" )
			)
			( pin "J8A1.2C5"
				( objectStatus "@baseboard_fab2_lib.baseboard_fab2(sch_1):page173_i163:txb1_dn" )
			)
			( pin "J8A1.2C4"
				( objectStatus "@baseboard_fab2_lib.baseboard_fab2(sch_1):page173_i163:txb1_dp" )
			)
			( pin "J8A1.2D8"
				( objectStatus "@baseboard_fab2_lib.baseboard_fab2(sch_1):page173_i163:txb2_dn" )
			)
			( pin "J8A1.2D7"
				( objectStatus "@baseboard_fab2_lib.baseboard_fab2(sch_1):page173_i163:txb2_dp" )
			)
			( pin "J8A1.2C8"
				( objectStatus "@baseboard_fab2_lib.baseboard_fab2(sch_1):page173_i163:txb3_dn" )
			)
			( pin "J8A1.2C7"
				( objectStatus "@baseboard_fab2_lib.baseboard_fab2(sch_1):page173_i163:txb3_dp" )
			)
			( pin "C2L13.1"
				( objectStatus "@baseboard_fab2_lib.baseboard_fab2(sch_1):page173_i165:a" )
			)
			( pin "C2L13.2"
				( objectStatus "@baseboard_fab2_lib.baseboard_fab2(sch_1):page173_i165:b" )
			)
			( pin "C2L6.1"
				( objectStatus "@baseboard_fab2_lib.baseboard_fab2(sch_1):page173_i166:a" )
			)
			( pin "C2L6.2"
				( objectStatus "@baseboard_fab2_lib.baseboard_fab2(sch_1):page173_i166:b" )
			)
			( pin "C2L19.1"
				( objectStatus "@baseboard_fab2_lib.baseboard_fab2(sch_1):page173_i172:a" )
			)
			( pin "C2L19.2"
				( objectStatus "@baseboard_fab2_lib.baseboard_fab2(sch_1):page173_i172:b" )
			)
			( pin "C2L10.1"
				( objectStatus "@baseboard_fab2_lib.baseboard_fab2(sch_1):page173_i173:a" )
			)
			( pin "C2L10.2"
				( objectStatus "@baseboard_fab2_lib.baseboard_fab2(sch_1):page173_i173:b" )
			)
			( pin "C2L17.1"
				( objectStatus "@baseboard_fab2_lib.baseboard_fab2(sch_1):page173_i174:a" )
			)
			( pin "C2L17.2"
				( objectStatus "@baseboard_fab2_lib.baseboard_fab2(sch_1):page173_i174:b" )
			)
			( pin "C2L15.1"
				( objectStatus "@baseboard_fab2_lib.baseboard_fab2(sch_1):page173_i191:a" )
			)
			( pin "C2L15.2"
				( objectStatus "@baseboard_fab2_lib.baseboard_fab2(sch_1):page173_i191:b" )
			)
			( pin "C2L4.1"
				( objectStatus "@baseboard_fab2_lib.baseboard_fab2(sch_1):page173_i192:a" )
			)
			( pin "C2L4.2"
				( objectStatus "@baseboard_fab2_lib.baseboard_fab2(sch_1):page173_i192:b" )
			)
			( pin "C2L3.1"
				( objectStatus "@baseboard_fab2_lib.baseboard_fab2(sch_1):page173_i194:a" )
			)
			( pin "C2L3.2"
				( objectStatus "@baseboard_fab2_lib.baseboard_fab2(sch_1):page173_i194:b" )
			)
			( pin "C2L20.1"
				( objectStatus "@baseboard_fab2_lib.baseboard_fab2(sch_1):page173_i195:a" )
			)
			( pin "C2L20.2"
				( objectStatus "@baseboard_fab2_lib.baseboard_fab2(sch_1):page173_i195:b" )
			)
			( pin "C2L12.1"
				( objectStatus "@baseboard_fab2_lib.baseboard_fab2(sch_1):page173_i196:a" )
			)
			( pin "C2L12.2"
				( objectStatus "@baseboard_fab2_lib.baseboard_fab2(sch_1):page173_i196:b" )
			)
			( pin "C2L18.1"
				( objectStatus "@baseboard_fab2_lib.baseboard_fab2(sch_1):page173_i197:a" )
			)
			( pin "C2L18.2"
				( objectStatus "@baseboard_fab2_lib.baseboard_fab2(sch_1):page173_i197:b" )
			)
			( pin "C2L16.1"
				( objectStatus "@baseboard_fab2_lib.baseboard_fab2(sch_1):page173_i205:a" )
			)
			( pin "C2L16.2"
				( objectStatus "@baseboard_fab2_lib.baseboard_fab2(sch_1):page173_i205:b" )
			)
			( pin "C2L7.1"
				( objectStatus "@baseboard_fab2_lib.baseboard_fab2(sch_1):page173_i206:a" )
			)
			( pin "C2L7.2"
				( objectStatus "@baseboard_fab2_lib.baseboard_fab2(sch_1):page173_i206:b" )
			)
			( pin "C2L9.1"
				( objectStatus "@baseboard_fab2_lib.baseboard_fab2(sch_1):page173_i207:a" )
			)
			( pin "C2L9.2"
				( objectStatus "@baseboard_fab2_lib.baseboard_fab2(sch_1):page173_i207:b" )
			)
			( pin "C2L14.1"
				( objectStatus "@baseboard_fab2_lib.baseboard_fab2(sch_1):page173_i208:a" )
			)
			( pin "C2L14.2"
				( objectStatus "@baseboard_fab2_lib.baseboard_fab2(sch_1):page173_i208:b" )
			)
			( pin "C2L5.1"
				( objectStatus "@baseboard_fab2_lib.baseboard_fab2(sch_1):page173_i209:a" )
			)
			( pin "C2L5.2"
				( objectStatus "@baseboard_fab2_lib.baseboard_fab2(sch_1):page173_i209:b" )
			)
			( pin "C2L40.1"
				( objectStatus "@baseboard_fab2_lib.baseboard_fab2(sch_1):page173_i220:a" )
			)
			( pin "C2L40.2"
				( objectStatus "@baseboard_fab2_lib.baseboard_fab2(sch_1):page173_i220:b" )
			)
			( pin "C2L39.1"
				( objectStatus "@baseboard_fab2_lib.baseboard_fab2(sch_1):page173_i221:a" )
			)
			( pin "C2L39.2"
				( objectStatus "@baseboard_fab2_lib.baseboard_fab2(sch_1):page173_i221:b" )
			)
			( pin "C2L43.1"
				( objectStatus "@baseboard_fab2_lib.baseboard_fab2(sch_1):page173_i222:a" )
			)
			( pin "C2L43.2"
				( objectStatus "@baseboard_fab2_lib.baseboard_fab2(sch_1):page173_i222:b" )
			)
			( pin "C2L44.1"
				( objectStatus "@baseboard_fab2_lib.baseboard_fab2(sch_1):page173_i228:a" )
			)
			( pin "C2L44.2"
				( objectStatus "@baseboard_fab2_lib.baseboard_fab2(sch_1):page173_i228:b" )
			)
			( pin "C2L42.1"
				( objectStatus "@baseboard_fab2_lib.baseboard_fab2(sch_1):page173_i233:a" )
			)
			( pin "C2L42.2"
				( objectStatus "@baseboard_fab2_lib.baseboard_fab2(sch_1):page173_i233:b" )
			)
			( pin "C2L22.1"
				( objectStatus "@baseboard_fab2_lib.baseboard_fab2(sch_1):page173_i234:a" )
			)
			( pin "C2L22.2"
				( objectStatus "@baseboard_fab2_lib.baseboard_fab2(sch_1):page173_i234:b" )
			)
			( pin "C2L37.1"
				( objectStatus "@baseboard_fab2_lib.baseboard_fab2(sch_1):page173_i238:a" )
			)
			( pin "C2L37.2"
				( objectStatus "@baseboard_fab2_lib.baseboard_fab2(sch_1):page173_i238:b" )
			)
			( pin "C2L47.1"
				( objectStatus "@baseboard_fab2_lib.baseboard_fab2(sch_1):page173_i239:a" )
			)
			( pin "C2L47.2"
				( objectStatus "@baseboard_fab2_lib.baseboard_fab2(sch_1):page173_i239:b" )
			)
			( pin "C2L27.1"
				( objectStatus "@baseboard_fab2_lib.baseboard_fab2(sch_1):page173_i240:a" )
			)
			( pin "C2L27.2"
				( objectStatus "@baseboard_fab2_lib.baseboard_fab2(sch_1):page173_i240:b" )
			)
			( pin "C2L23.1"
				( objectStatus "@baseboard_fab2_lib.baseboard_fab2(sch_1):page173_i241:a" )
			)
			( pin "C2L23.2"
				( objectStatus "@baseboard_fab2_lib.baseboard_fab2(sch_1):page173_i241:b" )
			)
			( pin "C2L41.1"
				( objectStatus "@baseboard_fab2_lib.baseboard_fab2(sch_1):page173_i242:a" )
			)
			( pin "C2L41.2"
				( objectStatus "@baseboard_fab2_lib.baseboard_fab2(sch_1):page173_i242:b" )
			)
			( pin "C2L26.1"
				( objectStatus "@baseboard_fab2_lib.baseboard_fab2(sch_1):page173_i255:a" )
			)
			( pin "C2L26.2"
				( objectStatus "@baseboard_fab2_lib.baseboard_fab2(sch_1):page173_i255:b" )
			)
			( pin "C2L38.1"
				( objectStatus "@baseboard_fab2_lib.baseboard_fab2(sch_1):page173_i256:a" )
			)
			( pin "C2L38.2"
				( objectStatus "@baseboard_fab2_lib.baseboard_fab2(sch_1):page173_i256:b" )
			)
			( pin "C2L48.1"
				( objectStatus "@baseboard_fab2_lib.baseboard_fab2(sch_1):page173_i257:a" )
			)
			( pin "C2L48.2"
				( objectStatus "@baseboard_fab2_lib.baseboard_fab2(sch_1):page173_i257:b" )
			)
			( pin "C2L24.1"
				( objectStatus "@baseboard_fab2_lib.baseboard_fab2(sch_1):page173_i258:a" )
			)
			( pin "C2L24.2"
				( objectStatus "@baseboard_fab2_lib.baseboard_fab2(sch_1):page173_i258:b" )
			)
			( pin "C2L21.1"
				( objectStatus "@baseboard_fab2_lib.baseboard_fab2(sch_1):page173_i259:a" )
			)
			( pin "C2L21.2"
				( objectStatus "@baseboard_fab2_lib.baseboard_fab2(sch_1):page173_i259:b" )
			)
			( pin "R2L23.1"
				( objectStatus "@baseboard_fab2_lib.baseboard_fab2(sch_1):page173_i261:a" )
			)
			( pin "R2L23.2"
				( objectStatus "@baseboard_fab2_lib.baseboard_fab2(sch_1):page173_i261:b" )
			)
			( pin "R2L21.1"
				( objectStatus "@baseboard_fab2_lib.baseboard_fab2(sch_1):page173_i263:a" )
			)
			( pin "R2L21.2"
				( objectStatus "@baseboard_fab2_lib.baseboard_fab2(sch_1):page173_i263:b" )
			)
			( pin "R2L22.1"
				( objectStatus "@baseboard_fab2_lib.baseboard_fab2(sch_1):page173_i264:a" )
			)
			( pin "R2L22.2"
				( objectStatus "@baseboard_fab2_lib.baseboard_fab2(sch_1):page173_i264:b" )
			)
			( pin "R2L18.1"
				( objectStatus "@baseboard_fab2_lib.baseboard_fab2(sch_1):page173_i266:a" )
			)
			( pin "R2L18.2"
				( objectStatus "@baseboard_fab2_lib.baseboard_fab2(sch_1):page173_i266:b" )
			)
			( pin "R1L3.1"
				( objectStatus "@baseboard_fab2_lib.baseboard_fab2(sch_1):page174_i5:a" )
			)
			( pin "R1L3.2"
				( objectStatus "@baseboard_fab2_lib.baseboard_fab2(sch_1):page174_i5:b" )
			)
			( pin "C1L3.1"
				( objectStatus "@baseboard_fab2_lib.baseboard_fab2(sch_1):page174_i8:a" )
			)
			( pin "C1L3.2"
				( objectStatus "@baseboard_fab2_lib.baseboard_fab2(sch_1):page174_i8:b" )
			)
			( pin "C1L2.1"
				( objectStatus "@baseboard_fab2_lib.baseboard_fab2(sch_1):page174_i9:a" )
			)
			( pin "C1L2.2"
				( objectStatus "@baseboard_fab2_lib.baseboard_fab2(sch_1):page174_i9:b" )
			)
			( pin "C1L7.1"
				( objectStatus "@baseboard_fab2_lib.baseboard_fab2(sch_1):page174_i12:a" )
			)
			( pin "C1L7.2"
				( objectStatus "@baseboard_fab2_lib.baseboard_fab2(sch_1):page174_i12:b" )
			)
			( pin "C1L6.1"
				( objectStatus "@baseboard_fab2_lib.baseboard_fab2(sch_1):page174_i13:a" )
			)
			( pin "C1L6.2"
				( objectStatus "@baseboard_fab2_lib.baseboard_fab2(sch_1):page174_i13:b" )
			)
			( pin "C1L13.1"
				( objectStatus "@baseboard_fab2_lib.baseboard_fab2(sch_1):page174_i14:a" )
			)
			( pin "C1L13.2"
				( objectStatus "@baseboard_fab2_lib.baseboard_fab2(sch_1):page174_i14:b" )
			)
			( pin "C1L15.1"
				( objectStatus "@baseboard_fab2_lib.baseboard_fab2(sch_1):page174_i18:a" )
			)
			( pin "C1L15.2"
				( objectStatus "@baseboard_fab2_lib.baseboard_fab2(sch_1):page174_i18:b" )
			)
			( pin "C1L12.1"
				( objectStatus "@baseboard_fab2_lib.baseboard_fab2(sch_1):page174_i19:a" )
			)
			( pin "C1L12.2"
				( objectStatus "@baseboard_fab2_lib.baseboard_fab2(sch_1):page174_i19:b" )
			)
			( pin "C1L14.1"
				( objectStatus "@baseboard_fab2_lib.baseboard_fab2(sch_1):page174_i20:a" )
			)
			( pin "C1L14.2"
				( objectStatus "@baseboard_fab2_lib.baseboard_fab2(sch_1):page174_i20:b" )
			)
			( pin "R1L1.1"
				( objectStatus "@baseboard_fab2_lib.baseboard_fab2(sch_1):page174_i25:a" )
			)
			( pin "R1L1.2"
				( objectStatus "@baseboard_fab2_lib.baseboard_fab2(sch_1):page174_i25:b" )
			)
			( pin "J8A2.A3"
				( objectStatus "@baseboard_fab2_lib.baseboard_fab2(sch_1):page174_i26:gnd1" )
			)
			( pin "J8A2.A6"
				( objectStatus "@baseboard_fab2_lib.baseboard_fab2(sch_1):page174_i26:gnd2" )
			)
			( pin "J8A2.A9"
				( objectStatus "@baseboard_fab2_lib.baseboard_fab2(sch_1):page174_i26:gnd3" )
			)
			( pin "J8A2.B3"
				( objectStatus "@baseboard_fab2_lib.baseboard_fab2(sch_1):page174_i26:gnd4" )
			)
			( pin "J8A2.B6"
				( objectStatus "@baseboard_fab2_lib.baseboard_fab2(sch_1):page174_i26:gnd5" )
			)
			( pin "J8A2.B9"
				( objectStatus "@baseboard_fab2_lib.baseboard_fab2(sch_1):page174_i26:gnd6" )
			)
			( pin "J8A2.C3"
				( objectStatus "@baseboard_fab2_lib.baseboard_fab2(sch_1):page174_i26:gnd7" )
			)
			( pin "J8A2.C6"
				( objectStatus "@baseboard_fab2_lib.baseboard_fab2(sch_1):page174_i26:gnd8" )
			)
			( pin "J8A2.C9"
				( objectStatus "@baseboard_fab2_lib.baseboard_fab2(sch_1):page174_i26:gnd9" )
			)
			( pin "J8A2.D3"
				( objectStatus "@baseboard_fab2_lib.baseboard_fab2(sch_1):page174_i26:gnd10" )
			)
			( pin "J8A2.D6"
				( objectStatus "@baseboard_fab2_lib.baseboard_fab2(sch_1):page174_i26:gnd11" )
			)
			( pin "J8A2.D9"
				( objectStatus "@baseboard_fab2_lib.baseboard_fab2(sch_1):page174_i26:gnd12" )
			)
			( pin "J8A2.B5"
				( objectStatus "@baseboard_fab2_lib.baseboard_fab2(sch_1):page174_i26:rxa0_dn" )
			)
			( pin "J8A2.B4"
				( objectStatus "@baseboard_fab2_lib.baseboard_fab2(sch_1):page174_i26:rxa0_dp" )
			)
			( pin "J8A2.A5"
				( objectStatus "@baseboard_fab2_lib.baseboard_fab2(sch_1):page174_i26:rxa1_dn" )
			)
			( pin "J8A2.A4"
				( objectStatus "@baseboard_fab2_lib.baseboard_fab2(sch_1):page174_i26:rxa1_dp" )
			)
			( pin "J8A2.B8"
				( objectStatus "@baseboard_fab2_lib.baseboard_fab2(sch_1):page174_i26:rxa2_dn" )
			)
			( pin "J8A2.B7"
				( objectStatus "@baseboard_fab2_lib.baseboard_fab2(sch_1):page174_i26:rxa2_dp" )
			)
			( pin "J8A2.A8"
				( objectStatus "@baseboard_fab2_lib.baseboard_fab2(sch_1):page174_i26:rxa3_dn" )
			)
			( pin "J8A2.A7"
				( objectStatus "@baseboard_fab2_lib.baseboard_fab2(sch_1):page174_i26:rxa3_dp" )
			)
			( pin "J8A2.A2"
				( objectStatus "@baseboard_fab2_lib.baseboard_fab2(sch_1):page174_i26:sideband0" )
			)
			( pin "J8A2.B2"
				( objectStatus "@baseboard_fab2_lib.baseboard_fab2(sch_1):page174_i26:sideband1" )
			)
			( pin "J8A2.C2"
				( objectStatus "@baseboard_fab2_lib.baseboard_fab2(sch_1):page174_i26:sideband2" )
			)
			( pin "J8A2.B1"
				( objectStatus "@baseboard_fab2_lib.baseboard_fab2(sch_1):page174_i26:sideband3" )
			)
			( pin "J8A2.C1"
				( objectStatus "@baseboard_fab2_lib.baseboard_fab2(sch_1):page174_i26:sideband4" )
			)
			( pin "J8A2.D1"
				( objectStatus "@baseboard_fab2_lib.baseboard_fab2(sch_1):page174_i26:sideband5" )
			)
			( pin "J8A2.D2"
				( objectStatus "@baseboard_fab2_lib.baseboard_fab2(sch_1):page174_i26:sideband6" )
			)
			( pin "J8A2.A1"
				( objectStatus "@baseboard_fab2_lib.baseboard_fab2(sch_1):page174_i26:sideband7" )
			)
			( pin "J8A2.D5"
				( objectStatus "@baseboard_fab2_lib.baseboard_fab2(sch_1):page174_i26:txa0_dn" )
			)
			( pin "J8A2.D4"
				( objectStatus "@baseboard_fab2_lib.baseboard_fab2(sch_1):page174_i26:txa0_dp" )
			)
			( pin "J8A2.C5"
				( objectStatus "@baseboard_fab2_lib.baseboard_fab2(sch_1):page174_i26:txa1_dn" )
			)
			( pin "J8A2.C4"
				( objectStatus "@baseboard_fab2_lib.baseboard_fab2(sch_1):page174_i26:txa1_dp" )
			)
			( pin "J8A2.D8"
				( objectStatus "@baseboard_fab2_lib.baseboard_fab2(sch_1):page174_i26:txa2_dn" )
			)
			( pin "J8A2.D7"
				( objectStatus "@baseboard_fab2_lib.baseboard_fab2(sch_1):page174_i26:txa2_dp" )
			)
			( pin "J8A2.C8"
				( objectStatus "@baseboard_fab2_lib.baseboard_fab2(sch_1):page174_i26:txa3_dn" )
			)
			( pin "J8A2.C7"
				( objectStatus "@baseboard_fab2_lib.baseboard_fab2(sch_1):page174_i26:txa3_dp" )
			)
			( pin "C2L30.1"
				( objectStatus "@baseboard_fab2_lib.baseboard_fab2(sch_1):page174_i28:a" )
			)
			( pin "C2L30.2"
				( objectStatus "@baseboard_fab2_lib.baseboard_fab2(sch_1):page174_i28:b" )
			)
			( pin "C2L31.1"
				( objectStatus "@baseboard_fab2_lib.baseboard_fab2(sch_1):page174_i29:a" )
			)
			( pin "C2L31.2"
				( objectStatus "@baseboard_fab2_lib.baseboard_fab2(sch_1):page174_i29:b" )
			)
			( pin "C2L28.1"
				( objectStatus "@baseboard_fab2_lib.baseboard_fab2(sch_1):page174_i30:a" )
			)
			( pin "C2L28.2"
				( objectStatus "@baseboard_fab2_lib.baseboard_fab2(sch_1):page174_i30:b" )
			)
			( pin "C2L35.1"
				( objectStatus "@baseboard_fab2_lib.baseboard_fab2(sch_1):page174_i31:a" )
			)
			( pin "C2L35.2"
				( objectStatus "@baseboard_fab2_lib.baseboard_fab2(sch_1):page174_i31:b" )
			)
			( pin "C2L29.1"
				( objectStatus "@baseboard_fab2_lib.baseboard_fab2(sch_1):page174_i32:a" )
			)
			( pin "C2L29.2"
				( objectStatus "@baseboard_fab2_lib.baseboard_fab2(sch_1):page174_i32:b" )
			)
			( pin "C2L36.1"
				( objectStatus "@baseboard_fab2_lib.baseboard_fab2(sch_1):page174_i39:a" )
			)
			( pin "C2L36.2"
				( objectStatus "@baseboard_fab2_lib.baseboard_fab2(sch_1):page174_i39:b" )
			)
			( pin "C2L33.1"
				( objectStatus "@baseboard_fab2_lib.baseboard_fab2(sch_1):page174_i40:a" )
			)
			( pin "C2L33.2"
				( objectStatus "@baseboard_fab2_lib.baseboard_fab2(sch_1):page174_i40:b" )
			)
			( pin "C2L34.1"
				( objectStatus "@baseboard_fab2_lib.baseboard_fab2(sch_1):page174_i41:a" )
			)
			( pin "C2L34.2"
				( objectStatus "@baseboard_fab2_lib.baseboard_fab2(sch_1):page174_i41:b" )
			)
			( pin "R1L31.1"
				( objectStatus "@baseboard_fab2_lib.baseboard_fab2(sch_1):page175_i4:a" )
			)
			( pin "R1L31.2"
				( objectStatus "@baseboard_fab2_lib.baseboard_fab2(sch_1):page175_i4:b" )
			)
			( pin "R1L27.1"
				( objectStatus "@baseboard_fab2_lib.baseboard_fab2(sch_1):page175_i5:a" )
			)
			( pin "R1L27.2"
				( objectStatus "@baseboard_fab2_lib.baseboard_fab2(sch_1):page175_i5:b" )
			)
			( pin "U9A4.1"
				( objectStatus "@baseboard_fab2_lib.baseboard_fab2(sch_1):page175_i9:a(0)" )
			)
			( pin "U9A4.6"
				( objectStatus "@baseboard_fab2_lib.baseboard_fab2(sch_1):page175_i9:y(0)" )
			)
			( pin "U9A4.3"
				( objectStatus "@baseboard_fab2_lib.baseboard_fab2(sch_1):page175_i10:a(0)" )
			)
			( pin "U9A4.4"
				( objectStatus "@baseboard_fab2_lib.baseboard_fab2(sch_1):page175_i10:y(0)" )
			)
			( pin "C1L18.1"
				( objectStatus "@baseboard_fab2_lib.baseboard_fab2(sch_1):page175_i11:a" )
			)
			( pin "C1L18.2"
				( objectStatus "@baseboard_fab2_lib.baseboard_fab2(sch_1):page175_i11:b" )
			)
			( pin "R1L26.1"
				( objectStatus "@baseboard_fab2_lib.baseboard_fab2(sch_1):page175_i13:a" )
			)
			( pin "R1L26.2"
				( objectStatus "@baseboard_fab2_lib.baseboard_fab2(sch_1):page175_i13:b" )
			)
			( pin "U9A3.3"
				( objectStatus "@baseboard_fab2_lib.baseboard_fab2(sch_1):page175_i15:a(0)" )
			)
			( pin "U9A3.4"
				( objectStatus "@baseboard_fab2_lib.baseboard_fab2(sch_1):page175_i15:y(0)" )
			)
			( pin "U9A3.1"
				( objectStatus "@baseboard_fab2_lib.baseboard_fab2(sch_1):page175_i18:a(0)" )
			)
			( pin "U9A3.6"
				( objectStatus "@baseboard_fab2_lib.baseboard_fab2(sch_1):page175_i18:y(0)" )
			)
			( pin "C1L10.1"
				( objectStatus "@baseboard_fab2_lib.baseboard_fab2(sch_1):page175_i19:a" )
			)
			( pin "C1L10.2"
				( objectStatus "@baseboard_fab2_lib.baseboard_fab2(sch_1):page175_i19:b" )
			)
			( pin "R1L22.1"
				( objectStatus "@baseboard_fab2_lib.baseboard_fab2(sch_1):page175_i22:a" )
			)
			( pin "R1L22.2"
				( objectStatus "@baseboard_fab2_lib.baseboard_fab2(sch_1):page175_i22:b" )
			)
			( pin "R1L19.1"
				( objectStatus "@baseboard_fab2_lib.baseboard_fab2(sch_1):page175_i24:a" )
			)
			( pin "R1L19.2"
				( objectStatus "@baseboard_fab2_lib.baseboard_fab2(sch_1):page175_i24:b" )
			)
			( pin "R9A9.1"
				( objectStatus "@baseboard_fab2_lib.baseboard_fab2(sch_1):page175_i35:a" )
			)
			( pin "R9A9.2"
				( objectStatus "@baseboard_fab2_lib.baseboard_fab2(sch_1):page175_i35:b" )
			)
			( pin "C1L17.1"
				( objectStatus "@baseboard_fab2_lib.baseboard_fab2(sch_1):page175_i37:a" )
			)
			( pin "C1L17.2"
				( objectStatus "@baseboard_fab2_lib.baseboard_fab2(sch_1):page175_i37:b" )
			)
			( pin "C1L9.1"
				( objectStatus "@baseboard_fab2_lib.baseboard_fab2(sch_1):page175_i38:a" )
			)
			( pin "C1L9.2"
				( objectStatus "@baseboard_fab2_lib.baseboard_fab2(sch_1):page175_i38:b" )
			)
			( pin "C9A3.1"
				( objectStatus "@baseboard_fab2_lib.baseboard_fab2(sch_1):page175_i40:a" )
			)
			( pin "C9A3.2"
				( objectStatus "@baseboard_fab2_lib.baseboard_fab2(sch_1):page175_i40:b" )
			)
			( pin "R1L33.1"
				( objectStatus "@baseboard_fab2_lib.baseboard_fab2(sch_1):page175_i45:a" )
			)
			( pin "R1L33.2"
				( objectStatus "@baseboard_fab2_lib.baseboard_fab2(sch_1):page175_i45:b" )
			)
			( pin "Q9A3.3"
				( objectStatus "@baseboard_fab2_lib.baseboard_fab2(sch_1):page175_i49:drn" )
			)
			( pin "Q9A3.1"
				( objectStatus "@baseboard_fab2_lib.baseboard_fab2(sch_1):page175_i49:gate" )
			)
			( pin "Q9A3.2"
				( objectStatus "@baseboard_fab2_lib.baseboard_fab2(sch_1):page175_i49:src" )
			)
			( pin "DS9A1.2"
				( objectStatus "@baseboard_fab2_lib.baseboard_fab2(sch_1):page175_i50:a" )
			)
			( pin "DS9A1.1"
				( objectStatus "@baseboard_fab2_lib.baseboard_fab2(sch_1):page175_i50:c" )
			)
			( pin "U1L2.1"
				( objectStatus "@baseboard_fab2_lib.baseboard_fab2(sch_1):page175_i57:a" )
			)
			( pin "U1L2.2"
				( objectStatus "@baseboard_fab2_lib.baseboard_fab2(sch_1):page175_i57:b" )
			)
			( pin "U1L2.4"
				( objectStatus "@baseboard_fab2_lib.baseboard_fab2(sch_1):page175_i57:y" )
			)
			( pin "R1L8.1"
				( objectStatus "@baseboard_fab2_lib.baseboard_fab2(sch_1):page175_i58:a" )
			)
			( pin "R1L8.2"
				( objectStatus "@baseboard_fab2_lib.baseboard_fab2(sch_1):page175_i58:b" )
			)
			( pin "R1L12.1"
				( objectStatus "@baseboard_fab2_lib.baseboard_fab2(sch_1):page175_i63:a" )
			)
			( pin "R1L12.2"
				( objectStatus "@baseboard_fab2_lib.baseboard_fab2(sch_1):page175_i63:b" )
			)
			( pin "C1L4.1"
				( objectStatus "@baseboard_fab2_lib.baseboard_fab2(sch_1):page175_i64:a" )
			)
			( pin "C1L4.2"
				( objectStatus "@baseboard_fab2_lib.baseboard_fab2(sch_1):page175_i64:b" )
			)
			( pin "DS9A3.2"
				( objectStatus "@baseboard_fab2_lib.baseboard_fab2(sch_1):page175_i67:a" )
			)
			( pin "DS9A3.1"
				( objectStatus "@baseboard_fab2_lib.baseboard_fab2(sch_1):page175_i67:c" )
			)
			( pin "S9A1.1"
				( objectStatus "@baseboard_fab2_lib.baseboard_fab2(sch_1):page175_i78:pin1" )
			)
			( pin "S9A1.2"
				( objectStatus "@baseboard_fab2_lib.baseboard_fab2(sch_1):page175_i78:pin2" )
			)
			( pin "S9A1.3"
				( objectStatus "@baseboard_fab2_lib.baseboard_fab2(sch_1):page175_i78:pin3" )
			)
			( pin "S9A1.4"
				( objectStatus "@baseboard_fab2_lib.baseboard_fab2(sch_1):page175_i78:pin4" )
			)
			( pin "S9A2.1"
				( objectStatus "@baseboard_fab2_lib.baseboard_fab2(sch_1):page175_i84:io1" )
			)
			( pin "S9A2.2"
				( objectStatus "@baseboard_fab2_lib.baseboard_fab2(sch_1):page175_i84:io2" )
			)
			( pin "S9A2.3"
				( objectStatus "@baseboard_fab2_lib.baseboard_fab2(sch_1):page175_i84:io3" )
			)
			( pin "S9A2.4"
				( objectStatus "@baseboard_fab2_lib.baseboard_fab2(sch_1):page175_i84:io4" )
			)
			( pin "R1M5.1"
				( objectStatus "@baseboard_fab2_lib.baseboard_fab2(sch_1):page176_i16:a" )
			)
			( pin "R1M5.2"
				( objectStatus "@baseboard_fab2_lib.baseboard_fab2(sch_1):page176_i16:b" )
			)
			( pin "L1M2.1"
				( objectStatus "@baseboard_fab2_lib.baseboard_fab2(sch_1):page176_i30:a1" )
			)
			( pin "L1M2.2"
				( objectStatus "@baseboard_fab2_lib.baseboard_fab2(sch_1):page176_i30:a2" )
			)
			( pin "L1M2.3"
				( objectStatus "@baseboard_fab2_lib.baseboard_fab2(sch_1):page176_i30:b1" )
			)
			( pin "L1M2.4"
				( objectStatus "@baseboard_fab2_lib.baseboard_fab2(sch_1):page176_i30:b2" )
			)
			( pin "R1M6.1"
				( objectStatus "@baseboard_fab2_lib.baseboard_fab2(sch_1):page176_i31:a" )
			)
			( pin "R1M6.2"
				( objectStatus "@baseboard_fab2_lib.baseboard_fab2(sch_1):page176_i31:b" )
			)
			( pin "J9B1.2"
				( objectStatus "@baseboard_fab2_lib.baseboard_fab2(sch_1):page176_i69:dn" )
			)
			( pin "J9B1.3"
				( objectStatus "@baseboard_fab2_lib.baseboard_fab2(sch_1):page176_i69:dp" )
			)
			( pin "J9B1.4"
				( objectStatus "@baseboard_fab2_lib.baseboard_fab2(sch_1):page176_i69:gnd" )
			)
			( pin "J9B1.7"
				( objectStatus "@baseboard_fab2_lib.baseboard_fab2(sch_1):page176_i69:gnd_drain" )
			)
			( pin "J9B1.MH1"
				( objectStatus "@baseboard_fab2_lib.baseboard_fab2(sch_1):page176_i69:mh1" )
			)
			( pin "J9B1.MH2"
				( objectStatus "@baseboard_fab2_lib.baseboard_fab2(sch_1):page176_i69:mh2" )
			)
			( pin "J9B1.MH3"
				( objectStatus "@baseboard_fab2_lib.baseboard_fab2(sch_1):page176_i69:mh3" )
			)
			( pin "J9B1.MH4"
				( objectStatus "@baseboard_fab2_lib.baseboard_fab2(sch_1):page176_i69:mh4" )
			)
			( pin "J9B1.5"
				( objectStatus "@baseboard_fab2_lib.baseboard_fab2(sch_1):page176_i69:stda_ssrxn" )
			)
			( pin "J9B1.6"
				( objectStatus "@baseboard_fab2_lib.baseboard_fab2(sch_1):page176_i69:stda_ssrxp" )
			)
			( pin "J9B1.8"
				( objectStatus "@baseboard_fab2_lib.baseboard_fab2(sch_1):page176_i69:stda_sstxn" )
			)
			( pin "J9B1.9"
				( objectStatus "@baseboard_fab2_lib.baseboard_fab2(sch_1):page176_i69:stda_sstxp" )
			)
			( pin "J9B1.1"
				( objectStatus "@baseboard_fab2_lib.baseboard_fab2(sch_1):page176_i69:vbus" )
			)
			( pin "CR1M2.1"
				( objectStatus "@baseboard_fab2_lib.baseboard_fab2(sch_1):page176_i98:ac0" )
			)
			( pin "CR1M2.2"
				( objectStatus "@baseboard_fab2_lib.baseboard_fab2(sch_1):page176_i98:ac1" )
			)
			( pin "CR1M2.4"
				( objectStatus "@baseboard_fab2_lib.baseboard_fab2(sch_1):page176_i98:ac2" )
			)
			( pin "CR1M2.5"
				( objectStatus "@baseboard_fab2_lib.baseboard_fab2(sch_1):page176_i98:ac3" )
			)
			( pin "CR1M2.3"
				( objectStatus "@baseboard_fab2_lib.baseboard_fab2(sch_1):page176_i98:gnd(0)" )
			)
			( pin "CR1M2.9"
				( objectStatus "@baseboard_fab2_lib.baseboard_fab2(sch_1):page176_i98:out0" )
			)
			( pin "CR1M2.8"
				( objectStatus "@baseboard_fab2_lib.baseboard_fab2(sch_1):page176_i98:out1" )
			)
			( pin "CR1M2.7"
				( objectStatus "@baseboard_fab2_lib.baseboard_fab2(sch_1):page176_i98:out2" )
			)
			( pin "CR1M2.6"
				( objectStatus "@baseboard_fab2_lib.baseboard_fab2(sch_1):page176_i98:out3" )
			)
			( pin "U1M3.4"
				( objectStatus "@baseboard_fab2_lib.baseboard_fab2(sch_1):page176_i100:en_n" )
			)
			( pin "U1M3.2"
				( objectStatus "@baseboard_fab2_lib.baseboard_fab2(sch_1):page176_i100:gnd" )
			)
			( pin "U1M3.5"
				( objectStatus "@baseboard_fab2_lib.baseboard_fab2(sch_1):page176_i100:\in\" )
			)
			( pin "U1M3.3"
				( objectStatus "@baseboard_fab2_lib.baseboard_fab2(sch_1):page176_i100:oc_n" )
			)
			( pin "U1M3.1"
				( objectStatus "@baseboard_fab2_lib.baseboard_fab2(sch_1):page176_i100:\out\" )
			)
			( pin "R1M24.1"
				( objectStatus "@baseboard_fab2_lib.baseboard_fab2(sch_1):page176_i105:a" )
			)
			( pin "R1M24.2"
				( objectStatus "@baseboard_fab2_lib.baseboard_fab2(sch_1):page176_i105:b" )
			)
			( pin "C1M38.1"
				( objectStatus "@baseboard_fab2_lib.baseboard_fab2(sch_1):page176_i108:a" )
			)
			( pin "C1M38.2"
				( objectStatus "@baseboard_fab2_lib.baseboard_fab2(sch_1):page176_i108:b" )
			)
			( pin "R1M25.1"
				( objectStatus "@baseboard_fab2_lib.baseboard_fab2(sch_1):page176_i111:a" )
			)
			( pin "R1M25.2"
				( objectStatus "@baseboard_fab2_lib.baseboard_fab2(sch_1):page176_i111:b" )
			)
			( pin "C9B8.1"
				( objectStatus "@baseboard_fab2_lib.baseboard_fab2(sch_1):page176_i113:a" )
			)
			( pin "C9B8.2"
				( objectStatus "@baseboard_fab2_lib.baseboard_fab2(sch_1):page176_i113:b" )
			)
			( pin "R1M13.1"
				( objectStatus "@baseboard_fab2_lib.baseboard_fab2(sch_1):page177_i3:a" )
			)
			( pin "R1M13.2"
				( objectStatus "@baseboard_fab2_lib.baseboard_fab2(sch_1):page177_i3:b" )
			)
			( pin "R1M10.1"
				( objectStatus "@baseboard_fab2_lib.baseboard_fab2(sch_1):page177_i6:a" )
			)
			( pin "R1M10.2"
				( objectStatus "@baseboard_fab2_lib.baseboard_fab2(sch_1):page177_i6:b" )
			)
			( pin "R1M12.1"
				( objectStatus "@baseboard_fab2_lib.baseboard_fab2(sch_1):page177_i8:a" )
			)
			( pin "R1M12.2"
				( objectStatus "@baseboard_fab2_lib.baseboard_fab2(sch_1):page177_i8:b" )
			)
			( pin "R1M11.1"
				( objectStatus "@baseboard_fab2_lib.baseboard_fab2(sch_1):page177_i9:a" )
			)
			( pin "R1M11.2"
				( objectStatus "@baseboard_fab2_lib.baseboard_fab2(sch_1):page177_i9:b" )
			)
			( pin "C1M3.1"
				( objectStatus "@baseboard_fab2_lib.baseboard_fab2(sch_1):page177_i20:a" )
			)
			( pin "C1M3.2"
				( objectStatus "@baseboard_fab2_lib.baseboard_fab2(sch_1):page177_i20:b" )
			)
			( pin "DS9A6.1"
				( objectStatus "@baseboard_fab2_lib.baseboard_fab2(sch_1):page177_i31:a" )
			)
			( pin "DS9A6.2"
				( objectStatus "@baseboard_fab2_lib.baseboard_fab2(sch_1):page177_i31:c" )
			)
			( pin "R1L37.1"
				( objectStatus "@baseboard_fab2_lib.baseboard_fab2(sch_1):page177_i33:a" )
			)
			( pin "R1L37.2"
				( objectStatus "@baseboard_fab2_lib.baseboard_fab2(sch_1):page177_i33:b" )
			)
			( pin "DS9A2.2"
				( objectStatus "@baseboard_fab2_lib.baseboard_fab2(sch_1):page177_i42:a" )
			)
			( pin "DS9A2.1"
				( objectStatus "@baseboard_fab2_lib.baseboard_fab2(sch_1):page177_i42:c" )
			)
			( pin "R1L21.1"
				( objectStatus "@baseboard_fab2_lib.baseboard_fab2(sch_1):page177_i43:a" )
			)
			( pin "R1L21.2"
				( objectStatus "@baseboard_fab2_lib.baseboard_fab2(sch_1):page177_i43:b" )
			)
			( pin "U1M1.1"
				( objectStatus "@baseboard_fab2_lib.baseboard_fab2(sch_1):page177_i70:a(0)" )
			)
			( pin "U1M1.2"
				( objectStatus "@baseboard_fab2_lib.baseboard_fab2(sch_1):page177_i70:b(0)" )
			)
			( pin "U1M1.4"
				( objectStatus "@baseboard_fab2_lib.baseboard_fab2(sch_1):page177_i70:y(0)" )
			)
			( pin "DS9F1.1"
				( objectStatus "@baseboard_fab2_lib.baseboard_fab2(sch_1):page177_i71:a" )
			)
			( pin "DS9F1.2"
				( objectStatus "@baseboard_fab2_lib.baseboard_fab2(sch_1):page177_i71:c" )
			)
			( pin "R9F28.1"
				( objectStatus "@baseboard_fab2_lib.baseboard_fab2(sch_1):page177_i72:a" )
			)
			( pin "R9F28.2"
				( objectStatus "@baseboard_fab2_lib.baseboard_fab2(sch_1):page177_i72:b" )
			)
			( pin "R9F30.1"
				( objectStatus "@baseboard_fab2_lib.baseboard_fab2(sch_1):page177_i76:a" )
			)
			( pin "R9F30.2"
				( objectStatus "@baseboard_fab2_lib.baseboard_fab2(sch_1):page177_i76:b" )
			)
			( pin "Q9F1.3"
				( objectStatus "@baseboard_fab2_lib.baseboard_fab2(sch_1):page177_i79:drain(0)" )
			)
			( pin "Q9F1.5"
				( objectStatus "@baseboard_fab2_lib.baseboard_fab2(sch_1):page177_i79:gate(0)" )
			)
			( pin "Q9F1.4"
				( objectStatus "@baseboard_fab2_lib.baseboard_fab2(sch_1):page177_i79:source(0)" )
			)
			( pin "Q9F1.6"
				( objectStatus "@baseboard_fab2_lib.baseboard_fab2(sch_1):page177_i80:drain(0)" )
			)
			( pin "Q9F1.2"
				( objectStatus "@baseboard_fab2_lib.baseboard_fab2(sch_1):page177_i80:gate(0)" )
			)
			( pin "Q9F1.1"
				( objectStatus "@baseboard_fab2_lib.baseboard_fab2(sch_1):page177_i80:source(0)" )
			)
			( pin "R9F52.1"
				( objectStatus "@baseboard_fab2_lib.baseboard_fab2(sch_1):page177_i82:a" )
			)
			( pin "R9F52.2"
				( objectStatus "@baseboard_fab2_lib.baseboard_fab2(sch_1):page177_i82:b" )
			)
			( pin "R8D20.1"
				( objectStatus "@baseboard_fab2_lib.baseboard_fab2(sch_1):page178_i1:a" )
			)
			( pin "R8D20.2"
				( objectStatus "@baseboard_fab2_lib.baseboard_fab2(sch_1):page178_i1:b" )
			)
			( pin "R2L12.1"
				( objectStatus "@baseboard_fab2_lib.baseboard_fab2(sch_1):page178_i2:a" )
			)
			( pin "R2L12.2"
				( objectStatus "@baseboard_fab2_lib.baseboard_fab2(sch_1):page178_i2:b" )
			)
			( pin "R8D19.1"
				( objectStatus "@baseboard_fab2_lib.baseboard_fab2(sch_1):page178_i8:a" )
			)
			( pin "R8D19.2"
				( objectStatus "@baseboard_fab2_lib.baseboard_fab2(sch_1):page178_i8:b" )
			)
			( pin "R2N31.1"
				( objectStatus "@baseboard_fab2_lib.baseboard_fab2(sch_1):page178_i11:a" )
			)
			( pin "R2N31.2"
				( objectStatus "@baseboard_fab2_lib.baseboard_fab2(sch_1):page178_i11:b" )
			)
			( pin "R2L15.1"
				( objectStatus "@baseboard_fab2_lib.baseboard_fab2(sch_1):page178_i12:a" )
			)
			( pin "R2L15.2"
				( objectStatus "@baseboard_fab2_lib.baseboard_fab2(sch_1):page178_i12:b" )
			)
			( pin "R2L11.1"
				( objectStatus "@baseboard_fab2_lib.baseboard_fab2(sch_1):page178_i13:a" )
			)
			( pin "R2L11.2"
				( objectStatus "@baseboard_fab2_lib.baseboard_fab2(sch_1):page178_i13:b" )
			)
			( pin "R2L6.1"
				( objectStatus "@baseboard_fab2_lib.baseboard_fab2(sch_1):page178_i17:a" )
			)
			( pin "R2L6.2"
				( objectStatus "@baseboard_fab2_lib.baseboard_fab2(sch_1):page178_i17:b" )
			)
			( pin "R2L4.1"
				( objectStatus "@baseboard_fab2_lib.baseboard_fab2(sch_1):page178_i18:a" )
			)
			( pin "R2L4.2"
				( objectStatus "@baseboard_fab2_lib.baseboard_fab2(sch_1):page178_i18:b" )
			)
			( pin "R2L5.1"
				( objectStatus "@baseboard_fab2_lib.baseboard_fab2(sch_1):page178_i20:a" )
			)
			( pin "R2L5.2"
				( objectStatus "@baseboard_fab2_lib.baseboard_fab2(sch_1):page178_i20:b" )
			)
			( pin "R8B29.1"
				( objectStatus "@baseboard_fab2_lib.baseboard_fab2(sch_1):page178_i21:a" )
			)
			( pin "R8B29.2"
				( objectStatus "@baseboard_fab2_lib.baseboard_fab2(sch_1):page178_i21:b" )
			)
			( pin "R2N19.1"
				( objectStatus "@baseboard_fab2_lib.baseboard_fab2(sch_1):page178_i22:a" )
			)
			( pin "R2N19.2"
				( objectStatus "@baseboard_fab2_lib.baseboard_fab2(sch_1):page178_i22:b" )
			)
			( pin "R2N22.1"
				( objectStatus "@baseboard_fab2_lib.baseboard_fab2(sch_1):page178_i23:a" )
			)
			( pin "R2N22.2"
				( objectStatus "@baseboard_fab2_lib.baseboard_fab2(sch_1):page178_i23:b" )
			)
			( pin "J1F1.A2"
				( objectStatus "@baseboard_fab2_lib.baseboard_fab2(sch_1):page181_i111:gnda2" )
			)
			( pin "J1F1.A4"
				( objectStatus "@baseboard_fab2_lib.baseboard_fab2(sch_1):page181_i111:gnda4" )
			)
			( pin "J1F1.A6"
				( objectStatus "@baseboard_fab2_lib.baseboard_fab2(sch_1):page181_i111:gnda6" )
			)
			( pin "J1F1.A8"
				( objectStatus "@baseboard_fab2_lib.baseboard_fab2(sch_1):page181_i111:gnda8" )
			)
			( pin "J1F1.C1"
				( objectStatus "@baseboard_fab2_lib.baseboard_fab2(sch_1):page181_i111:gndc1" )
			)
			( pin "J1F1.C3"
				( objectStatus "@baseboard_fab2_lib.baseboard_fab2(sch_1):page181_i111:gndc3" )
			)
			( pin "J1F1.C5"
				( objectStatus "@baseboard_fab2_lib.baseboard_fab2(sch_1):page181_i111:gndc5" )
			)
			( pin "J1F1.C7"
				( objectStatus "@baseboard_fab2_lib.baseboard_fab2(sch_1):page181_i111:gndc7" )
			)
			( pin "J1F1.D2"
				( objectStatus "@baseboard_fab2_lib.baseboard_fab2(sch_1):page181_i111:gndd2" )
			)
			( pin "J1F1.D4"
				( objectStatus "@baseboard_fab2_lib.baseboard_fab2(sch_1):page181_i111:gndd4" )
			)
			( pin "J1F1.D6"
				( objectStatus "@baseboard_fab2_lib.baseboard_fab2(sch_1):page181_i111:gndd6" )
			)
			( pin "J1F1.D8"
				( objectStatus "@baseboard_fab2_lib.baseboard_fab2(sch_1):page181_i111:gndd8" )
			)
			( pin "J1F1.F1"
				( objectStatus "@baseboard_fab2_lib.baseboard_fab2(sch_1):page181_i111:gndf1" )
			)
			( pin "J1F1.F3"
				( objectStatus "@baseboard_fab2_lib.baseboard_fab2(sch_1):page181_i111:gndf3" )
			)
			( pin "J1F1.F5"
				( objectStatus "@baseboard_fab2_lib.baseboard_fab2(sch_1):page181_i111:gndf5" )
			)
			( pin "J1F1.F7"
				( objectStatus "@baseboard_fab2_lib.baseboard_fab2(sch_1):page181_i111:gndf7" )
			)
			( pin "J1F1.G2"
				( objectStatus "@baseboard_fab2_lib.baseboard_fab2(sch_1):page181_i111:gndg2" )
			)
			( pin "J1F1.G4"
				( objectStatus "@baseboard_fab2_lib.baseboard_fab2(sch_1):page181_i111:gndg4" )
			)
			( pin "J1F1.G6"
				( objectStatus "@baseboard_fab2_lib.baseboard_fab2(sch_1):page181_i111:gndg6" )
			)
			( pin "J1F1.G8"
				( objectStatus "@baseboard_fab2_lib.baseboard_fab2(sch_1):page181_i111:gndg8" )
			)
			( pin "J1F1.I1"
				( objectStatus "@baseboard_fab2_lib.baseboard_fab2(sch_1):page181_i111:gndi1" )
			)
			( pin "J1F1.I3"
				( objectStatus "@baseboard_fab2_lib.baseboard_fab2(sch_1):page181_i111:gndi3" )
			)
			( pin "J1F1.I5"
				( objectStatus "@baseboard_fab2_lib.baseboard_fab2(sch_1):page181_i111:gndi5" )
			)
			( pin "J1F1.I7"
				( objectStatus "@baseboard_fab2_lib.baseboard_fab2(sch_1):page181_i111:gndi7" )
			)
			( pin "J1F1.J2"
				( objectStatus "@baseboard_fab2_lib.baseboard_fab2(sch_1):page181_i111:gndj2" )
			)
			( pin "J1F1.J4"
				( objectStatus "@baseboard_fab2_lib.baseboard_fab2(sch_1):page181_i111:gndj4" )
			)
			( pin "J1F1.J6"
				( objectStatus "@baseboard_fab2_lib.baseboard_fab2(sch_1):page181_i111:gndj6" )
			)
			( pin "J1F1.J8"
				( objectStatus "@baseboard_fab2_lib.baseboard_fab2(sch_1):page181_i111:gndj8" )
			)
			( pin "J1F1.A1"
				( objectStatus "@baseboard_fab2_lib.baseboard_fab2(sch_1):page181_i111:ioa1" )
			)
			( pin "J1F1.A3"
				( objectStatus "@baseboard_fab2_lib.baseboard_fab2(sch_1):page181_i111:ioa3" )
			)
			( pin "J1F1.A5"
				( objectStatus "@baseboard_fab2_lib.baseboard_fab2(sch_1):page181_i111:ioa5" )
			)
			( pin "J1F1.A7"
				( objectStatus "@baseboard_fab2_lib.baseboard_fab2(sch_1):page181_i111:ioa7" )
			)
			( pin "J1F1.B1"
				( objectStatus "@baseboard_fab2_lib.baseboard_fab2(sch_1):page181_i111:iob1" )
			)
			( pin "J1F1.B2"
				( objectStatus "@baseboard_fab2_lib.baseboard_fab2(sch_1):page181_i111:iob2" )
			)
			( pin "J1F1.B3"
				( objectStatus "@baseboard_fab2_lib.baseboard_fab2(sch_1):page181_i111:iob3" )
			)
			( pin "J1F1.B4"
				( objectStatus "@baseboard_fab2_lib.baseboard_fab2(sch_1):page181_i111:iob4" )
			)
			( pin "J1F1.B5"
				( objectStatus "@baseboard_fab2_lib.baseboard_fab2(sch_1):page181_i111:iob5" )
			)
			( pin "J1F1.B6"
				( objectStatus "@baseboard_fab2_lib.baseboard_fab2(sch_1):page181_i111:iob6" )
			)
			( pin "J1F1.B7"
				( objectStatus "@baseboard_fab2_lib.baseboard_fab2(sch_1):page181_i111:iob7" )
			)
			( pin "J1F1.B8"
				( objectStatus "@baseboard_fab2_lib.baseboard_fab2(sch_1):page181_i111:iob8" )
			)
			( pin "J1F1.C2"
				( objectStatus "@baseboard_fab2_lib.baseboard_fab2(sch_1):page181_i111:ioc2" )
			)
			( pin "J1F1.C4"
				( objectStatus "@baseboard_fab2_lib.baseboard_fab2(sch_1):page181_i111:ioc4" )
			)
			( pin "J1F1.C6"
				( objectStatus "@baseboard_fab2_lib.baseboard_fab2(sch_1):page181_i111:ioc6" )
			)
			( pin "J1F1.C8"
				( objectStatus "@baseboard_fab2_lib.baseboard_fab2(sch_1):page181_i111:ioc8" )
			)
			( pin "J1F1.D1"
				( objectStatus "@baseboard_fab2_lib.baseboard_fab2(sch_1):page181_i111:iod1" )
			)
			( pin "J1F1.D3"
				( objectStatus "@baseboard_fab2_lib.baseboard_fab2(sch_1):page181_i111:iod3" )
			)
			( pin "J1F1.D5"
				( objectStatus "@baseboard_fab2_lib.baseboard_fab2(sch_1):page181_i111:iod5" )
			)
			( pin "J1F1.D7"
				( objectStatus "@baseboard_fab2_lib.baseboard_fab2(sch_1):page181_i111:iod7" )
			)
			( pin "J1F1.E1"
				( objectStatus "@baseboard_fab2_lib.baseboard_fab2(sch_1):page181_i111:ioe1" )
			)
			( pin "J1F1.E2"
				( objectStatus "@baseboard_fab2_lib.baseboard_fab2(sch_1):page181_i111:ioe2" )
			)
			( pin "J1F1.E3"
				( objectStatus "@baseboard_fab2_lib.baseboard_fab2(sch_1):page181_i111:ioe3" )
			)
			( pin "J1F1.E4"
				( objectStatus "@baseboard_fab2_lib.baseboard_fab2(sch_1):page181_i111:ioe4" )
			)
			( pin "J1F1.E5"
				( objectStatus "@baseboard_fab2_lib.baseboard_fab2(sch_1):page181_i111:ioe5" )
			)
			( pin "J1F1.E6"
				( objectStatus "@baseboard_fab2_lib.baseboard_fab2(sch_1):page181_i111:ioe6" )
			)
			( pin "J1F1.E7"
				( objectStatus "@baseboard_fab2_lib.baseboard_fab2(sch_1):page181_i111:ioe7" )
			)
			( pin "J1F1.E8"
				( objectStatus "@baseboard_fab2_lib.baseboard_fab2(sch_1):page181_i111:ioe8" )
			)
			( pin "J1F1.F2"
				( objectStatus "@baseboard_fab2_lib.baseboard_fab2(sch_1):page181_i111:iof2" )
			)
			( pin "J1F1.F4"
				( objectStatus "@baseboard_fab2_lib.baseboard_fab2(sch_1):page181_i111:iof4" )
			)
			( pin "J1F1.F6"
				( objectStatus "@baseboard_fab2_lib.baseboard_fab2(sch_1):page181_i111:iof6" )
			)
			( pin "J1F1.F8"
				( objectStatus "@baseboard_fab2_lib.baseboard_fab2(sch_1):page181_i111:iof8" )
			)
			( pin "J1F1.G1"
				( objectStatus "@baseboard_fab2_lib.baseboard_fab2(sch_1):page181_i111:iog1" )
			)
			( pin "J1F1.G3"
				( objectStatus "@baseboard_fab2_lib.baseboard_fab2(sch_1):page181_i111:iog3" )
			)
			( pin "J1F1.G5"
				( objectStatus "@baseboard_fab2_lib.baseboard_fab2(sch_1):page181_i111:iog5" )
			)
			( pin "J1F1.G7"
				( objectStatus "@baseboard_fab2_lib.baseboard_fab2(sch_1):page181_i111:iog7" )
			)
			( pin "J1F1.H1"
				( objectStatus "@baseboard_fab2_lib.baseboard_fab2(sch_1):page181_i111:ioh1" )
			)
			( pin "J1F1.H2"
				( objectStatus "@baseboard_fab2_lib.baseboard_fab2(sch_1):page181_i111:ioh2" )
			)
			( pin "J1F1.H3"
				( objectStatus "@baseboard_fab2_lib.baseboard_fab2(sch_1):page181_i111:ioh3" )
			)
			( pin "J1F1.H4"
				( objectStatus "@baseboard_fab2_lib.baseboard_fab2(sch_1):page181_i111:ioh4" )
			)
			( pin "J1F1.H5"
				( objectStatus "@baseboard_fab2_lib.baseboard_fab2(sch_1):page181_i111:ioh5" )
			)
			( pin "J1F1.H6"
				( objectStatus "@baseboard_fab2_lib.baseboard_fab2(sch_1):page181_i111:ioh6" )
			)
			( pin "J1F1.H7"
				( objectStatus "@baseboard_fab2_lib.baseboard_fab2(sch_1):page181_i111:ioh7" )
			)
			( pin "J1F1.H8"
				( objectStatus "@baseboard_fab2_lib.baseboard_fab2(sch_1):page181_i111:ioh8" )
			)
			( pin "J1F1.I2"
				( objectStatus "@baseboard_fab2_lib.baseboard_fab2(sch_1):page181_i111:ioi2" )
			)
			( pin "J1F1.I4"
				( objectStatus "@baseboard_fab2_lib.baseboard_fab2(sch_1):page181_i111:ioi4" )
			)
			( pin "J1F1.I6"
				( objectStatus "@baseboard_fab2_lib.baseboard_fab2(sch_1):page181_i111:ioi6" )
			)
			( pin "J1F1.I8"
				( objectStatus "@baseboard_fab2_lib.baseboard_fab2(sch_1):page181_i111:ioi8" )
			)
			( pin "C1F4.1"
				( objectStatus "@baseboard_fab2_lib.baseboard_fab2(sch_1):page181_i160:a" )
			)
			( pin "C1F4.2"
				( objectStatus "@baseboard_fab2_lib.baseboard_fab2(sch_1):page181_i160:b" )
			)
			( pin "C1F5.1"
				( objectStatus "@baseboard_fab2_lib.baseboard_fab2(sch_1):page181_i161:a" )
			)
			( pin "C1F5.2"
				( objectStatus "@baseboard_fab2_lib.baseboard_fab2(sch_1):page181_i161:b" )
			)
			( pin "C1F2.1"
				( objectStatus "@baseboard_fab2_lib.baseboard_fab2(sch_1):page181_i162:a" )
			)
			( pin "C1F2.2"
				( objectStatus "@baseboard_fab2_lib.baseboard_fab2(sch_1):page181_i162:b" )
			)
			( pin "C1F13.1"
				( objectStatus "@baseboard_fab2_lib.baseboard_fab2(sch_1):page181_i163:a" )
			)
			( pin "C1F13.2"
				( objectStatus "@baseboard_fab2_lib.baseboard_fab2(sch_1):page181_i163:b" )
			)
			( pin "C1F10.1"
				( objectStatus "@baseboard_fab2_lib.baseboard_fab2(sch_1):page181_i164:a" )
			)
			( pin "C1F10.2"
				( objectStatus "@baseboard_fab2_lib.baseboard_fab2(sch_1):page181_i164:b" )
			)
			( pin "C1F6.1"
				( objectStatus "@baseboard_fab2_lib.baseboard_fab2(sch_1):page181_i165:a" )
			)
			( pin "C1F6.2"
				( objectStatus "@baseboard_fab2_lib.baseboard_fab2(sch_1):page181_i165:b" )
			)
			( pin "C1F20.1"
				( objectStatus "@baseboard_fab2_lib.baseboard_fab2(sch_1):page181_i166:a" )
			)
			( pin "C1F20.2"
				( objectStatus "@baseboard_fab2_lib.baseboard_fab2(sch_1):page181_i166:b" )
			)
			( pin "C1F3.1"
				( objectStatus "@baseboard_fab2_lib.baseboard_fab2(sch_1):page181_i167:a" )
			)
			( pin "C1F3.2"
				( objectStatus "@baseboard_fab2_lib.baseboard_fab2(sch_1):page181_i167:b" )
			)
			( pin "C1F12.1"
				( objectStatus "@baseboard_fab2_lib.baseboard_fab2(sch_1):page181_i168:a" )
			)
			( pin "C1F12.2"
				( objectStatus "@baseboard_fab2_lib.baseboard_fab2(sch_1):page181_i168:b" )
			)
			( pin "C1F11.1"
				( objectStatus "@baseboard_fab2_lib.baseboard_fab2(sch_1):page181_i169:a" )
			)
			( pin "C1F11.2"
				( objectStatus "@baseboard_fab2_lib.baseboard_fab2(sch_1):page181_i169:b" )
			)
			( pin "C1F8.1"
				( objectStatus "@baseboard_fab2_lib.baseboard_fab2(sch_1):page181_i170:a" )
			)
			( pin "C1F8.2"
				( objectStatus "@baseboard_fab2_lib.baseboard_fab2(sch_1):page181_i170:b" )
			)
			( pin "C1F18.1"
				( objectStatus "@baseboard_fab2_lib.baseboard_fab2(sch_1):page181_i171:a" )
			)
			( pin "C1F18.2"
				( objectStatus "@baseboard_fab2_lib.baseboard_fab2(sch_1):page181_i171:b" )
			)
			( pin "C1F16.1"
				( objectStatus "@baseboard_fab2_lib.baseboard_fab2(sch_1):page181_i172:a" )
			)
			( pin "C1F16.2"
				( objectStatus "@baseboard_fab2_lib.baseboard_fab2(sch_1):page181_i172:b" )
			)
			( pin "C1F17.1"
				( objectStatus "@baseboard_fab2_lib.baseboard_fab2(sch_1):page181_i173:a" )
			)
			( pin "C1F17.2"
				( objectStatus "@baseboard_fab2_lib.baseboard_fab2(sch_1):page181_i173:b" )
			)
			( pin "C1F15.1"
				( objectStatus "@baseboard_fab2_lib.baseboard_fab2(sch_1):page181_i174:a" )
			)
			( pin "C1F15.2"
				( objectStatus "@baseboard_fab2_lib.baseboard_fab2(sch_1):page181_i174:b" )
			)
			( pin "C1F14.1"
				( objectStatus "@baseboard_fab2_lib.baseboard_fab2(sch_1):page181_i175:a" )
			)
			( pin "C1F14.2"
				( objectStatus "@baseboard_fab2_lib.baseboard_fab2(sch_1):page181_i175:b" )
			)
			( pin "R9T9.1"
				( objectStatus "@baseboard_fab2_lib.baseboard_fab2(sch_1):page181_i177:a" )
			)
			( pin "R9T9.2"
				( objectStatus "@baseboard_fab2_lib.baseboard_fab2(sch_1):page181_i177:b" )
			)
			( pin "CR1F4.2"
				( objectStatus "@baseboard_fab2_lib.baseboard_fab2(sch_1):page181_i178:a" )
			)
			( pin "CR1F4.1"
				( objectStatus "@baseboard_fab2_lib.baseboard_fab2(sch_1):page181_i178:c" )
			)
			( pin "CR1F3.2"
				( objectStatus "@baseboard_fab2_lib.baseboard_fab2(sch_1):page181_i180:a" )
			)
			( pin "CR1F3.1"
				( objectStatus "@baseboard_fab2_lib.baseboard_fab2(sch_1):page181_i180:c" )
			)
			( pin "Q9T1.1"
				( objectStatus "@baseboard_fab2_lib.baseboard_fab2(sch_1):page181_i181:b" )
			)
			( pin "Q9T1.3"
				( objectStatus "@baseboard_fab2_lib.baseboard_fab2(sch_1):page181_i181:c" )
			)
			( pin "Q9T1.2"
				( objectStatus "@baseboard_fab2_lib.baseboard_fab2(sch_1):page181_i181:e" )
			)
			( pin "R9T6.1"
				( objectStatus "@baseboard_fab2_lib.baseboard_fab2(sch_1):page181_i183:a" )
			)
			( pin "R9T6.2"
				( objectStatus "@baseboard_fab2_lib.baseboard_fab2(sch_1):page181_i183:b" )
			)
			( pin "R9T3.1"
				( objectStatus "@baseboard_fab2_lib.baseboard_fab2(sch_1):page181_i185:a" )
			)
			( pin "R9T3.2"
				( objectStatus "@baseboard_fab2_lib.baseboard_fab2(sch_1):page181_i185:b" )
			)
			( pin "J1F3.1"
				( objectStatus "@baseboard_fab2_lib.baseboard_fab2(sch_1):page181_i189:io1" )
			)
			( pin "J1F3.2"
				( objectStatus "@baseboard_fab2_lib.baseboard_fab2(sch_1):page181_i189:io2" )
			)
			( pin "J1F3.3"
				( objectStatus "@baseboard_fab2_lib.baseboard_fab2(sch_1):page181_i189:io3" )
			)
			( pin "J1F3.4"
				( objectStatus "@baseboard_fab2_lib.baseboard_fab2(sch_1):page181_i189:io4" )
			)
			( pin "J1F3.5"
				( objectStatus "@baseboard_fab2_lib.baseboard_fab2(sch_1):page181_i189:io5" )
			)
			( pin "J1F3.6"
				( objectStatus "@baseboard_fab2_lib.baseboard_fab2(sch_1):page181_i189:io6" )
			)
			( pin "J1F3.7"
				( objectStatus "@baseboard_fab2_lib.baseboard_fab2(sch_1):page181_i189:io7" )
			)
			( pin "J1F3.8"
				( objectStatus "@baseboard_fab2_lib.baseboard_fab2(sch_1):page181_i189:io8" )
			)
			( pin "R7D5.1"
				( objectStatus "@baseboard_fab2_lib.baseboard_fab2(sch_1):page181_i199:a" )
			)
			( pin "R7D5.2"
				( objectStatus "@baseboard_fab2_lib.baseboard_fab2(sch_1):page181_i199:b" )
			)
			( pin "R7D9.1"
				( objectStatus "@baseboard_fab2_lib.baseboard_fab2(sch_1):page181_i200:a" )
			)
			( pin "R7D9.2"
				( objectStatus "@baseboard_fab2_lib.baseboard_fab2(sch_1):page181_i200:b" )
			)
			( pin "R3P61.1"
				( objectStatus "@baseboard_fab2_lib.baseboard_fab2(sch_1):page181_i201:a" )
			)
			( pin "R3P61.2"
				( objectStatus "@baseboard_fab2_lib.baseboard_fab2(sch_1):page181_i201:b" )
			)
			( pin "R8E5.1"
				( objectStatus "@baseboard_fab2_lib.baseboard_fab2(sch_1):page181_i218:a" )
			)
			( pin "R8E5.2"
				( objectStatus "@baseboard_fab2_lib.baseboard_fab2(sch_1):page181_i218:b" )
			)
			( pin "C2R6.1"
				( objectStatus "@baseboard_fab2_lib.baseboard_fab2(sch_1):page181_i224:a" )
			)
			( pin "C2R6.2"
				( objectStatus "@baseboard_fab2_lib.baseboard_fab2(sch_1):page181_i224:b" )
			)
			( pin "U8E1.9"
				( objectStatus "@baseboard_fab2_lib.baseboard_fab2(sch_1):page181_i243:a(0)" )
			)
			( pin "U8E1.10"
				( objectStatus "@baseboard_fab2_lib.baseboard_fab2(sch_1):page181_i243:b(0)" )
			)
			( pin "U8E1.8"
				( objectStatus "@baseboard_fab2_lib.baseboard_fab2(sch_1):page181_i243:y(0)" )
			)
			( pin "C8E1.1"
				( objectStatus "@baseboard_fab2_lib.baseboard_fab2(sch_1):page181_i253:a" )
			)
			( pin "C8E1.2"
				( objectStatus "@baseboard_fab2_lib.baseboard_fab2(sch_1):page181_i253:b" )
			)
			( pin "R9R9.1"
				( objectStatus "@baseboard_fab2_lib.baseboard_fab2(sch_1):page181_i254:a" )
			)
			( pin "R9R9.2"
				( objectStatus "@baseboard_fab2_lib.baseboard_fab2(sch_1):page181_i254:b" )
			)
			( pin "R9R12.1"
				( objectStatus "@baseboard_fab2_lib.baseboard_fab2(sch_1):page181_i255:a" )
			)
			( pin "R9R12.2"
				( objectStatus "@baseboard_fab2_lib.baseboard_fab2(sch_1):page181_i255:b" )
			)
			( pin "R9R10.1"
				( objectStatus "@baseboard_fab2_lib.baseboard_fab2(sch_1):page181_i256:a" )
			)
			( pin "R9R10.2"
				( objectStatus "@baseboard_fab2_lib.baseboard_fab2(sch_1):page181_i256:b" )
			)
			( pin "R9T1.1"
				( objectStatus "@baseboard_fab2_lib.baseboard_fab2(sch_1):page181_i261:a" )
			)
			( pin "R9T1.2"
				( objectStatus "@baseboard_fab2_lib.baseboard_fab2(sch_1):page181_i261:b" )
			)
			( pin "R1F8.1"
				( objectStatus "@baseboard_fab2_lib.baseboard_fab2(sch_1):page181_i268:a" )
			)
			( pin "R1F8.2"
				( objectStatus "@baseboard_fab2_lib.baseboard_fab2(sch_1):page181_i268:b" )
			)
			( pin "R9F69.1"
				( objectStatus "@baseboard_fab2_lib.baseboard_fab2(sch_1):page158_i150:a" )
			)
			( pin "R9F69.2"
				( objectStatus "@baseboard_fab2_lib.baseboard_fab2(sch_1):page158_i150:b" )
			)
			( pin "R9F68.1"
				( objectStatus "@baseboard_fab2_lib.baseboard_fab2(sch_1):page158_i149:a" )
			)
			( pin "R9F68.2"
				( objectStatus "@baseboard_fab2_lib.baseboard_fab2(sch_1):page158_i149:b" )
			)
			( pin "C9N18.1"
				( objectStatus "@baseboard_fab2_lib.baseboard_fab2(sch_1):page182_i9:a" )
			)
			( pin "C9N18.2"
				( objectStatus "@baseboard_fab2_lib.baseboard_fab2(sch_1):page182_i9:b" )
			)
			( pin "C9N17.1"
				( objectStatus "@baseboard_fab2_lib.baseboard_fab2(sch_1):page182_i12:a" )
			)
			( pin "C9N17.2"
				( objectStatus "@baseboard_fab2_lib.baseboard_fab2(sch_1):page182_i12:b" )
			)
			( pin "C9N15.1"
				( objectStatus "@baseboard_fab2_lib.baseboard_fab2(sch_1):page182_i13:a" )
			)
			( pin "C9N15.2"
				( objectStatus "@baseboard_fab2_lib.baseboard_fab2(sch_1):page182_i13:b" )
			)
			( pin "C9N1.1"
				( objectStatus "@baseboard_fab2_lib.baseboard_fab2(sch_1):page182_i14:a" )
			)
			( pin "C9N1.2"
				( objectStatus "@baseboard_fab2_lib.baseboard_fab2(sch_1):page182_i14:b" )
			)
			( pin "C9N2.1"
				( objectStatus "@baseboard_fab2_lib.baseboard_fab2(sch_1):page182_i15:a" )
			)
			( pin "C9N2.2"
				( objectStatus "@baseboard_fab2_lib.baseboard_fab2(sch_1):page182_i15:b" )
			)
			( pin "C9N12.1"
				( objectStatus "@baseboard_fab2_lib.baseboard_fab2(sch_1):page182_i16:a" )
			)
			( pin "C9N12.2"
				( objectStatus "@baseboard_fab2_lib.baseboard_fab2(sch_1):page182_i16:b" )
			)
			( pin "J1C1.A2"
				( objectStatus "@baseboard_fab2_lib.baseboard_fab2(sch_1):page182_i18:gnda2" )
			)
			( pin "J1C1.A4"
				( objectStatus "@baseboard_fab2_lib.baseboard_fab2(sch_1):page182_i18:gnda4" )
			)
			( pin "J1C1.A6"
				( objectStatus "@baseboard_fab2_lib.baseboard_fab2(sch_1):page182_i18:gnda6" )
			)
			( pin "J1C1.A8"
				( objectStatus "@baseboard_fab2_lib.baseboard_fab2(sch_1):page182_i18:gnda8" )
			)
			( pin "J1C1.C1"
				( objectStatus "@baseboard_fab2_lib.baseboard_fab2(sch_1):page182_i18:gndc1" )
			)
			( pin "J1C1.C3"
				( objectStatus "@baseboard_fab2_lib.baseboard_fab2(sch_1):page182_i18:gndc3" )
			)
			( pin "J1C1.C5"
				( objectStatus "@baseboard_fab2_lib.baseboard_fab2(sch_1):page182_i18:gndc5" )
			)
			( pin "J1C1.C7"
				( objectStatus "@baseboard_fab2_lib.baseboard_fab2(sch_1):page182_i18:gndc7" )
			)
			( pin "J1C1.D2"
				( objectStatus "@baseboard_fab2_lib.baseboard_fab2(sch_1):page182_i18:gndd2" )
			)
			( pin "J1C1.D4"
				( objectStatus "@baseboard_fab2_lib.baseboard_fab2(sch_1):page182_i18:gndd4" )
			)
			( pin "J1C1.D6"
				( objectStatus "@baseboard_fab2_lib.baseboard_fab2(sch_1):page182_i18:gndd6" )
			)
			( pin "J1C1.D8"
				( objectStatus "@baseboard_fab2_lib.baseboard_fab2(sch_1):page182_i18:gndd8" )
			)
			( pin "J1C1.F1"
				( objectStatus "@baseboard_fab2_lib.baseboard_fab2(sch_1):page182_i18:gndf1" )
			)
			( pin "J1C1.F3"
				( objectStatus "@baseboard_fab2_lib.baseboard_fab2(sch_1):page182_i18:gndf3" )
			)
			( pin "J1C1.F5"
				( objectStatus "@baseboard_fab2_lib.baseboard_fab2(sch_1):page182_i18:gndf5" )
			)
			( pin "J1C1.F7"
				( objectStatus "@baseboard_fab2_lib.baseboard_fab2(sch_1):page182_i18:gndf7" )
			)
			( pin "J1C1.G2"
				( objectStatus "@baseboard_fab2_lib.baseboard_fab2(sch_1):page182_i18:gndg2" )
			)
			( pin "J1C1.G4"
				( objectStatus "@baseboard_fab2_lib.baseboard_fab2(sch_1):page182_i18:gndg4" )
			)
			( pin "J1C1.G6"
				( objectStatus "@baseboard_fab2_lib.baseboard_fab2(sch_1):page182_i18:gndg6" )
			)
			( pin "J1C1.G8"
				( objectStatus "@baseboard_fab2_lib.baseboard_fab2(sch_1):page182_i18:gndg8" )
			)
			( pin "J1C1.I1"
				( objectStatus "@baseboard_fab2_lib.baseboard_fab2(sch_1):page182_i18:gndi1" )
			)
			( pin "J1C1.I3"
				( objectStatus "@baseboard_fab2_lib.baseboard_fab2(sch_1):page182_i18:gndi3" )
			)
			( pin "J1C1.I5"
				( objectStatus "@baseboard_fab2_lib.baseboard_fab2(sch_1):page182_i18:gndi5" )
			)
			( pin "J1C1.I7"
				( objectStatus "@baseboard_fab2_lib.baseboard_fab2(sch_1):page182_i18:gndi7" )
			)
			( pin "J1C1.J2"
				( objectStatus "@baseboard_fab2_lib.baseboard_fab2(sch_1):page182_i18:gndj2" )
			)
			( pin "J1C1.J4"
				( objectStatus "@baseboard_fab2_lib.baseboard_fab2(sch_1):page182_i18:gndj4" )
			)
			( pin "J1C1.J6"
				( objectStatus "@baseboard_fab2_lib.baseboard_fab2(sch_1):page182_i18:gndj6" )
			)
			( pin "J1C1.J8"
				( objectStatus "@baseboard_fab2_lib.baseboard_fab2(sch_1):page182_i18:gndj8" )
			)
			( pin "J1C1.A1"
				( objectStatus "@baseboard_fab2_lib.baseboard_fab2(sch_1):page182_i18:ioa1" )
			)
			( pin "J1C1.A3"
				( objectStatus "@baseboard_fab2_lib.baseboard_fab2(sch_1):page182_i18:ioa3" )
			)
			( pin "J1C1.A5"
				( objectStatus "@baseboard_fab2_lib.baseboard_fab2(sch_1):page182_i18:ioa5" )
			)
			( pin "J1C1.A7"
				( objectStatus "@baseboard_fab2_lib.baseboard_fab2(sch_1):page182_i18:ioa7" )
			)
			( pin "J1C1.B1"
				( objectStatus "@baseboard_fab2_lib.baseboard_fab2(sch_1):page182_i18:iob1" )
			)
			( pin "J1C1.B2"
				( objectStatus "@baseboard_fab2_lib.baseboard_fab2(sch_1):page182_i18:iob2" )
			)
			( pin "J1C1.B3"
				( objectStatus "@baseboard_fab2_lib.baseboard_fab2(sch_1):page182_i18:iob3" )
			)
			( pin "J1C1.B4"
				( objectStatus "@baseboard_fab2_lib.baseboard_fab2(sch_1):page182_i18:iob4" )
			)
			( pin "J1C1.B5"
				( objectStatus "@baseboard_fab2_lib.baseboard_fab2(sch_1):page182_i18:iob5" )
			)
			( pin "J1C1.B6"
				( objectStatus "@baseboard_fab2_lib.baseboard_fab2(sch_1):page182_i18:iob6" )
			)
			( pin "J1C1.B7"
				( objectStatus "@baseboard_fab2_lib.baseboard_fab2(sch_1):page182_i18:iob7" )
			)
			( pin "J1C1.B8"
				( objectStatus "@baseboard_fab2_lib.baseboard_fab2(sch_1):page182_i18:iob8" )
			)
			( pin "J1C1.C2"
				( objectStatus "@baseboard_fab2_lib.baseboard_fab2(sch_1):page182_i18:ioc2" )
			)
			( pin "J1C1.C4"
				( objectStatus "@baseboard_fab2_lib.baseboard_fab2(sch_1):page182_i18:ioc4" )
			)
			( pin "J1C1.C6"
				( objectStatus "@baseboard_fab2_lib.baseboard_fab2(sch_1):page182_i18:ioc6" )
			)
			( pin "J1C1.C8"
				( objectStatus "@baseboard_fab2_lib.baseboard_fab2(sch_1):page182_i18:ioc8" )
			)
			( pin "J1C1.D1"
				( objectStatus "@baseboard_fab2_lib.baseboard_fab2(sch_1):page182_i18:iod1" )
			)
			( pin "J1C1.D3"
				( objectStatus "@baseboard_fab2_lib.baseboard_fab2(sch_1):page182_i18:iod3" )
			)
			( pin "J1C1.D5"
				( objectStatus "@baseboard_fab2_lib.baseboard_fab2(sch_1):page182_i18:iod5" )
			)
			( pin "J1C1.D7"
				( objectStatus "@baseboard_fab2_lib.baseboard_fab2(sch_1):page182_i18:iod7" )
			)
			( pin "J1C1.E1"
				( objectStatus "@baseboard_fab2_lib.baseboard_fab2(sch_1):page182_i18:ioe1" )
			)
			( pin "J1C1.E2"
				( objectStatus "@baseboard_fab2_lib.baseboard_fab2(sch_1):page182_i18:ioe2" )
			)
			( pin "J1C1.E3"
				( objectStatus "@baseboard_fab2_lib.baseboard_fab2(sch_1):page182_i18:ioe3" )
			)
			( pin "J1C1.E4"
				( objectStatus "@baseboard_fab2_lib.baseboard_fab2(sch_1):page182_i18:ioe4" )
			)
			( pin "J1C1.E5"
				( objectStatus "@baseboard_fab2_lib.baseboard_fab2(sch_1):page182_i18:ioe5" )
			)
			( pin "J1C1.E6"
				( objectStatus "@baseboard_fab2_lib.baseboard_fab2(sch_1):page182_i18:ioe6" )
			)
			( pin "J1C1.E7"
				( objectStatus "@baseboard_fab2_lib.baseboard_fab2(sch_1):page182_i18:ioe7" )
			)
			( pin "J1C1.E8"
				( objectStatus "@baseboard_fab2_lib.baseboard_fab2(sch_1):page182_i18:ioe8" )
			)
			( pin "J1C1.F2"
				( objectStatus "@baseboard_fab2_lib.baseboard_fab2(sch_1):page182_i18:iof2" )
			)
			( pin "J1C1.F4"
				( objectStatus "@baseboard_fab2_lib.baseboard_fab2(sch_1):page182_i18:iof4" )
			)
			( pin "J1C1.F6"
				( objectStatus "@baseboard_fab2_lib.baseboard_fab2(sch_1):page182_i18:iof6" )
			)
			( pin "J1C1.F8"
				( objectStatus "@baseboard_fab2_lib.baseboard_fab2(sch_1):page182_i18:iof8" )
			)
			( pin "J1C1.G1"
				( objectStatus "@baseboard_fab2_lib.baseboard_fab2(sch_1):page182_i18:iog1" )
			)
			( pin "J1C1.G3"
				( objectStatus "@baseboard_fab2_lib.baseboard_fab2(sch_1):page182_i18:iog3" )
			)
			( pin "J1C1.G5"
				( objectStatus "@baseboard_fab2_lib.baseboard_fab2(sch_1):page182_i18:iog5" )
			)
			( pin "J1C1.G7"
				( objectStatus "@baseboard_fab2_lib.baseboard_fab2(sch_1):page182_i18:iog7" )
			)
			( pin "J1C1.H1"
				( objectStatus "@baseboard_fab2_lib.baseboard_fab2(sch_1):page182_i18:ioh1" )
			)
			( pin "J1C1.H2"
				( objectStatus "@baseboard_fab2_lib.baseboard_fab2(sch_1):page182_i18:ioh2" )
			)
			( pin "J1C1.H3"
				( objectStatus "@baseboard_fab2_lib.baseboard_fab2(sch_1):page182_i18:ioh3" )
			)
			( pin "J1C1.H4"
				( objectStatus "@baseboard_fab2_lib.baseboard_fab2(sch_1):page182_i18:ioh4" )
			)
			( pin "J1C1.H5"
				( objectStatus "@baseboard_fab2_lib.baseboard_fab2(sch_1):page182_i18:ioh5" )
			)
			( pin "J1C1.H6"
				( objectStatus "@baseboard_fab2_lib.baseboard_fab2(sch_1):page182_i18:ioh6" )
			)
			( pin "J1C1.H7"
				( objectStatus "@baseboard_fab2_lib.baseboard_fab2(sch_1):page182_i18:ioh7" )
			)
			( pin "J1C1.H8"
				( objectStatus "@baseboard_fab2_lib.baseboard_fab2(sch_1):page182_i18:ioh8" )
			)
			( pin "J1C1.I2"
				( objectStatus "@baseboard_fab2_lib.baseboard_fab2(sch_1):page182_i18:ioi2" )
			)
			( pin "J1C1.I4"
				( objectStatus "@baseboard_fab2_lib.baseboard_fab2(sch_1):page182_i18:ioi4" )
			)
			( pin "J1C1.I6"
				( objectStatus "@baseboard_fab2_lib.baseboard_fab2(sch_1):page182_i18:ioi6" )
			)
			( pin "J1C1.I8"
				( objectStatus "@baseboard_fab2_lib.baseboard_fab2(sch_1):page182_i18:ioi8" )
			)
			( pin "C9N9.1"
				( objectStatus "@baseboard_fab2_lib.baseboard_fab2(sch_1):page182_i49:a" )
			)
			( pin "C9N9.2"
				( objectStatus "@baseboard_fab2_lib.baseboard_fab2(sch_1):page182_i49:b" )
			)
			( pin "C9N8.1"
				( objectStatus "@baseboard_fab2_lib.baseboard_fab2(sch_1):page182_i50:a" )
			)
			( pin "C9N8.2"
				( objectStatus "@baseboard_fab2_lib.baseboard_fab2(sch_1):page182_i50:b" )
			)
			( pin "C9N3.1"
				( objectStatus "@baseboard_fab2_lib.baseboard_fab2(sch_1):page182_i51:a" )
			)
			( pin "C9N3.2"
				( objectStatus "@baseboard_fab2_lib.baseboard_fab2(sch_1):page182_i51:b" )
			)
			( pin "C9N16.1"
				( objectStatus "@baseboard_fab2_lib.baseboard_fab2(sch_1):page182_i52:a" )
			)
			( pin "C9N16.2"
				( objectStatus "@baseboard_fab2_lib.baseboard_fab2(sch_1):page182_i52:b" )
			)
			( pin "C9N10.1"
				( objectStatus "@baseboard_fab2_lib.baseboard_fab2(sch_1):page182_i53:a" )
			)
			( pin "C9N10.2"
				( objectStatus "@baseboard_fab2_lib.baseboard_fab2(sch_1):page182_i53:b" )
			)
			( pin "C9N7.1"
				( objectStatus "@baseboard_fab2_lib.baseboard_fab2(sch_1):page182_i54:a" )
			)
			( pin "C9N7.2"
				( objectStatus "@baseboard_fab2_lib.baseboard_fab2(sch_1):page182_i54:b" )
			)
			( pin "C9N4.1"
				( objectStatus "@baseboard_fab2_lib.baseboard_fab2(sch_1):page182_i55:a" )
			)
			( pin "C9N4.2"
				( objectStatus "@baseboard_fab2_lib.baseboard_fab2(sch_1):page182_i55:b" )
			)
			( pin "C9N14.1"
				( objectStatus "@baseboard_fab2_lib.baseboard_fab2(sch_1):page182_i56:a" )
			)
			( pin "C9N14.2"
				( objectStatus "@baseboard_fab2_lib.baseboard_fab2(sch_1):page182_i56:b" )
			)
			( pin "C9N6.1"
				( objectStatus "@baseboard_fab2_lib.baseboard_fab2(sch_1):page182_i81:a" )
			)
			( pin "C9N6.2"
				( objectStatus "@baseboard_fab2_lib.baseboard_fab2(sch_1):page182_i81:b" )
			)
			( pin "C9N5.1"
				( objectStatus "@baseboard_fab2_lib.baseboard_fab2(sch_1):page182_i83:a" )
			)
			( pin "C9N5.2"
				( objectStatus "@baseboard_fab2_lib.baseboard_fab2(sch_1):page182_i83:b" )
			)
			( pin "R1C11.1"
				( objectStatus "@baseboard_fab2_lib.baseboard_fab2(sch_1):page182_i97:a" )
			)
			( pin "R1C11.2"
				( objectStatus "@baseboard_fab2_lib.baseboard_fab2(sch_1):page182_i97:b" )
			)
			( pin "R1C10.1"
				( objectStatus "@baseboard_fab2_lib.baseboard_fab2(sch_1):page182_i101:a" )
			)
			( pin "R1C10.2"
				( objectStatus "@baseboard_fab2_lib.baseboard_fab2(sch_1):page182_i101:b" )
			)
			( pin "R1C9.1"
				( objectStatus "@baseboard_fab2_lib.baseboard_fab2(sch_1):page182_i104:a" )
			)
			( pin "R1C9.2"
				( objectStatus "@baseboard_fab2_lib.baseboard_fab2(sch_1):page182_i104:b" )
			)
			( pin "R1F9.1"
				( objectStatus "@baseboard_fab2_lib.baseboard_fab2(sch_1):page182_i107:a" )
			)
			( pin "R1F9.2"
				( objectStatus "@baseboard_fab2_lib.baseboard_fab2(sch_1):page182_i107:b" )
			)
			( pin "R1C31.1"
				( objectStatus "@baseboard_fab2_lib.baseboard_fab2(sch_1):page182_i110:a" )
			)
			( pin "R1C31.2"
				( objectStatus "@baseboard_fab2_lib.baseboard_fab2(sch_1):page182_i110:b" )
			)
			( pin "EU9F3.30"
				( objectStatus "@baseboard_fab2_lib.baseboard_fab2(sch_1):page183_i1:a0_cs_n" )
			)
			( pin "EU9F3.31"
				( objectStatus "@baseboard_fab2_lib.baseboard_fab2(sch_1):page183_i1:a1_s1" )
			)
			( pin "EU9F3.25"
				( objectStatus "@baseboard_fab2_lib.baseboard_fab2(sch_1):page183_i1:ctsa_n" )
			)
			( pin "EU9F3.16"
				( objectStatus "@baseboard_fab2_lib.baseboard_fab2(sch_1):page183_i1:ctsb_n" )
			)
			( pin "EU9F3.19"
				( objectStatus "@baseboard_fab2_lib.baseboard_fab2(sch_1):page183_i1:en485_n" )
			)
			( pin "EU9F3.18"
				( objectStatus "@baseboard_fab2_lib.baseboard_fab2(sch_1):page183_i1:enir_n" )
			)
			( pin "EU9F3.12"
				( objectStatus "@baseboard_fab2_lib.baseboard_fab2(sch_1):page183_i1:gnd" )
			)
			( pin "EU9F3.13"
				( objectStatus "@baseboard_fab2_lib.baseboard_fab2(sch_1):page183_i1:gpio0_dsrb_n" )
			)
			( pin "EU9F3.23"
				( objectStatus "@baseboard_fab2_lib.baseboard_fab2(sch_1):page183_i1:gpio1_dtrb_n" )
			)
			( pin "EU9F3.11"
				( objectStatus "@baseboard_fab2_lib.baseboard_fab2(sch_1):page183_i1:gpio2_cdb_n" )
			)
			( pin "EU9F3.14"
				( objectStatus "@baseboard_fab2_lib.baseboard_fab2(sch_1):page183_i1:gpio3_rib_n" )
			)
			( pin "EU9F3.26"
				( objectStatus "@baseboard_fab2_lib.baseboard_fab2(sch_1):page183_i1:gpio4_dsra_n" )
			)
			( pin "EU9F3.22"
				( objectStatus "@baseboard_fab2_lib.baseboard_fab2(sch_1):page183_i1:gpio5_dtra_n" )
			)
			( pin "EU9F3.27"
				( objectStatus "@baseboard_fab2_lib.baseboard_fab2(sch_1):page183_i1:gpio6_cda_n" )
			)
			( pin "EU9F3.28"
				( objectStatus "@baseboard_fab2_lib.baseboard_fab2(sch_1):page183_i1:gpio7_ria_n" )
			)
			( pin "EU9F3.32"
				( objectStatus "@baseboard_fab2_lib.baseboard_fab2(sch_1):page183_i1:i2c_spi_n" )
			)
			( pin "EU9F3.20"
				( objectStatus "@baseboard_fab2_lib.baseboard_fab2(sch_1):page183_i1:irq_n" )
			)
			( pin "EU9F3.1"
				( objectStatus "@baseboard_fab2_lib.baseboard_fab2(sch_1):page183_i1:nc(0)" )
			)
			( pin "EU9F3.8"
				( objectStatus "@baseboard_fab2_lib.baseboard_fab2(sch_1):page183_i1:nc(1)" )
			)
			( pin "EU9F3.24"
				( objectStatus "@baseboard_fab2_lib.baseboard_fab2(sch_1):page183_i1:reset_n" )
			)
			( pin "EU9F3.21"
				( objectStatus "@baseboard_fab2_lib.baseboard_fab2(sch_1):page183_i1:rtsa_n" )
			)
			( pin "EU9F3.15"
				( objectStatus "@baseboard_fab2_lib.baseboard_fab2(sch_1):page183_i1:rtsb_n" )
			)
			( pin "EU9F3.5"
				( objectStatus "@baseboard_fab2_lib.baseboard_fab2(sch_1):page183_i1:rxa" )
			)
			( pin "EU9F3.4"
				( objectStatus "@baseboard_fab2_lib.baseboard_fab2(sch_1):page183_i1:rxb" )
			)
			( pin "EU9F3.17"
				( objectStatus "@baseboard_fab2_lib.baseboard_fab2(sch_1):page183_i1:scl" )
			)
			( pin "EU9F3.3"
				( objectStatus "@baseboard_fab2_lib.baseboard_fab2(sch_1):page183_i1:sda" )
			)
			( pin "EU9F3.2"
				( objectStatus "@baseboard_fab2_lib.baseboard_fab2(sch_1):page183_i1:so" )
			)
			( pin "EU9F3.33"
				( objectStatus "@baseboard_fab2_lib.baseboard_fab2(sch_1):page183_i1:thpad" )
			)
			( pin "EU9F3.6"
				( objectStatus "@baseboard_fab2_lib.baseboard_fab2(sch_1):page183_i1:txa" )
			)
			( pin "EU9F3.7"
				( objectStatus "@baseboard_fab2_lib.baseboard_fab2(sch_1):page183_i1:txb" )
			)
			( pin "EU9F3.29"
				( objectStatus "@baseboard_fab2_lib.baseboard_fab2(sch_1):page183_i1:vdd" )
			)
			( pin "EU9F3.9"
				( objectStatus "@baseboard_fab2_lib.baseboard_fab2(sch_1):page183_i1:xtal1" )
			)
			( pin "EU9F3.10"
				( objectStatus "@baseboard_fab2_lib.baseboard_fab2(sch_1):page183_i1:xtal2" )
			)
			( pin "R9F47.1"
				( objectStatus "@baseboard_fab2_lib.baseboard_fab2(sch_1):page183_i4:a" )
			)
			( pin "R9F47.2"
				( objectStatus "@baseboard_fab2_lib.baseboard_fab2(sch_1):page183_i4:b" )
			)
			( pin "C9F19.1"
				( objectStatus "@baseboard_fab2_lib.baseboard_fab2(sch_1):page183_i7:a" )
			)
			( pin "C9F19.2"
				( objectStatus "@baseboard_fab2_lib.baseboard_fab2(sch_1):page183_i7:b" )
			)
			( pin "R9F50.1"
				( objectStatus "@baseboard_fab2_lib.baseboard_fab2(sch_1):page183_i11:a" )
			)
			( pin "R9F50.2"
				( objectStatus "@baseboard_fab2_lib.baseboard_fab2(sch_1):page183_i11:b" )
			)
			( pin "R9F51.1"
				( objectStatus "@baseboard_fab2_lib.baseboard_fab2(sch_1):page183_i12:a" )
			)
			( pin "R9F51.2"
				( objectStatus "@baseboard_fab2_lib.baseboard_fab2(sch_1):page183_i12:b" )
			)
			( pin "R9F48.1"
				( objectStatus "@baseboard_fab2_lib.baseboard_fab2(sch_1):page183_i13:a" )
			)
			( pin "R9F48.2"
				( objectStatus "@baseboard_fab2_lib.baseboard_fab2(sch_1):page183_i13:b" )
			)
			( pin "R9F49.1"
				( objectStatus "@baseboard_fab2_lib.baseboard_fab2(sch_1):page183_i14:a" )
			)
			( pin "R9F49.2"
				( objectStatus "@baseboard_fab2_lib.baseboard_fab2(sch_1):page183_i14:b" )
			)
			( pin "Y9F1.1"
				( objectStatus "@baseboard_fab2_lib.baseboard_fab2(sch_1):page183_i19:a" )
			)
			( pin "Y9F1.2"
				( objectStatus "@baseboard_fab2_lib.baseboard_fab2(sch_1):page183_i19:b" )
			)
			( pin "C9F20.1"
				( objectStatus "@baseboard_fab2_lib.baseboard_fab2(sch_1):page183_i20:a" )
			)
			( pin "C9F20.2"
				( objectStatus "@baseboard_fab2_lib.baseboard_fab2(sch_1):page183_i20:b" )
			)
			( pin "C9F21.1"
				( objectStatus "@baseboard_fab2_lib.baseboard_fab2(sch_1):page183_i21:a" )
			)
			( pin "C9F21.2"
				( objectStatus "@baseboard_fab2_lib.baseboard_fab2(sch_1):page183_i21:b" )
			)
			( pin "R9F58.1"
				( objectStatus "@baseboard_fab2_lib.baseboard_fab2(sch_1):page183_i24:a" )
			)
			( pin "R9F58.2"
				( objectStatus "@baseboard_fab2_lib.baseboard_fab2(sch_1):page183_i24:b" )
			)
			( pin "R9F59.1"
				( objectStatus "@baseboard_fab2_lib.baseboard_fab2(sch_1):page183_i25:a" )
			)
			( pin "R9F59.2"
				( objectStatus "@baseboard_fab2_lib.baseboard_fab2(sch_1):page183_i25:b" )
			)
			( pin "R9F55.1"
				( objectStatus "@baseboard_fab2_lib.baseboard_fab2(sch_1):page183_i30:a" )
			)
			( pin "R9F55.2"
				( objectStatus "@baseboard_fab2_lib.baseboard_fab2(sch_1):page183_i30:b" )
			)
			( pin "R9F57.1"
				( objectStatus "@baseboard_fab2_lib.baseboard_fab2(sch_1):page183_i48:a" )
			)
			( pin "R9F57.2"
				( objectStatus "@baseboard_fab2_lib.baseboard_fab2(sch_1):page183_i48:b" )
			)
			( pin "R9F56.1"
				( objectStatus "@baseboard_fab2_lib.baseboard_fab2(sch_1):page183_i49:a" )
			)
			( pin "R9F56.2"
				( objectStatus "@baseboard_fab2_lib.baseboard_fab2(sch_1):page183_i49:b" )
			)
			( pin "R9F54.1"
				( objectStatus "@baseboard_fab2_lib.baseboard_fab2(sch_1):page183_i52:a" )
			)
			( pin "R9F54.2"
				( objectStatus "@baseboard_fab2_lib.baseboard_fab2(sch_1):page183_i52:b" )
			)
			( pin "R9F53.1"
				( objectStatus "@baseboard_fab2_lib.baseboard_fab2(sch_1):page183_i53:a" )
			)
			( pin "R9F53.2"
				( objectStatus "@baseboard_fab2_lib.baseboard_fab2(sch_1):page183_i53:b" )
			)
			( pin "J8E1.1"
				( objectStatus "@baseboard_fab2_lib.baseboard_fab2(sch_1):page184_i87:io1" )
			)
			( pin "J8E1.2"
				( objectStatus "@baseboard_fab2_lib.baseboard_fab2(sch_1):page184_i87:io2" )
			)
			( pin "J8E1.3"
				( objectStatus "@baseboard_fab2_lib.baseboard_fab2(sch_1):page184_i87:io3" )
			)
			( pin "J8E1.4"
				( objectStatus "@baseboard_fab2_lib.baseboard_fab2(sch_1):page184_i87:io4" )
			)
			( pin "J8E1.5"
				( objectStatus "@baseboard_fab2_lib.baseboard_fab2(sch_1):page184_i87:io5" )
			)
			( pin "J8E1.6"
				( objectStatus "@baseboard_fab2_lib.baseboard_fab2(sch_1):page184_i87:io6" )
			)
			( pin "J8E1.7"
				( objectStatus "@baseboard_fab2_lib.baseboard_fab2(sch_1):page184_i87:io7" )
			)
			( pin "J8E1.8"
				( objectStatus "@baseboard_fab2_lib.baseboard_fab2(sch_1):page184_i87:io8" )
			)
			( pin "J8E1.9"
				( objectStatus "@baseboard_fab2_lib.baseboard_fab2(sch_1):page184_i87:io9" )
			)
			( pin "J8E1.10"
				( objectStatus "@baseboard_fab2_lib.baseboard_fab2(sch_1):page184_i87:io10" )
			)
			( pin "J8E1.11"
				( objectStatus "@baseboard_fab2_lib.baseboard_fab2(sch_1):page184_i87:io11" )
			)
			( pin "J8E1.MP1"
				( objectStatus "@baseboard_fab2_lib.baseboard_fab2(sch_1):page184_i87:mp1" )
			)
			( pin "J8E1.MP2"
				( objectStatus "@baseboard_fab2_lib.baseboard_fab2(sch_1):page184_i87:mp2" )
			)
			( pin "R8E9.1"
				( objectStatus "@baseboard_fab2_lib.baseboard_fab2(sch_1):page184_i88:a" )
			)
			( pin "R8E9.2"
				( objectStatus "@baseboard_fab2_lib.baseboard_fab2(sch_1):page184_i88:b" )
			)
			( pin "R8D35.1"
				( objectStatus "@baseboard_fab2_lib.baseboard_fab2(sch_1):page184_i92:a" )
			)
			( pin "R8D35.2"
				( objectStatus "@baseboard_fab2_lib.baseboard_fab2(sch_1):page184_i92:b" )
			)
			( pin "R8E13.1"
				( objectStatus "@baseboard_fab2_lib.baseboard_fab2(sch_1):page184_i93:a" )
			)
			( pin "R8E13.2"
				( objectStatus "@baseboard_fab2_lib.baseboard_fab2(sch_1):page184_i93:b" )
			)
			( pin "R8E10.1"
				( objectStatus "@baseboard_fab2_lib.baseboard_fab2(sch_1):page184_i95:a" )
			)
			( pin "R8E10.2"
				( objectStatus "@baseboard_fab2_lib.baseboard_fab2(sch_1):page184_i95:b" )
			)
			( pin "R8E1.1"
				( objectStatus "@baseboard_fab2_lib.baseboard_fab2(sch_1):page184_i99:a" )
			)
			( pin "R8E1.2"
				( objectStatus "@baseboard_fab2_lib.baseboard_fab2(sch_1):page184_i99:b" )
			)
			( pin "RM8D1.1"
				( objectStatus "@baseboard_fab2_lib.baseboard_fab2(sch_1):page184_i104:io1" )
			)
			( pin "J8F1.2"
				( objectStatus "@baseboard_fab2_lib.baseboard_fab2(sch_1):page185_i53:\3_3v\(0)" )
			)
			( pin "J8F1.4"
				( objectStatus "@baseboard_fab2_lib.baseboard_fab2(sch_1):page185_i53:\3_3v\(1)" )
			)
			( pin "J8F1.12"
				( objectStatus "@baseboard_fab2_lib.baseboard_fab2(sch_1):page185_i53:\3_3v\(2)" )
			)
			( pin "J8F1.14"
				( objectStatus "@baseboard_fab2_lib.baseboard_fab2(sch_1):page185_i53:\3_3v\(3)" )
			)
			( pin "J8F1.16"
				( objectStatus "@baseboard_fab2_lib.baseboard_fab2(sch_1):page185_i53:\3_3v\(4)" )
			)
			( pin "J8F1.18"
				( objectStatus "@baseboard_fab2_lib.baseboard_fab2(sch_1):page185_i53:\3_3v\(5)" )
			)
			( pin "J8F1.70"
				( objectStatus "@baseboard_fab2_lib.baseboard_fab2(sch_1):page185_i53:\3_3v\(6)" )
			)
			( pin "J8F1.72"
				( objectStatus "@baseboard_fab2_lib.baseboard_fab2(sch_1):page185_i53:\3_3v\(7)" )
			)
			( pin "J8F1.74"
				( objectStatus "@baseboard_fab2_lib.baseboard_fab2(sch_1):page185_i53:\3_3v\(8)" )
			)
			( pin "J8F1.52"
				( objectStatus "@baseboard_fab2_lib.baseboard_fab2(sch_1):page185_i53:clkreq_n_nc" )
			)
			( pin "J8F1.10"
				( objectStatus "@baseboard_fab2_lib.baseboard_fab2(sch_1):page185_i53:das_dss_n" )
			)
			( pin "J8F1.38"
				( objectStatus "@baseboard_fab2_lib.baseboard_fab2(sch_1):page185_i53:devslp" )
			)
			( pin "J8F1.1"
				( objectStatus "@baseboard_fab2_lib.baseboard_fab2(sch_1):page185_i53:gnd(0)" )
			)
			( pin "J8F1.3"
				( objectStatus "@baseboard_fab2_lib.baseboard_fab2(sch_1):page185_i53:gnd(1)" )
			)
			( pin "J8F1.9"
				( objectStatus "@baseboard_fab2_lib.baseboard_fab2(sch_1):page185_i53:gnd(2)" )
			)
			( pin "J8F1.15"
				( objectStatus "@baseboard_fab2_lib.baseboard_fab2(sch_1):page185_i53:gnd(3)" )
			)
			( pin "J8F1.21"
				( objectStatus "@baseboard_fab2_lib.baseboard_fab2(sch_1):page185_i53:gnd(4)" )
			)
			( pin "J8F1.27"
				( objectStatus "@baseboard_fab2_lib.baseboard_fab2(sch_1):page185_i53:gnd(5)" )
			)
			( pin "J8F1.33"
				( objectStatus "@baseboard_fab2_lib.baseboard_fab2(sch_1):page185_i53:gnd(6)" )
			)
			( pin "J8F1.39"
				( objectStatus "@baseboard_fab2_lib.baseboard_fab2(sch_1):page185_i53:gnd(7)" )
			)
			( pin "J8F1.45"
				( objectStatus "@baseboard_fab2_lib.baseboard_fab2(sch_1):page185_i53:gnd(8)" )
			)
			( pin "J8F1.51"
				( objectStatus "@baseboard_fab2_lib.baseboard_fab2(sch_1):page185_i53:gnd(9)" )
			)
			( pin "J8F1.57"
				( objectStatus "@baseboard_fab2_lib.baseboard_fab2(sch_1):page185_i53:gnd(10)" )
			)
			( pin "J8F1.71"
				( objectStatus "@baseboard_fab2_lib.baseboard_fab2(sch_1):page185_i53:gnd(11)" )
			)
			( pin "J8F1.73"
				( objectStatus "@baseboard_fab2_lib.baseboard_fab2(sch_1):page185_i53:gnd(12)" )
			)
			( pin "J8F1.75"
				( objectStatus "@baseboard_fab2_lib.baseboard_fab2(sch_1):page185_i53:gnd(13)" )
			)
			( pin "J8F1.MP1"
				( objectStatus "@baseboard_fab2_lib.baseboard_fab2(sch_1):page185_i53:mp1" )
			)
			( pin "J8F1.MP2"
				( objectStatus "@baseboard_fab2_lib.baseboard_fab2(sch_1):page185_i53:mp2" )
			)
			( pin "J8F1.6"
				( objectStatus "@baseboard_fab2_lib.baseboard_fab2(sch_1):page185_i53:nc(0)" )
			)
			( pin "J8F1.8"
				( objectStatus "@baseboard_fab2_lib.baseboard_fab2(sch_1):page185_i53:nc(1)" )
			)
			( pin "J8F1.20"
				( objectStatus "@baseboard_fab2_lib.baseboard_fab2(sch_1):page185_i53:nc(2)" )
			)
			( pin "J8F1.22"
				( objectStatus "@baseboard_fab2_lib.baseboard_fab2(sch_1):page185_i53:nc(3)" )
			)
			( pin "J8F1.24"
				( objectStatus "@baseboard_fab2_lib.baseboard_fab2(sch_1):page185_i53:nc(4)" )
			)
			( pin "J8F1.26"
				( objectStatus "@baseboard_fab2_lib.baseboard_fab2(sch_1):page185_i53:nc(5)" )
			)
			( pin "J8F1.28"
				( objectStatus "@baseboard_fab2_lib.baseboard_fab2(sch_1):page185_i53:nc(6)" )
			)
			( pin "J8F1.30"
				( objectStatus "@baseboard_fab2_lib.baseboard_fab2(sch_1):page185_i53:nc(7)" )
			)
			( pin "J8F1.32"
				( objectStatus "@baseboard_fab2_lib.baseboard_fab2(sch_1):page185_i53:nc(8)" )
			)
			( pin "J8F1.34"
				( objectStatus "@baseboard_fab2_lib.baseboard_fab2(sch_1):page185_i53:nc(9)" )
			)
			( pin "J8F1.36"
				( objectStatus "@baseboard_fab2_lib.baseboard_fab2(sch_1):page185_i53:nc(10)" )
			)
			( pin "J8F1.40"
				( objectStatus "@baseboard_fab2_lib.baseboard_fab2(sch_1):page185_i53:nc(11)" )
			)
			( pin "J8F1.42"
				( objectStatus "@baseboard_fab2_lib.baseboard_fab2(sch_1):page185_i53:nc(12)" )
			)
			( pin "J8F1.44"
				( objectStatus "@baseboard_fab2_lib.baseboard_fab2(sch_1):page185_i53:nc(13)" )
			)
			( pin "J8F1.46"
				( objectStatus "@baseboard_fab2_lib.baseboard_fab2(sch_1):page185_i53:nc(14)" )
			)
			( pin "J8F1.48"
				( objectStatus "@baseboard_fab2_lib.baseboard_fab2(sch_1):page185_i53:nc(15)" )
			)
			( pin "J8F1.56"
				( objectStatus "@baseboard_fab2_lib.baseboard_fab2(sch_1):page185_i53:nc(16)" )
			)
			( pin "J8F1.58"
				( objectStatus "@baseboard_fab2_lib.baseboard_fab2(sch_1):page185_i53:nc(17)" )
			)
			( pin "J8F1.67"
				( objectStatus "@baseboard_fab2_lib.baseboard_fab2(sch_1):page185_i53:nc(18)" )
			)
			( pin "J8F1.69"
				( objectStatus "@baseboard_fab2_lib.baseboard_fab2(sch_1):page185_i53:pedet" )
			)
			( pin "J8F1.41"
				( objectStatus "@baseboard_fab2_lib.baseboard_fab2(sch_1):page185_i53:pern0_sata_bp" )
			)
			( pin "J8F1.29"
				( objectStatus "@baseboard_fab2_lib.baseboard_fab2(sch_1):page185_i53:pern1" )
			)
			( pin "J8F1.17"
				( objectStatus "@baseboard_fab2_lib.baseboard_fab2(sch_1):page185_i53:pern2" )
			)
			( pin "J8F1.5"
				( objectStatus "@baseboard_fab2_lib.baseboard_fab2(sch_1):page185_i53:pern3" )
			)
			( pin "J8F1.43"
				( objectStatus "@baseboard_fab2_lib.baseboard_fab2(sch_1):page185_i53:perp0_sata_bn" )
			)
			( pin "J8F1.31"
				( objectStatus "@baseboard_fab2_lib.baseboard_fab2(sch_1):page185_i53:perp1" )
			)
			( pin "J8F1.19"
				( objectStatus "@baseboard_fab2_lib.baseboard_fab2(sch_1):page185_i53:perp2" )
			)
			( pin "J8F1.7"
				( objectStatus "@baseboard_fab2_lib.baseboard_fab2(sch_1):page185_i53:perp3" )
			)
			( pin "J8F1.50"
				( objectStatus "@baseboard_fab2_lib.baseboard_fab2(sch_1):page185_i53:perst_n_nc" )
			)
			( pin "J8F1.47"
				( objectStatus "@baseboard_fab2_lib.baseboard_fab2(sch_1):page185_i53:petn0_sata_an" )
			)
			( pin "J8F1.35"
				( objectStatus "@baseboard_fab2_lib.baseboard_fab2(sch_1):page185_i53:petn1" )
			)
			( pin "J8F1.23"
				( objectStatus "@baseboard_fab2_lib.baseboard_fab2(sch_1):page185_i53:petn2" )
			)
			( pin "J8F1.11"
				( objectStatus "@baseboard_fab2_lib.baseboard_fab2(sch_1):page185_i53:petn3" )
			)
			( pin "J8F1.49"
				( objectStatus "@baseboard_fab2_lib.baseboard_fab2(sch_1):page185_i53:petp0_sata_ap" )
			)
			( pin "J8F1.37"
				( objectStatus "@baseboard_fab2_lib.baseboard_fab2(sch_1):page185_i53:petp1" )
			)
			( pin "J8F1.25"
				( objectStatus "@baseboard_fab2_lib.baseboard_fab2(sch_1):page185_i53:petp2" )
			)
			( pin "J8F1.13"
				( objectStatus "@baseboard_fab2_lib.baseboard_fab2(sch_1):page185_i53:petp3" )
			)
			( pin "J8F1.54"
				( objectStatus "@baseboard_fab2_lib.baseboard_fab2(sch_1):page185_i53:pewake_n_nc" )
			)
			( pin "J8F1.53"
				( objectStatus "@baseboard_fab2_lib.baseboard_fab2(sch_1):page185_i53:refclkn" )
			)
			( pin "J8F1.55"
				( objectStatus "@baseboard_fab2_lib.baseboard_fab2(sch_1):page185_i53:refclkp" )
			)
			( pin "J8F1.68"
				( objectStatus "@baseboard_fab2_lib.baseboard_fab2(sch_1):page185_i53:susclk" )
			)
			( pin "C2T11.1"
				( objectStatus "@baseboard_fab2_lib.baseboard_fab2(sch_1):page185_i62:a" )
			)
			( pin "C2T11.2"
				( objectStatus "@baseboard_fab2_lib.baseboard_fab2(sch_1):page185_i62:b" )
			)
			( pin "C2T10.1"
				( objectStatus "@baseboard_fab2_lib.baseboard_fab2(sch_1):page185_i63:a" )
			)
			( pin "C2T10.2"
				( objectStatus "@baseboard_fab2_lib.baseboard_fab2(sch_1):page185_i63:b" )
			)
			( pin "C2T13.1"
				( objectStatus "@baseboard_fab2_lib.baseboard_fab2(sch_1):page185_i64:a" )
			)
			( pin "C2T13.2"
				( objectStatus "@baseboard_fab2_lib.baseboard_fab2(sch_1):page185_i64:b" )
			)
			( pin "C2T14.1"
				( objectStatus "@baseboard_fab2_lib.baseboard_fab2(sch_1):page185_i65:a" )
			)
			( pin "C2T14.2"
				( objectStatus "@baseboard_fab2_lib.baseboard_fab2(sch_1):page185_i65:b" )
			)
			( pin "C2T20.1"
				( objectStatus "@baseboard_fab2_lib.baseboard_fab2(sch_1):page185_i66:a" )
			)
			( pin "C2T20.2"
				( objectStatus "@baseboard_fab2_lib.baseboard_fab2(sch_1):page185_i66:b" )
			)
			( pin "C2T23.1"
				( objectStatus "@baseboard_fab2_lib.baseboard_fab2(sch_1):page185_i67:a" )
			)
			( pin "C2T23.2"
				( objectStatus "@baseboard_fab2_lib.baseboard_fab2(sch_1):page185_i67:b" )
			)
			( pin "C8F15.1"
				( objectStatus "@baseboard_fab2_lib.baseboard_fab2(sch_1):page185_i90:a" )
			)
			( pin "C8F15.2"
				( objectStatus "@baseboard_fab2_lib.baseboard_fab2(sch_1):page185_i90:b" )
			)
			( pin "C8F6.1"
				( objectStatus "@baseboard_fab2_lib.baseboard_fab2(sch_1):page185_i95:a" )
			)
			( pin "C8F6.2"
				( objectStatus "@baseboard_fab2_lib.baseboard_fab2(sch_1):page185_i95:b" )
			)
			( pin "C8F7.1"
				( objectStatus "@baseboard_fab2_lib.baseboard_fab2(sch_1):page185_i96:a" )
			)
			( pin "C8F7.2"
				( objectStatus "@baseboard_fab2_lib.baseboard_fab2(sch_1):page185_i96:b" )
			)
			( pin "C8F11.1"
				( objectStatus "@baseboard_fab2_lib.baseboard_fab2(sch_1):page185_i97:a" )
			)
			( pin "C8F11.2"
				( objectStatus "@baseboard_fab2_lib.baseboard_fab2(sch_1):page185_i97:b" )
			)
			( pin "C8F12.1"
				( objectStatus "@baseboard_fab2_lib.baseboard_fab2(sch_1):page185_i98:a" )
			)
			( pin "C8F12.2"
				( objectStatus "@baseboard_fab2_lib.baseboard_fab2(sch_1):page185_i98:b" )
			)
			( pin "C8F13.1"
				( objectStatus "@baseboard_fab2_lib.baseboard_fab2(sch_1):page185_i99:a" )
			)
			( pin "C8F13.2"
				( objectStatus "@baseboard_fab2_lib.baseboard_fab2(sch_1):page185_i99:b" )
			)
			( pin "R8F18.1"
				( objectStatus "@baseboard_fab2_lib.baseboard_fab2(sch_1):page185_i105:a" )
			)
			( pin "R8F18.2"
				( objectStatus "@baseboard_fab2_lib.baseboard_fab2(sch_1):page185_i105:b" )
			)
			( pin "R8F21.1"
				( objectStatus "@baseboard_fab2_lib.baseboard_fab2(sch_1):page185_i106:a" )
			)
			( pin "R8F21.2"
				( objectStatus "@baseboard_fab2_lib.baseboard_fab2(sch_1):page185_i106:b" )
			)
			( pin "U2P1.2"
				( objectStatus "@baseboard_fab2_lib.baseboard_fab2(sch_1):page185_i110:a" )
			)
			( pin "U2P1.4"
				( objectStatus "@baseboard_fab2_lib.baseboard_fab2(sch_1):page185_i110:y" )
			)
			( pin "R2P15.1"
				( objectStatus "@baseboard_fab2_lib.baseboard_fab2(sch_1):page185_i111:a" )
			)
			( pin "R2P15.2"
				( objectStatus "@baseboard_fab2_lib.baseboard_fab2(sch_1):page185_i111:b" )
			)
			( pin "R2P16.1"
				( objectStatus "@baseboard_fab2_lib.baseboard_fab2(sch_1):page185_i113:a" )
			)
			( pin "R2P16.2"
				( objectStatus "@baseboard_fab2_lib.baseboard_fab2(sch_1):page185_i113:b" )
			)
			( pin "R2P14.1"
				( objectStatus "@baseboard_fab2_lib.baseboard_fab2(sch_1):page185_i115:a" )
			)
			( pin "R2P14.2"
				( objectStatus "@baseboard_fab2_lib.baseboard_fab2(sch_1):page185_i115:b" )
			)
			( pin "C2P9.1"
				( objectStatus "@baseboard_fab2_lib.baseboard_fab2(sch_1):page185_i117:a" )
			)
			( pin "C2P9.2"
				( objectStatus "@baseboard_fab2_lib.baseboard_fab2(sch_1):page185_i117:b" )
			)
			( pin "C2T29.1"
				( objectStatus "@baseboard_fab2_lib.baseboard_fab2(sch_1):page185_i120:a" )
			)
			( pin "C2T29.2"
				( objectStatus "@baseboard_fab2_lib.baseboard_fab2(sch_1):page185_i120:b" )
			)
			( pin "C2T26.1"
				( objectStatus "@baseboard_fab2_lib.baseboard_fab2(sch_1):page185_i123:a" )
			)
			( pin "C2T26.2"
				( objectStatus "@baseboard_fab2_lib.baseboard_fab2(sch_1):page185_i123:b" )
			)
			( pin "C2T21.1"
				( objectStatus "@baseboard_fab2_lib.baseboard_fab2(sch_1):page185_i124:a" )
			)
			( pin "C2T21.2"
				( objectStatus "@baseboard_fab2_lib.baseboard_fab2(sch_1):page185_i124:b" )
			)
			( pin "C2T16.1"
				( objectStatus "@baseboard_fab2_lib.baseboard_fab2(sch_1):page185_i126:a" )
			)
			( pin "C2T16.2"
				( objectStatus "@baseboard_fab2_lib.baseboard_fab2(sch_1):page185_i126:b" )
			)
			( pin "C2T15.1"
				( objectStatus "@baseboard_fab2_lib.baseboard_fab2(sch_1):page185_i127:a" )
			)
			( pin "C2T15.2"
				( objectStatus "@baseboard_fab2_lib.baseboard_fab2(sch_1):page185_i127:b" )
			)
			( pin "C2T24.1"
				( objectStatus "@baseboard_fab2_lib.baseboard_fab2(sch_1):page185_i129:a" )
			)
			( pin "C2T24.2"
				( objectStatus "@baseboard_fab2_lib.baseboard_fab2(sch_1):page185_i129:b" )
			)
			( pin "C2T2.1"
				( objectStatus "@baseboard_fab2_lib.baseboard_fab2(sch_1):page185_i131:a" )
			)
			( pin "C2T2.2"
				( objectStatus "@baseboard_fab2_lib.baseboard_fab2(sch_1):page185_i131:b" )
			)
			( pin "C2T4.1"
				( objectStatus "@baseboard_fab2_lib.baseboard_fab2(sch_1):page185_i132:a" )
			)
			( pin "C2T4.2"
				( objectStatus "@baseboard_fab2_lib.baseboard_fab2(sch_1):page185_i132:b" )
			)
			( pin "C2T5.1"
				( objectStatus "@baseboard_fab2_lib.baseboard_fab2(sch_1):page185_i135:a" )
			)
			( pin "C2T5.2"
				( objectStatus "@baseboard_fab2_lib.baseboard_fab2(sch_1):page185_i135:b" )
			)
			( pin "R8F36.1"
				( objectStatus "@baseboard_fab2_lib.baseboard_fab2(sch_1):page185_i136:a" )
			)
			( pin "R8F36.2"
				( objectStatus "@baseboard_fab2_lib.baseboard_fab2(sch_1):page185_i136:b" )
			)
			( pin "C1M27.1"
				( objectStatus "@baseboard_fab2_lib.baseboard_fab2(sch_1):page186_i3:a" )
			)
			( pin "C1M27.2"
				( objectStatus "@baseboard_fab2_lib.baseboard_fab2(sch_1):page186_i3:b" )
			)
			( pin "C1M26.1"
				( objectStatus "@baseboard_fab2_lib.baseboard_fab2(sch_1):page186_i6:a" )
			)
			( pin "C1M26.2"
				( objectStatus "@baseboard_fab2_lib.baseboard_fab2(sch_1):page186_i6:b" )
			)
			( pin "C1M23.1"
				( objectStatus "@baseboard_fab2_lib.baseboard_fab2(sch_1):page186_i7:a" )
			)
			( pin "C1M23.2"
				( objectStatus "@baseboard_fab2_lib.baseboard_fab2(sch_1):page186_i7:b" )
			)
			( pin "C1M22.1"
				( objectStatus "@baseboard_fab2_lib.baseboard_fab2(sch_1):page186_i8:a" )
			)
			( pin "C1M22.2"
				( objectStatus "@baseboard_fab2_lib.baseboard_fab2(sch_1):page186_i8:b" )
			)
			( pin "C1M24.1"
				( objectStatus "@baseboard_fab2_lib.baseboard_fab2(sch_1):page186_i10:a" )
			)
			( pin "C1M24.2"
				( objectStatus "@baseboard_fab2_lib.baseboard_fab2(sch_1):page186_i10:b" )
			)
			( pin "R1M14.1"
				( objectStatus "@baseboard_fab2_lib.baseboard_fab2(sch_1):page186_i220:a" )
			)
			( pin "R1M14.2"
				( objectStatus "@baseboard_fab2_lib.baseboard_fab2(sch_1):page186_i220:b" )
			)
			( pin "R9B7.1"
				( objectStatus "@baseboard_fab2_lib.baseboard_fab2(sch_1):page186_i222:a" )
			)
			( pin "R9B7.2"
				( objectStatus "@baseboard_fab2_lib.baseboard_fab2(sch_1):page186_i222:b" )
			)
			( pin "C1M20.1"
				( objectStatus "@baseboard_fab2_lib.baseboard_fab2(sch_1):page186_i270:a" )
			)
			( pin "C1M20.2"
				( objectStatus "@baseboard_fab2_lib.baseboard_fab2(sch_1):page186_i270:b" )
			)
			( pin "C1M21.1"
				( objectStatus "@baseboard_fab2_lib.baseboard_fab2(sch_1):page186_i334:a" )
			)
			( pin "C1M21.2"
				( objectStatus "@baseboard_fab2_lib.baseboard_fab2(sch_1):page186_i334:b" )
			)
			( pin "C1M25.1"
				( objectStatus "@baseboard_fab2_lib.baseboard_fab2(sch_1):page186_i335:a" )
			)
			( pin "C1M25.2"
				( objectStatus "@baseboard_fab2_lib.baseboard_fab2(sch_1):page186_i335:b" )
			)
			( pin "J9B3.1"
				( objectStatus "@baseboard_fab2_lib.baseboard_fab2(sch_1):page186_i336:io1" )
			)
			( pin "J9B3.2"
				( objectStatus "@baseboard_fab2_lib.baseboard_fab2(sch_1):page186_i336:io2" )
			)
			( pin "J9B3.3"
				( objectStatus "@baseboard_fab2_lib.baseboard_fab2(sch_1):page186_i336:io3" )
			)
			( pin "J9B3.4"
				( objectStatus "@baseboard_fab2_lib.baseboard_fab2(sch_1):page186_i336:io4" )
			)
			( pin "J9B3.5"
				( objectStatus "@baseboard_fab2_lib.baseboard_fab2(sch_1):page186_i336:io5" )
			)
			( pin "J9B3.6"
				( objectStatus "@baseboard_fab2_lib.baseboard_fab2(sch_1):page186_i336:io6" )
			)
			( pin "J9B3.7"
				( objectStatus "@baseboard_fab2_lib.baseboard_fab2(sch_1):page186_i336:io7" )
			)
			( pin "J9B3.8"
				( objectStatus "@baseboard_fab2_lib.baseboard_fab2(sch_1):page186_i336:io8" )
			)
			( pin "J9B3.9"
				( objectStatus "@baseboard_fab2_lib.baseboard_fab2(sch_1):page186_i336:io9" )
			)
			( pin "J9B3.10"
				( objectStatus "@baseboard_fab2_lib.baseboard_fab2(sch_1):page186_i336:io10" )
			)
			( pin "J9B3.11"
				( objectStatus "@baseboard_fab2_lib.baseboard_fab2(sch_1):page186_i336:io11" )
			)
			( pin "J9B3.12"
				( objectStatus "@baseboard_fab2_lib.baseboard_fab2(sch_1):page186_i336:io12" )
			)
			( pin "J9B3.13"
				( objectStatus "@baseboard_fab2_lib.baseboard_fab2(sch_1):page186_i336:io13" )
			)
			( pin "J9B3.14"
				( objectStatus "@baseboard_fab2_lib.baseboard_fab2(sch_1):page186_i336:io14" )
			)
			( pin "J9B3.15"
				( objectStatus "@baseboard_fab2_lib.baseboard_fab2(sch_1):page186_i336:io15" )
			)
			( pin "J9B3.16"
				( objectStatus "@baseboard_fab2_lib.baseboard_fab2(sch_1):page186_i336:io16" )
			)
			( pin "J9B3.17"
				( objectStatus "@baseboard_fab2_lib.baseboard_fab2(sch_1):page186_i336:io17" )
			)
			( pin "J9B3.18"
				( objectStatus "@baseboard_fab2_lib.baseboard_fab2(sch_1):page186_i336:io18" )
			)
			( pin "J9B3.19"
				( objectStatus "@baseboard_fab2_lib.baseboard_fab2(sch_1):page186_i336:io19" )
			)
			( pin "J9B3.20"
				( objectStatus "@baseboard_fab2_lib.baseboard_fab2(sch_1):page186_i336:io20" )
			)
			( pin "J9B3.21"
				( objectStatus "@baseboard_fab2_lib.baseboard_fab2(sch_1):page186_i336:io21" )
			)
			( pin "J9B3.22"
				( objectStatus "@baseboard_fab2_lib.baseboard_fab2(sch_1):page186_i336:io22" )
			)
			( pin "J9B3.23"
				( objectStatus "@baseboard_fab2_lib.baseboard_fab2(sch_1):page186_i336:io23" )
			)
			( pin "J9B3.24"
				( objectStatus "@baseboard_fab2_lib.baseboard_fab2(sch_1):page186_i336:io24" )
			)
			( pin "J9B3.25"
				( objectStatus "@baseboard_fab2_lib.baseboard_fab2(sch_1):page186_i336:io25" )
			)
			( pin "J9B3.26"
				( objectStatus "@baseboard_fab2_lib.baseboard_fab2(sch_1):page186_i336:io26" )
			)
			( pin "J9B3.27"
				( objectStatus "@baseboard_fab2_lib.baseboard_fab2(sch_1):page186_i336:io27" )
			)
			( pin "J9B3.28"
				( objectStatus "@baseboard_fab2_lib.baseboard_fab2(sch_1):page186_i336:io28" )
			)
			( pin "J9B3.29"
				( objectStatus "@baseboard_fab2_lib.baseboard_fab2(sch_1):page186_i336:io29" )
			)
			( pin "J9B3.30"
				( objectStatus "@baseboard_fab2_lib.baseboard_fab2(sch_1):page186_i336:io30" )
			)
			( pin "J9B3.31"
				( objectStatus "@baseboard_fab2_lib.baseboard_fab2(sch_1):page186_i336:io31" )
			)
			( pin "J9B3.32"
				( objectStatus "@baseboard_fab2_lib.baseboard_fab2(sch_1):page186_i336:io32" )
			)
			( pin "J9B3.33"
				( objectStatus "@baseboard_fab2_lib.baseboard_fab2(sch_1):page186_i336:io33" )
			)
			( pin "J9B3.34"
				( objectStatus "@baseboard_fab2_lib.baseboard_fab2(sch_1):page186_i336:io34" )
			)
			( pin "J9B3.35"
				( objectStatus "@baseboard_fab2_lib.baseboard_fab2(sch_1):page186_i336:io35" )
			)
			( pin "J9B3.36"
				( objectStatus "@baseboard_fab2_lib.baseboard_fab2(sch_1):page186_i336:io36" )
			)
			( pin "J9B3.37"
				( objectStatus "@baseboard_fab2_lib.baseboard_fab2(sch_1):page186_i336:io37" )
			)
			( pin "J9B3.38"
				( objectStatus "@baseboard_fab2_lib.baseboard_fab2(sch_1):page186_i336:io38" )
			)
			( pin "J9B3.39"
				( objectStatus "@baseboard_fab2_lib.baseboard_fab2(sch_1):page186_i336:io39" )
			)
			( pin "J9B3.40"
				( objectStatus "@baseboard_fab2_lib.baseboard_fab2(sch_1):page186_i336:io40" )
			)
			( pin "J9B3.41"
				( objectStatus "@baseboard_fab2_lib.baseboard_fab2(sch_1):page186_i336:io41" )
			)
			( pin "J9B3.42"
				( objectStatus "@baseboard_fab2_lib.baseboard_fab2(sch_1):page186_i336:io42" )
			)
			( pin "J9B3.43"
				( objectStatus "@baseboard_fab2_lib.baseboard_fab2(sch_1):page186_i336:io43" )
			)
			( pin "J9B3.44"
				( objectStatus "@baseboard_fab2_lib.baseboard_fab2(sch_1):page186_i336:io44" )
			)
			( pin "J9B3.45"
				( objectStatus "@baseboard_fab2_lib.baseboard_fab2(sch_1):page186_i336:io45" )
			)
			( pin "J9B3.46"
				( objectStatus "@baseboard_fab2_lib.baseboard_fab2(sch_1):page186_i336:io46" )
			)
			( pin "J9B3.47"
				( objectStatus "@baseboard_fab2_lib.baseboard_fab2(sch_1):page186_i336:io47" )
			)
			( pin "J9B3.48"
				( objectStatus "@baseboard_fab2_lib.baseboard_fab2(sch_1):page186_i336:io48" )
			)
			( pin "J9B3.49"
				( objectStatus "@baseboard_fab2_lib.baseboard_fab2(sch_1):page186_i336:io49" )
			)
			( pin "J9B3.50"
				( objectStatus "@baseboard_fab2_lib.baseboard_fab2(sch_1):page186_i336:io50" )
			)
			( pin "J9B3.51"
				( objectStatus "@baseboard_fab2_lib.baseboard_fab2(sch_1):page186_i336:io51" )
			)
			( pin "J9B3.52"
				( objectStatus "@baseboard_fab2_lib.baseboard_fab2(sch_1):page186_i336:io52" )
			)
			( pin "J9B3.53"
				( objectStatus "@baseboard_fab2_lib.baseboard_fab2(sch_1):page186_i336:io53" )
			)
			( pin "J9B3.54"
				( objectStatus "@baseboard_fab2_lib.baseboard_fab2(sch_1):page186_i336:io54" )
			)
			( pin "J9B3.55"
				( objectStatus "@baseboard_fab2_lib.baseboard_fab2(sch_1):page186_i336:io55" )
			)
			( pin "J9B3.56"
				( objectStatus "@baseboard_fab2_lib.baseboard_fab2(sch_1):page186_i336:io56" )
			)
			( pin "J9B3.57"
				( objectStatus "@baseboard_fab2_lib.baseboard_fab2(sch_1):page186_i336:io57" )
			)
			( pin "J9B3.58"
				( objectStatus "@baseboard_fab2_lib.baseboard_fab2(sch_1):page186_i336:io58" )
			)
			( pin "J9B3.59"
				( objectStatus "@baseboard_fab2_lib.baseboard_fab2(sch_1):page186_i336:io59" )
			)
			( pin "J9B3.60"
				( objectStatus "@baseboard_fab2_lib.baseboard_fab2(sch_1):page186_i336:io60" )
			)
			( pin "J9B3.61"
				( objectStatus "@baseboard_fab2_lib.baseboard_fab2(sch_1):page186_i336:io61" )
			)
			( pin "J9B3.62"
				( objectStatus "@baseboard_fab2_lib.baseboard_fab2(sch_1):page186_i336:io62" )
			)
			( pin "J9B3.63"
				( objectStatus "@baseboard_fab2_lib.baseboard_fab2(sch_1):page186_i336:io63" )
			)
			( pin "J9B3.64"
				( objectStatus "@baseboard_fab2_lib.baseboard_fab2(sch_1):page186_i336:io64" )
			)
			( pin "J9B3.65"
				( objectStatus "@baseboard_fab2_lib.baseboard_fab2(sch_1):page186_i336:io65" )
			)
			( pin "J9B3.66"
				( objectStatus "@baseboard_fab2_lib.baseboard_fab2(sch_1):page186_i336:io66" )
			)
			( pin "J9B3.67"
				( objectStatus "@baseboard_fab2_lib.baseboard_fab2(sch_1):page186_i336:io67" )
			)
			( pin "J9B3.68"
				( objectStatus "@baseboard_fab2_lib.baseboard_fab2(sch_1):page186_i336:io68" )
			)
			( pin "J9B3.69"
				( objectStatus "@baseboard_fab2_lib.baseboard_fab2(sch_1):page186_i336:io69" )
			)
			( pin "J9B3.70"
				( objectStatus "@baseboard_fab2_lib.baseboard_fab2(sch_1):page186_i336:io70" )
			)
			( pin "J9B3.71"
				( objectStatus "@baseboard_fab2_lib.baseboard_fab2(sch_1):page186_i336:io71" )
			)
			( pin "J9B3.72"
				( objectStatus "@baseboard_fab2_lib.baseboard_fab2(sch_1):page186_i336:io72" )
			)
			( pin "J9B3.73"
				( objectStatus "@baseboard_fab2_lib.baseboard_fab2(sch_1):page186_i336:io73" )
			)
			( pin "J9B3.74"
				( objectStatus "@baseboard_fab2_lib.baseboard_fab2(sch_1):page186_i336:io74" )
			)
			( pin "J9B3.75"
				( objectStatus "@baseboard_fab2_lib.baseboard_fab2(sch_1):page186_i336:io75" )
			)
			( pin "J9B3.76"
				( objectStatus "@baseboard_fab2_lib.baseboard_fab2(sch_1):page186_i336:io76" )
			)
			( pin "J9B3.77"
				( objectStatus "@baseboard_fab2_lib.baseboard_fab2(sch_1):page186_i336:io77" )
			)
			( pin "J9B3.78"
				( objectStatus "@baseboard_fab2_lib.baseboard_fab2(sch_1):page186_i336:io78" )
			)
			( pin "J9B3.79"
				( objectStatus "@baseboard_fab2_lib.baseboard_fab2(sch_1):page186_i336:io79" )
			)
			( pin "J9B3.80"
				( objectStatus "@baseboard_fab2_lib.baseboard_fab2(sch_1):page186_i336:io80" )
			)
			( pin "J9B3.81"
				( objectStatus "@baseboard_fab2_lib.baseboard_fab2(sch_1):page186_i336:io81" )
			)
			( pin "J9B3.82"
				( objectStatus "@baseboard_fab2_lib.baseboard_fab2(sch_1):page186_i336:io82" )
			)
			( pin "J9B3.83"
				( objectStatus "@baseboard_fab2_lib.baseboard_fab2(sch_1):page186_i336:io83" )
			)
			( pin "J9B3.84"
				( objectStatus "@baseboard_fab2_lib.baseboard_fab2(sch_1):page186_i336:io84" )
			)
			( pin "J9B3.85"
				( objectStatus "@baseboard_fab2_lib.baseboard_fab2(sch_1):page186_i336:io85" )
			)
			( pin "J9B3.86"
				( objectStatus "@baseboard_fab2_lib.baseboard_fab2(sch_1):page186_i336:io86" )
			)
			( pin "J9B3.87"
				( objectStatus "@baseboard_fab2_lib.baseboard_fab2(sch_1):page186_i336:io87" )
			)
			( pin "J9B3.88"
				( objectStatus "@baseboard_fab2_lib.baseboard_fab2(sch_1):page186_i336:io88" )
			)
			( pin "J9B3.89"
				( objectStatus "@baseboard_fab2_lib.baseboard_fab2(sch_1):page186_i336:io89" )
			)
			( pin "J9B3.90"
				( objectStatus "@baseboard_fab2_lib.baseboard_fab2(sch_1):page186_i336:io90" )
			)
			( pin "J9B3.91"
				( objectStatus "@baseboard_fab2_lib.baseboard_fab2(sch_1):page186_i336:io91" )
			)
			( pin "J9B3.92"
				( objectStatus "@baseboard_fab2_lib.baseboard_fab2(sch_1):page186_i336:io92" )
			)
			( pin "J9B3.93"
				( objectStatus "@baseboard_fab2_lib.baseboard_fab2(sch_1):page186_i336:io93" )
			)
			( pin "J9B3.94"
				( objectStatus "@baseboard_fab2_lib.baseboard_fab2(sch_1):page186_i336:io94" )
			)
			( pin "J9B3.95"
				( objectStatus "@baseboard_fab2_lib.baseboard_fab2(sch_1):page186_i336:io95" )
			)
			( pin "J9B3.96"
				( objectStatus "@baseboard_fab2_lib.baseboard_fab2(sch_1):page186_i336:io96" )
			)
			( pin "J9B3.97"
				( objectStatus "@baseboard_fab2_lib.baseboard_fab2(sch_1):page186_i336:io97" )
			)
			( pin "J9B3.98"
				( objectStatus "@baseboard_fab2_lib.baseboard_fab2(sch_1):page186_i336:io98" )
			)
			( pin "J9B3.99"
				( objectStatus "@baseboard_fab2_lib.baseboard_fab2(sch_1):page186_i336:io99" )
			)
			( pin "J9B3.100"
				( objectStatus "@baseboard_fab2_lib.baseboard_fab2(sch_1):page186_i336:io100" )
			)
			( pin "J9B3.101"
				( objectStatus "@baseboard_fab2_lib.baseboard_fab2(sch_1):page186_i336:io101" )
			)
			( pin "J9B3.102"
				( objectStatus "@baseboard_fab2_lib.baseboard_fab2(sch_1):page186_i336:io102" )
			)
			( pin "J9B3.103"
				( objectStatus "@baseboard_fab2_lib.baseboard_fab2(sch_1):page186_i336:io103" )
			)
			( pin "J9B3.104"
				( objectStatus "@baseboard_fab2_lib.baseboard_fab2(sch_1):page186_i336:io104" )
			)
			( pin "J9B3.105"
				( objectStatus "@baseboard_fab2_lib.baseboard_fab2(sch_1):page186_i336:io105" )
			)
			( pin "J9B3.106"
				( objectStatus "@baseboard_fab2_lib.baseboard_fab2(sch_1):page186_i336:io106" )
			)
			( pin "J9B3.107"
				( objectStatus "@baseboard_fab2_lib.baseboard_fab2(sch_1):page186_i336:io107" )
			)
			( pin "J9B3.108"
				( objectStatus "@baseboard_fab2_lib.baseboard_fab2(sch_1):page186_i336:io108" )
			)
			( pin "J9B3.109"
				( objectStatus "@baseboard_fab2_lib.baseboard_fab2(sch_1):page186_i336:io109" )
			)
			( pin "J9B3.110"
				( objectStatus "@baseboard_fab2_lib.baseboard_fab2(sch_1):page186_i336:io110" )
			)
			( pin "J9B3.111"
				( objectStatus "@baseboard_fab2_lib.baseboard_fab2(sch_1):page186_i336:io111" )
			)
			( pin "J9B3.112"
				( objectStatus "@baseboard_fab2_lib.baseboard_fab2(sch_1):page186_i336:io112" )
			)
			( pin "J9B3.113"
				( objectStatus "@baseboard_fab2_lib.baseboard_fab2(sch_1):page186_i336:io113" )
			)
			( pin "J9B3.114"
				( objectStatus "@baseboard_fab2_lib.baseboard_fab2(sch_1):page186_i336:io114" )
			)
			( pin "J9B3.115"
				( objectStatus "@baseboard_fab2_lib.baseboard_fab2(sch_1):page186_i336:io115" )
			)
			( pin "J9B3.116"
				( objectStatus "@baseboard_fab2_lib.baseboard_fab2(sch_1):page186_i336:io116" )
			)
			( pin "J9B3.117"
				( objectStatus "@baseboard_fab2_lib.baseboard_fab2(sch_1):page186_i336:io117" )
			)
			( pin "J9B3.118"
				( objectStatus "@baseboard_fab2_lib.baseboard_fab2(sch_1):page186_i336:io118" )
			)
			( pin "J9B3.119"
				( objectStatus "@baseboard_fab2_lib.baseboard_fab2(sch_1):page186_i336:io119" )
			)
			( pin "J9B3.120"
				( objectStatus "@baseboard_fab2_lib.baseboard_fab2(sch_1):page186_i336:io120" )
			)
			( pin "R1M16.1"
				( objectStatus "@baseboard_fab2_lib.baseboard_fab2(sch_1):page186_i337:a" )
			)
			( pin "R1M16.2"
				( objectStatus "@baseboard_fab2_lib.baseboard_fab2(sch_1):page186_i337:b" )
			)
			( pin "R1M17.1"
				( objectStatus "@baseboard_fab2_lib.baseboard_fab2(sch_1):page186_i338:a" )
			)
			( pin "R1M17.2"
				( objectStatus "@baseboard_fab2_lib.baseboard_fab2(sch_1):page186_i338:b" )
			)
			( pin "R1M15.1"
				( objectStatus "@baseboard_fab2_lib.baseboard_fab2(sch_1):page186_i339:a" )
			)
			( pin "R1M15.2"
				( objectStatus "@baseboard_fab2_lib.baseboard_fab2(sch_1):page186_i339:b" )
			)
			( pin "R1M18.1"
				( objectStatus "@baseboard_fab2_lib.baseboard_fab2(sch_1):page186_i340:a" )
			)
			( pin "R1M18.2"
				( objectStatus "@baseboard_fab2_lib.baseboard_fab2(sch_1):page186_i340:b" )
			)
			( pin "C9B10.1"
				( objectStatus "@baseboard_fab2_lib.baseboard_fab2(sch_1):page186_i345:a" )
			)
			( pin "C9B10.2"
				( objectStatus "@baseboard_fab2_lib.baseboard_fab2(sch_1):page186_i345:b" )
			)
			( pin "C9B9.1"
				( objectStatus "@baseboard_fab2_lib.baseboard_fab2(sch_1):page186_i347:a" )
			)
			( pin "C9B9.2"
				( objectStatus "@baseboard_fab2_lib.baseboard_fab2(sch_1):page186_i347:b" )
			)
			( pin "R2R8.1"
				( objectStatus "@baseboard_fab2_lib.baseboard_fab2(sch_1):page187_i18:a" )
			)
			( pin "R2R8.2"
				( objectStatus "@baseboard_fab2_lib.baseboard_fab2(sch_1):page187_i18:b" )
			)
			( pin "J8E3.1"
				( objectStatus "@baseboard_fab2_lib.baseboard_fab2(sch_1):page187_i119:io1" )
			)
			( pin "J8E3.2"
				( objectStatus "@baseboard_fab2_lib.baseboard_fab2(sch_1):page187_i119:io2" )
			)
			( pin "J8E3.3"
				( objectStatus "@baseboard_fab2_lib.baseboard_fab2(sch_1):page187_i119:io3" )
			)
			( pin "J8E3.4"
				( objectStatus "@baseboard_fab2_lib.baseboard_fab2(sch_1):page187_i119:io4" )
			)
			( pin "J8E3.5"
				( objectStatus "@baseboard_fab2_lib.baseboard_fab2(sch_1):page187_i119:io5" )
			)
			( pin "J8E3.6"
				( objectStatus "@baseboard_fab2_lib.baseboard_fab2(sch_1):page187_i119:io6" )
			)
			( pin "J8E3.7"
				( objectStatus "@baseboard_fab2_lib.baseboard_fab2(sch_1):page187_i119:io7" )
			)
			( pin "J8E3.8"
				( objectStatus "@baseboard_fab2_lib.baseboard_fab2(sch_1):page187_i119:io8" )
			)
			( pin "J8E3.9"
				( objectStatus "@baseboard_fab2_lib.baseboard_fab2(sch_1):page187_i119:io9" )
			)
			( pin "J8E3.10"
				( objectStatus "@baseboard_fab2_lib.baseboard_fab2(sch_1):page187_i119:io10" )
			)
			( pin "J8E3.11"
				( objectStatus "@baseboard_fab2_lib.baseboard_fab2(sch_1):page187_i119:io11" )
			)
			( pin "J8E3.12"
				( objectStatus "@baseboard_fab2_lib.baseboard_fab2(sch_1):page187_i119:io12" )
			)
			( pin "J8E3.13"
				( objectStatus "@baseboard_fab2_lib.baseboard_fab2(sch_1):page187_i119:io13" )
			)
			( pin "J8E3.14"
				( objectStatus "@baseboard_fab2_lib.baseboard_fab2(sch_1):page187_i119:io14" )
			)
			( pin "J8E3.15"
				( objectStatus "@baseboard_fab2_lib.baseboard_fab2(sch_1):page187_i119:io15" )
			)
			( pin "J8E3.16"
				( objectStatus "@baseboard_fab2_lib.baseboard_fab2(sch_1):page187_i119:io16" )
			)
			( pin "J8E3.17"
				( objectStatus "@baseboard_fab2_lib.baseboard_fab2(sch_1):page187_i119:io17" )
			)
			( pin "J8E3.18"
				( objectStatus "@baseboard_fab2_lib.baseboard_fab2(sch_1):page187_i119:io18" )
			)
			( pin "J8E3.19"
				( objectStatus "@baseboard_fab2_lib.baseboard_fab2(sch_1):page187_i119:io19" )
			)
			( pin "J8E3.20"
				( objectStatus "@baseboard_fab2_lib.baseboard_fab2(sch_1):page187_i119:io20" )
			)
			( pin "J8E3.21"
				( objectStatus "@baseboard_fab2_lib.baseboard_fab2(sch_1):page187_i119:io21" )
			)
			( pin "J8E3.22"
				( objectStatus "@baseboard_fab2_lib.baseboard_fab2(sch_1):page187_i119:io22" )
			)
			( pin "J8E3.23"
				( objectStatus "@baseboard_fab2_lib.baseboard_fab2(sch_1):page187_i119:io23" )
			)
			( pin "J8E3.24"
				( objectStatus "@baseboard_fab2_lib.baseboard_fab2(sch_1):page187_i119:io24" )
			)
			( pin "J8E3.25"
				( objectStatus "@baseboard_fab2_lib.baseboard_fab2(sch_1):page187_i119:io25" )
			)
			( pin "J8E3.26"
				( objectStatus "@baseboard_fab2_lib.baseboard_fab2(sch_1):page187_i119:io26" )
			)
			( pin "J8E3.27"
				( objectStatus "@baseboard_fab2_lib.baseboard_fab2(sch_1):page187_i119:io27" )
			)
			( pin "J8E3.28"
				( objectStatus "@baseboard_fab2_lib.baseboard_fab2(sch_1):page187_i119:io28" )
			)
			( pin "J8E3.29"
				( objectStatus "@baseboard_fab2_lib.baseboard_fab2(sch_1):page187_i119:io29" )
			)
			( pin "J8E3.30"
				( objectStatus "@baseboard_fab2_lib.baseboard_fab2(sch_1):page187_i119:io30" )
			)
			( pin "J8E3.31"
				( objectStatus "@baseboard_fab2_lib.baseboard_fab2(sch_1):page187_i119:io31" )
			)
			( pin "J8E3.32"
				( objectStatus "@baseboard_fab2_lib.baseboard_fab2(sch_1):page187_i119:io32" )
			)
			( pin "J8E3.33"
				( objectStatus "@baseboard_fab2_lib.baseboard_fab2(sch_1):page187_i119:io33" )
			)
			( pin "J8E3.34"
				( objectStatus "@baseboard_fab2_lib.baseboard_fab2(sch_1):page187_i119:io34" )
			)
			( pin "J8E3.35"
				( objectStatus "@baseboard_fab2_lib.baseboard_fab2(sch_1):page187_i119:io35" )
			)
			( pin "J8E3.36"
				( objectStatus "@baseboard_fab2_lib.baseboard_fab2(sch_1):page187_i119:io36" )
			)
			( pin "J8E3.37"
				( objectStatus "@baseboard_fab2_lib.baseboard_fab2(sch_1):page187_i119:io37" )
			)
			( pin "J8E3.38"
				( objectStatus "@baseboard_fab2_lib.baseboard_fab2(sch_1):page187_i119:io38" )
			)
			( pin "J8E3.39"
				( objectStatus "@baseboard_fab2_lib.baseboard_fab2(sch_1):page187_i119:io39" )
			)
			( pin "J8E3.40"
				( objectStatus "@baseboard_fab2_lib.baseboard_fab2(sch_1):page187_i119:io40" )
			)
			( pin "J8E3.41"
				( objectStatus "@baseboard_fab2_lib.baseboard_fab2(sch_1):page187_i119:io41" )
			)
			( pin "J8E3.42"
				( objectStatus "@baseboard_fab2_lib.baseboard_fab2(sch_1):page187_i119:io42" )
			)
			( pin "J8E3.43"
				( objectStatus "@baseboard_fab2_lib.baseboard_fab2(sch_1):page187_i119:io43" )
			)
			( pin "J8E3.44"
				( objectStatus "@baseboard_fab2_lib.baseboard_fab2(sch_1):page187_i119:io44" )
			)
			( pin "J8E3.45"
				( objectStatus "@baseboard_fab2_lib.baseboard_fab2(sch_1):page187_i119:io45" )
			)
			( pin "J8E3.46"
				( objectStatus "@baseboard_fab2_lib.baseboard_fab2(sch_1):page187_i119:io46" )
			)
			( pin "J8E3.47"
				( objectStatus "@baseboard_fab2_lib.baseboard_fab2(sch_1):page187_i119:io47" )
			)
			( pin "J8E3.48"
				( objectStatus "@baseboard_fab2_lib.baseboard_fab2(sch_1):page187_i119:io48" )
			)
			( pin "J8E3.49"
				( objectStatus "@baseboard_fab2_lib.baseboard_fab2(sch_1):page187_i119:io49" )
			)
			( pin "J8E3.50"
				( objectStatus "@baseboard_fab2_lib.baseboard_fab2(sch_1):page187_i119:io50" )
			)
			( pin "J8E3.51"
				( objectStatus "@baseboard_fab2_lib.baseboard_fab2(sch_1):page187_i119:io51" )
			)
			( pin "J8E3.52"
				( objectStatus "@baseboard_fab2_lib.baseboard_fab2(sch_1):page187_i119:io52" )
			)
			( pin "J8E3.53"
				( objectStatus "@baseboard_fab2_lib.baseboard_fab2(sch_1):page187_i119:io53" )
			)
			( pin "J8E3.54"
				( objectStatus "@baseboard_fab2_lib.baseboard_fab2(sch_1):page187_i119:io54" )
			)
			( pin "J8E3.55"
				( objectStatus "@baseboard_fab2_lib.baseboard_fab2(sch_1):page187_i119:io55" )
			)
			( pin "J8E3.56"
				( objectStatus "@baseboard_fab2_lib.baseboard_fab2(sch_1):page187_i119:io56" )
			)
			( pin "J8E3.57"
				( objectStatus "@baseboard_fab2_lib.baseboard_fab2(sch_1):page187_i119:io57" )
			)
			( pin "J8E3.58"
				( objectStatus "@baseboard_fab2_lib.baseboard_fab2(sch_1):page187_i119:io58" )
			)
			( pin "J8E3.59"
				( objectStatus "@baseboard_fab2_lib.baseboard_fab2(sch_1):page187_i119:io59" )
			)
			( pin "J8E3.60"
				( objectStatus "@baseboard_fab2_lib.baseboard_fab2(sch_1):page187_i119:io60" )
			)
			( pin "J8E3.61"
				( objectStatus "@baseboard_fab2_lib.baseboard_fab2(sch_1):page187_i119:io61" )
			)
			( pin "J8E3.62"
				( objectStatus "@baseboard_fab2_lib.baseboard_fab2(sch_1):page187_i119:io62" )
			)
			( pin "J8E3.63"
				( objectStatus "@baseboard_fab2_lib.baseboard_fab2(sch_1):page187_i119:io63" )
			)
			( pin "J8E3.64"
				( objectStatus "@baseboard_fab2_lib.baseboard_fab2(sch_1):page187_i119:io64" )
			)
			( pin "J8E3.65"
				( objectStatus "@baseboard_fab2_lib.baseboard_fab2(sch_1):page187_i119:io65" )
			)
			( pin "J8E3.66"
				( objectStatus "@baseboard_fab2_lib.baseboard_fab2(sch_1):page187_i119:io66" )
			)
			( pin "J8E3.67"
				( objectStatus "@baseboard_fab2_lib.baseboard_fab2(sch_1):page187_i119:io67" )
			)
			( pin "J8E3.68"
				( objectStatus "@baseboard_fab2_lib.baseboard_fab2(sch_1):page187_i119:io68" )
			)
			( pin "J8E3.69"
				( objectStatus "@baseboard_fab2_lib.baseboard_fab2(sch_1):page187_i119:io69" )
			)
			( pin "J8E3.70"
				( objectStatus "@baseboard_fab2_lib.baseboard_fab2(sch_1):page187_i119:io70" )
			)
			( pin "J8E3.71"
				( objectStatus "@baseboard_fab2_lib.baseboard_fab2(sch_1):page187_i119:io71" )
			)
			( pin "J8E3.72"
				( objectStatus "@baseboard_fab2_lib.baseboard_fab2(sch_1):page187_i119:io72" )
			)
			( pin "J8E3.73"
				( objectStatus "@baseboard_fab2_lib.baseboard_fab2(sch_1):page187_i119:io73" )
			)
			( pin "J8E3.74"
				( objectStatus "@baseboard_fab2_lib.baseboard_fab2(sch_1):page187_i119:io74" )
			)
			( pin "J8E3.75"
				( objectStatus "@baseboard_fab2_lib.baseboard_fab2(sch_1):page187_i119:io75" )
			)
			( pin "J8E3.76"
				( objectStatus "@baseboard_fab2_lib.baseboard_fab2(sch_1):page187_i119:io76" )
			)
			( pin "J8E3.77"
				( objectStatus "@baseboard_fab2_lib.baseboard_fab2(sch_1):page187_i119:io77" )
			)
			( pin "J8E3.78"
				( objectStatus "@baseboard_fab2_lib.baseboard_fab2(sch_1):page187_i119:io78" )
			)
			( pin "J8E3.79"
				( objectStatus "@baseboard_fab2_lib.baseboard_fab2(sch_1):page187_i119:io79" )
			)
			( pin "J8E3.80"
				( objectStatus "@baseboard_fab2_lib.baseboard_fab2(sch_1):page187_i119:io80" )
			)
			( pin "R9E10.1"
				( objectStatus "@baseboard_fab2_lib.baseboard_fab2(sch_1):page187_i145:a" )
			)
			( pin "R9E10.2"
				( objectStatus "@baseboard_fab2_lib.baseboard_fab2(sch_1):page187_i145:b" )
			)
			( pin "R9E11.1"
				( objectStatus "@baseboard_fab2_lib.baseboard_fab2(sch_1):page187_i150:a" )
			)
			( pin "R9E11.2"
				( objectStatus "@baseboard_fab2_lib.baseboard_fab2(sch_1):page187_i150:b" )
			)
			( pin "R9E12.1"
				( objectStatus "@baseboard_fab2_lib.baseboard_fab2(sch_1):page187_i153:a" )
			)
			( pin "R9E12.2"
				( objectStatus "@baseboard_fab2_lib.baseboard_fab2(sch_1):page187_i153:b" )
			)
			( pin "C2R15.1"
				( objectStatus "@baseboard_fab2_lib.baseboard_fab2(sch_1):page188_i2:a" )
			)
			( pin "C2R15.2"
				( objectStatus "@baseboard_fab2_lib.baseboard_fab2(sch_1):page188_i2:b" )
			)
			( pin "C2R18.1"
				( objectStatus "@baseboard_fab2_lib.baseboard_fab2(sch_1):page188_i3:a" )
			)
			( pin "C2R18.2"
				( objectStatus "@baseboard_fab2_lib.baseboard_fab2(sch_1):page188_i3:b" )
			)
			( pin "C2P11.1"
				( objectStatus "@baseboard_fab2_lib.baseboard_fab2(sch_1):page188_i21:a" )
			)
			( pin "C2P11.2"
				( objectStatus "@baseboard_fab2_lib.baseboard_fab2(sch_1):page188_i21:b" )
			)
			( pin "C2P12.1"
				( objectStatus "@baseboard_fab2_lib.baseboard_fab2(sch_1):page188_i23:a" )
			)
			( pin "C2P12.2"
				( objectStatus "@baseboard_fab2_lib.baseboard_fab2(sch_1):page188_i23:b" )
			)
			( pin "C2R17.1"
				( objectStatus "@baseboard_fab2_lib.baseboard_fab2(sch_1):page188_i25:a" )
			)
			( pin "C2R17.2"
				( objectStatus "@baseboard_fab2_lib.baseboard_fab2(sch_1):page188_i25:b" )
			)
			( pin "J8E4.1"
				( objectStatus "@baseboard_fab2_lib.baseboard_fab2(sch_1):page188_i27:io1" )
			)
			( pin "J8E4.2"
				( objectStatus "@baseboard_fab2_lib.baseboard_fab2(sch_1):page188_i27:io2" )
			)
			( pin "J8E4.3"
				( objectStatus "@baseboard_fab2_lib.baseboard_fab2(sch_1):page188_i27:io3" )
			)
			( pin "J8E4.4"
				( objectStatus "@baseboard_fab2_lib.baseboard_fab2(sch_1):page188_i27:io4" )
			)
			( pin "J8E4.5"
				( objectStatus "@baseboard_fab2_lib.baseboard_fab2(sch_1):page188_i27:io5" )
			)
			( pin "J8E4.6"
				( objectStatus "@baseboard_fab2_lib.baseboard_fab2(sch_1):page188_i27:io6" )
			)
			( pin "J8E4.7"
				( objectStatus "@baseboard_fab2_lib.baseboard_fab2(sch_1):page188_i27:io7" )
			)
			( pin "J8E4.8"
				( objectStatus "@baseboard_fab2_lib.baseboard_fab2(sch_1):page188_i27:io8" )
			)
			( pin "J8E4.9"
				( objectStatus "@baseboard_fab2_lib.baseboard_fab2(sch_1):page188_i27:io9" )
			)
			( pin "J8E4.10"
				( objectStatus "@baseboard_fab2_lib.baseboard_fab2(sch_1):page188_i27:io10" )
			)
			( pin "J8E4.11"
				( objectStatus "@baseboard_fab2_lib.baseboard_fab2(sch_1):page188_i27:io11" )
			)
			( pin "J8E4.12"
				( objectStatus "@baseboard_fab2_lib.baseboard_fab2(sch_1):page188_i27:io12" )
			)
			( pin "J8E4.13"
				( objectStatus "@baseboard_fab2_lib.baseboard_fab2(sch_1):page188_i27:io13" )
			)
			( pin "J8E4.14"
				( objectStatus "@baseboard_fab2_lib.baseboard_fab2(sch_1):page188_i27:io14" )
			)
			( pin "J8E4.15"
				( objectStatus "@baseboard_fab2_lib.baseboard_fab2(sch_1):page188_i27:io15" )
			)
			( pin "J8E4.16"
				( objectStatus "@baseboard_fab2_lib.baseboard_fab2(sch_1):page188_i27:io16" )
			)
			( pin "J8E4.17"
				( objectStatus "@baseboard_fab2_lib.baseboard_fab2(sch_1):page188_i27:io17" )
			)
			( pin "J8E4.18"
				( objectStatus "@baseboard_fab2_lib.baseboard_fab2(sch_1):page188_i27:io18" )
			)
			( pin "J8E4.19"
				( objectStatus "@baseboard_fab2_lib.baseboard_fab2(sch_1):page188_i27:io19" )
			)
			( pin "J8E4.20"
				( objectStatus "@baseboard_fab2_lib.baseboard_fab2(sch_1):page188_i27:io20" )
			)
			( pin "J8E4.21"
				( objectStatus "@baseboard_fab2_lib.baseboard_fab2(sch_1):page188_i27:io21" )
			)
			( pin "J8E4.22"
				( objectStatus "@baseboard_fab2_lib.baseboard_fab2(sch_1):page188_i27:io22" )
			)
			( pin "J8E4.23"
				( objectStatus "@baseboard_fab2_lib.baseboard_fab2(sch_1):page188_i27:io23" )
			)
			( pin "J8E4.24"
				( objectStatus "@baseboard_fab2_lib.baseboard_fab2(sch_1):page188_i27:io24" )
			)
			( pin "J8E4.25"
				( objectStatus "@baseboard_fab2_lib.baseboard_fab2(sch_1):page188_i27:io25" )
			)
			( pin "J8E4.26"
				( objectStatus "@baseboard_fab2_lib.baseboard_fab2(sch_1):page188_i27:io26" )
			)
			( pin "J8E4.27"
				( objectStatus "@baseboard_fab2_lib.baseboard_fab2(sch_1):page188_i27:io27" )
			)
			( pin "J8E4.28"
				( objectStatus "@baseboard_fab2_lib.baseboard_fab2(sch_1):page188_i27:io28" )
			)
			( pin "J8E4.29"
				( objectStatus "@baseboard_fab2_lib.baseboard_fab2(sch_1):page188_i27:io29" )
			)
			( pin "J8E4.30"
				( objectStatus "@baseboard_fab2_lib.baseboard_fab2(sch_1):page188_i27:io30" )
			)
			( pin "J8E4.31"
				( objectStatus "@baseboard_fab2_lib.baseboard_fab2(sch_1):page188_i27:io31" )
			)
			( pin "J8E4.32"
				( objectStatus "@baseboard_fab2_lib.baseboard_fab2(sch_1):page188_i27:io32" )
			)
			( pin "J8E4.33"
				( objectStatus "@baseboard_fab2_lib.baseboard_fab2(sch_1):page188_i27:io33" )
			)
			( pin "J8E4.34"
				( objectStatus "@baseboard_fab2_lib.baseboard_fab2(sch_1):page188_i27:io34" )
			)
			( pin "J8E4.35"
				( objectStatus "@baseboard_fab2_lib.baseboard_fab2(sch_1):page188_i27:io35" )
			)
			( pin "J8E4.36"
				( objectStatus "@baseboard_fab2_lib.baseboard_fab2(sch_1):page188_i27:io36" )
			)
			( pin "J8E4.37"
				( objectStatus "@baseboard_fab2_lib.baseboard_fab2(sch_1):page188_i27:io37" )
			)
			( pin "J8E4.38"
				( objectStatus "@baseboard_fab2_lib.baseboard_fab2(sch_1):page188_i27:io38" )
			)
			( pin "J8E4.39"
				( objectStatus "@baseboard_fab2_lib.baseboard_fab2(sch_1):page188_i27:io39" )
			)
			( pin "J8E4.40"
				( objectStatus "@baseboard_fab2_lib.baseboard_fab2(sch_1):page188_i27:io40" )
			)
			( pin "J8E4.41"
				( objectStatus "@baseboard_fab2_lib.baseboard_fab2(sch_1):page188_i27:io41" )
			)
			( pin "J8E4.42"
				( objectStatus "@baseboard_fab2_lib.baseboard_fab2(sch_1):page188_i27:io42" )
			)
			( pin "J8E4.43"
				( objectStatus "@baseboard_fab2_lib.baseboard_fab2(sch_1):page188_i27:io43" )
			)
			( pin "J8E4.44"
				( objectStatus "@baseboard_fab2_lib.baseboard_fab2(sch_1):page188_i27:io44" )
			)
			( pin "J8E4.45"
				( objectStatus "@baseboard_fab2_lib.baseboard_fab2(sch_1):page188_i27:io45" )
			)
			( pin "J8E4.46"
				( objectStatus "@baseboard_fab2_lib.baseboard_fab2(sch_1):page188_i27:io46" )
			)
			( pin "J8E4.47"
				( objectStatus "@baseboard_fab2_lib.baseboard_fab2(sch_1):page188_i27:io47" )
			)
			( pin "J8E4.48"
				( objectStatus "@baseboard_fab2_lib.baseboard_fab2(sch_1):page188_i27:io48" )
			)
			( pin "J8E4.49"
				( objectStatus "@baseboard_fab2_lib.baseboard_fab2(sch_1):page188_i27:io49" )
			)
			( pin "J8E4.50"
				( objectStatus "@baseboard_fab2_lib.baseboard_fab2(sch_1):page188_i27:io50" )
			)
			( pin "J8E4.51"
				( objectStatus "@baseboard_fab2_lib.baseboard_fab2(sch_1):page188_i27:io51" )
			)
			( pin "J8E4.52"
				( objectStatus "@baseboard_fab2_lib.baseboard_fab2(sch_1):page188_i27:io52" )
			)
			( pin "J8E4.53"
				( objectStatus "@baseboard_fab2_lib.baseboard_fab2(sch_1):page188_i27:io53" )
			)
			( pin "J8E4.54"
				( objectStatus "@baseboard_fab2_lib.baseboard_fab2(sch_1):page188_i27:io54" )
			)
			( pin "J8E4.55"
				( objectStatus "@baseboard_fab2_lib.baseboard_fab2(sch_1):page188_i27:io55" )
			)
			( pin "J8E4.56"
				( objectStatus "@baseboard_fab2_lib.baseboard_fab2(sch_1):page188_i27:io56" )
			)
			( pin "J8E4.57"
				( objectStatus "@baseboard_fab2_lib.baseboard_fab2(sch_1):page188_i27:io57" )
			)
			( pin "J8E4.58"
				( objectStatus "@baseboard_fab2_lib.baseboard_fab2(sch_1):page188_i27:io58" )
			)
			( pin "J8E4.59"
				( objectStatus "@baseboard_fab2_lib.baseboard_fab2(sch_1):page188_i27:io59" )
			)
			( pin "J8E4.60"
				( objectStatus "@baseboard_fab2_lib.baseboard_fab2(sch_1):page188_i27:io60" )
			)
			( pin "J8E4.61"
				( objectStatus "@baseboard_fab2_lib.baseboard_fab2(sch_1):page188_i27:io61" )
			)
			( pin "J8E4.62"
				( objectStatus "@baseboard_fab2_lib.baseboard_fab2(sch_1):page188_i27:io62" )
			)
			( pin "J8E4.63"
				( objectStatus "@baseboard_fab2_lib.baseboard_fab2(sch_1):page188_i27:io63" )
			)
			( pin "J8E4.64"
				( objectStatus "@baseboard_fab2_lib.baseboard_fab2(sch_1):page188_i27:io64" )
			)
			( pin "C2R16.1"
				( objectStatus "@baseboard_fab2_lib.baseboard_fab2(sch_1):page188_i40:a" )
			)
			( pin "C2R16.2"
				( objectStatus "@baseboard_fab2_lib.baseboard_fab2(sch_1):page188_i40:b" )
			)
			( pin "C2P10.1"
				( objectStatus "@baseboard_fab2_lib.baseboard_fab2(sch_1):page188_i41:a" )
			)
			( pin "C2P10.2"
				( objectStatus "@baseboard_fab2_lib.baseboard_fab2(sch_1):page188_i41:b" )
			)
			( pin "C2P16.1"
				( objectStatus "@baseboard_fab2_lib.baseboard_fab2(sch_1):page188_i53:a" )
			)
			( pin "C2P16.2"
				( objectStatus "@baseboard_fab2_lib.baseboard_fab2(sch_1):page188_i53:b" )
			)
			( pin "C2P15.1"
				( objectStatus "@baseboard_fab2_lib.baseboard_fab2(sch_1):page188_i55:a" )
			)
			( pin "C2P15.2"
				( objectStatus "@baseboard_fab2_lib.baseboard_fab2(sch_1):page188_i55:b" )
			)
			( pin "C2P14.1"
				( objectStatus "@baseboard_fab2_lib.baseboard_fab2(sch_1):page188_i56:a" )
			)
			( pin "C2P14.2"
				( objectStatus "@baseboard_fab2_lib.baseboard_fab2(sch_1):page188_i56:b" )
			)
			( pin "C2P13.1"
				( objectStatus "@baseboard_fab2_lib.baseboard_fab2(sch_1):page188_i57:a" )
			)
			( pin "C2P13.2"
				( objectStatus "@baseboard_fab2_lib.baseboard_fab2(sch_1):page188_i57:b" )
			)
			( pin "C8C8.1"
				( objectStatus "@baseboard_fab2_lib.baseboard_fab2(sch_1):page188_i64:a" )
			)
			( pin "C8C8.2"
				( objectStatus "@baseboard_fab2_lib.baseboard_fab2(sch_1):page188_i64:b" )
			)
			( pin "C8C9.1"
				( objectStatus "@baseboard_fab2_lib.baseboard_fab2(sch_1):page188_i68:a" )
			)
			( pin "C8C9.2"
				( objectStatus "@baseboard_fab2_lib.baseboard_fab2(sch_1):page188_i68:b" )
			)
			( pin "C8C11.1"
				( objectStatus "@baseboard_fab2_lib.baseboard_fab2(sch_1):page188_i72:a" )
			)
			( pin "C8C11.2"
				( objectStatus "@baseboard_fab2_lib.baseboard_fab2(sch_1):page188_i72:b" )
			)
			( pin "C8C10.1"
				( objectStatus "@baseboard_fab2_lib.baseboard_fab2(sch_1):page188_i73:a" )
			)
			( pin "C8C10.2"
				( objectStatus "@baseboard_fab2_lib.baseboard_fab2(sch_1):page188_i73:b" )
			)
			( pin "C8C12.1"
				( objectStatus "@baseboard_fab2_lib.baseboard_fab2(sch_1):page188_i80:a" )
			)
			( pin "C8C12.2"
				( objectStatus "@baseboard_fab2_lib.baseboard_fab2(sch_1):page188_i80:b" )
			)
			( pin "C8C13.1"
				( objectStatus "@baseboard_fab2_lib.baseboard_fab2(sch_1):page188_i81:a" )
			)
			( pin "C8C13.2"
				( objectStatus "@baseboard_fab2_lib.baseboard_fab2(sch_1):page188_i81:b" )
			)
			( pin "C8C15.1"
				( objectStatus "@baseboard_fab2_lib.baseboard_fab2(sch_1):page188_i82:a" )
			)
			( pin "C8C15.2"
				( objectStatus "@baseboard_fab2_lib.baseboard_fab2(sch_1):page188_i82:b" )
			)
			( pin "C8C14.1"
				( objectStatus "@baseboard_fab2_lib.baseboard_fab2(sch_1):page188_i86:a" )
			)
			( pin "C8C14.2"
				( objectStatus "@baseboard_fab2_lib.baseboard_fab2(sch_1):page188_i86:b" )
			)
			( pin "R1R18.1"
				( objectStatus "@baseboard_fab2_lib.baseboard_fab2(sch_1):page188_i88:a" )
			)
			( pin "R1R18.2"
				( objectStatus "@baseboard_fab2_lib.baseboard_fab2(sch_1):page188_i88:b" )
			)
			( pin "R1R19.1"
				( objectStatus "@baseboard_fab2_lib.baseboard_fab2(sch_1):page188_i89:a" )
			)
			( pin "R1R19.2"
				( objectStatus "@baseboard_fab2_lib.baseboard_fab2(sch_1):page188_i89:b" )
			)
			( pin "R1R21.1"
				( objectStatus "@baseboard_fab2_lib.baseboard_fab2(sch_1):page188_i90:a" )
			)
			( pin "R1R21.2"
				( objectStatus "@baseboard_fab2_lib.baseboard_fab2(sch_1):page188_i90:b" )
			)
			( pin "R1R20.1"
				( objectStatus "@baseboard_fab2_lib.baseboard_fab2(sch_1):page188_i91:a" )
			)
			( pin "R1R20.2"
				( objectStatus "@baseboard_fab2_lib.baseboard_fab2(sch_1):page188_i91:b" )
			)
			( pin "R1R22.1"
				( objectStatus "@baseboard_fab2_lib.baseboard_fab2(sch_1):page188_i92:a" )
			)
			( pin "R1R22.2"
				( objectStatus "@baseboard_fab2_lib.baseboard_fab2(sch_1):page188_i92:b" )
			)
			( pin "R1R16.1"
				( objectStatus "@baseboard_fab2_lib.baseboard_fab2(sch_1):page188_i93:a" )
			)
			( pin "R1R16.2"
				( objectStatus "@baseboard_fab2_lib.baseboard_fab2(sch_1):page188_i93:b" )
			)
			( pin "R1R17.1"
				( objectStatus "@baseboard_fab2_lib.baseboard_fab2(sch_1):page188_i94:a" )
			)
			( pin "R1R17.2"
				( objectStatus "@baseboard_fab2_lib.baseboard_fab2(sch_1):page188_i94:b" )
			)
			( pin "R1R23.1"
				( objectStatus "@baseboard_fab2_lib.baseboard_fab2(sch_1):page188_i95:a" )
			)
			( pin "R1R23.2"
				( objectStatus "@baseboard_fab2_lib.baseboard_fab2(sch_1):page188_i95:b" )
			)
			( pin "R8G10.1"
				( objectStatus "@baseboard_fab2_lib.baseboard_fab2(sch_1):page189_i7:a" )
			)
			( pin "R8G10.2"
				( objectStatus "@baseboard_fab2_lib.baseboard_fab2(sch_1):page189_i7:b" )
			)
			( pin "R7G19.1"
				( objectStatus "@baseboard_fab2_lib.baseboard_fab2(sch_1):page189_i8:a" )
			)
			( pin "R7G19.2"
				( objectStatus "@baseboard_fab2_lib.baseboard_fab2(sch_1):page189_i8:b" )
			)
			( pin "R8G9.1"
				( objectStatus "@baseboard_fab2_lib.baseboard_fab2(sch_1):page189_i9:a" )
			)
			( pin "R8G9.2"
				( objectStatus "@baseboard_fab2_lib.baseboard_fab2(sch_1):page189_i9:b" )
			)
			( pin "R7G18.1"
				( objectStatus "@baseboard_fab2_lib.baseboard_fab2(sch_1):page189_i13:a" )
			)
			( pin "R7G18.2"
				( objectStatus "@baseboard_fab2_lib.baseboard_fab2(sch_1):page189_i13:b" )
			)
			( pin "R8G8.1"
				( objectStatus "@baseboard_fab2_lib.baseboard_fab2(sch_1):page189_i17:a" )
			)
			( pin "R8G8.2"
				( objectStatus "@baseboard_fab2_lib.baseboard_fab2(sch_1):page189_i17:b" )
			)
			( pin "R8G7.1"
				( objectStatus "@baseboard_fab2_lib.baseboard_fab2(sch_1):page189_i18:a" )
			)
			( pin "R8G7.2"
				( objectStatus "@baseboard_fab2_lib.baseboard_fab2(sch_1):page189_i18:b" )
			)
			( pin "R8G11.1"
				( objectStatus "@baseboard_fab2_lib.baseboard_fab2(sch_1):page189_i19:a" )
			)
			( pin "R8G11.2"
				( objectStatus "@baseboard_fab2_lib.baseboard_fab2(sch_1):page189_i19:b" )
			)
			( pin "R8G14.1"
				( objectStatus "@baseboard_fab2_lib.baseboard_fab2(sch_1):page189_i20:a" )
			)
			( pin "R8G14.2"
				( objectStatus "@baseboard_fab2_lib.baseboard_fab2(sch_1):page189_i20:b" )
			)
			( pin "R8G12.1"
				( objectStatus "@baseboard_fab2_lib.baseboard_fab2(sch_1):page189_i21:a" )
			)
			( pin "R8G12.2"
				( objectStatus "@baseboard_fab2_lib.baseboard_fab2(sch_1):page189_i21:b" )
			)
			( pin "R8G16.1"
				( objectStatus "@baseboard_fab2_lib.baseboard_fab2(sch_1):page189_i22:a" )
			)
			( pin "R8G16.2"
				( objectStatus "@baseboard_fab2_lib.baseboard_fab2(sch_1):page189_i22:b" )
			)
			( pin "R8G13.1"
				( objectStatus "@baseboard_fab2_lib.baseboard_fab2(sch_1):page189_i23:a" )
			)
			( pin "R8G13.2"
				( objectStatus "@baseboard_fab2_lib.baseboard_fab2(sch_1):page189_i23:b" )
			)
			( pin "R8G15.1"
				( objectStatus "@baseboard_fab2_lib.baseboard_fab2(sch_1):page189_i24:a" )
			)
			( pin "R8G15.2"
				( objectStatus "@baseboard_fab2_lib.baseboard_fab2(sch_1):page189_i24:b" )
			)
			( pin "R8G17.1"
				( objectStatus "@baseboard_fab2_lib.baseboard_fab2(sch_1):page189_i25:a" )
			)
			( pin "R8G17.2"
				( objectStatus "@baseboard_fab2_lib.baseboard_fab2(sch_1):page189_i25:b" )
			)
			( pin "R8G18.1"
				( objectStatus "@baseboard_fab2_lib.baseboard_fab2(sch_1):page189_i26:a" )
			)
			( pin "R8G18.2"
				( objectStatus "@baseboard_fab2_lib.baseboard_fab2(sch_1):page189_i26:b" )
			)
			( pin "R7G16.1"
				( objectStatus "@baseboard_fab2_lib.baseboard_fab2(sch_1):page189_i27:a" )
			)
			( pin "R7G16.2"
				( objectStatus "@baseboard_fab2_lib.baseboard_fab2(sch_1):page189_i27:b" )
			)
			( pin "R7G15.1"
				( objectStatus "@baseboard_fab2_lib.baseboard_fab2(sch_1):page189_i36:a" )
			)
			( pin "R7G15.2"
				( objectStatus "@baseboard_fab2_lib.baseboard_fab2(sch_1):page189_i36:b" )
			)
			( pin "R7G17.1"
				( objectStatus "@baseboard_fab2_lib.baseboard_fab2(sch_1):page189_i37:a" )
			)
			( pin "R7G17.2"
				( objectStatus "@baseboard_fab2_lib.baseboard_fab2(sch_1):page189_i37:b" )
			)
			( pin "R7G14.1"
				( objectStatus "@baseboard_fab2_lib.baseboard_fab2(sch_1):page189_i38:a" )
			)
			( pin "R7G14.2"
				( objectStatus "@baseboard_fab2_lib.baseboard_fab2(sch_1):page189_i38:b" )
			)
			( pin "R3R15.1"
				( objectStatus "@baseboard_fab2_lib.baseboard_fab2(sch_1):page189_i44:a" )
			)
			( pin "R3R15.2"
				( objectStatus "@baseboard_fab2_lib.baseboard_fab2(sch_1):page189_i44:b" )
			)
			( pin "R3R11.1"
				( objectStatus "@baseboard_fab2_lib.baseboard_fab2(sch_1):page189_i45:a" )
			)
			( pin "R3R11.2"
				( objectStatus "@baseboard_fab2_lib.baseboard_fab2(sch_1):page189_i45:b" )
			)
			( pin "J7G2.1"
				( objectStatus "@baseboard_fab2_lib.baseboard_fab2(sch_1):page189_i47:io1" )
			)
			( pin "J7G2.2"
				( objectStatus "@baseboard_fab2_lib.baseboard_fab2(sch_1):page189_i47:io2" )
			)
			( pin "J7G2.3"
				( objectStatus "@baseboard_fab2_lib.baseboard_fab2(sch_1):page189_i47:io3" )
			)
			( pin "J7G2.4"
				( objectStatus "@baseboard_fab2_lib.baseboard_fab2(sch_1):page189_i47:io4" )
			)
			( pin "J7G2.5"
				( objectStatus "@baseboard_fab2_lib.baseboard_fab2(sch_1):page189_i47:io5" )
			)
			( pin "J7G2.6"
				( objectStatus "@baseboard_fab2_lib.baseboard_fab2(sch_1):page189_i47:io6" )
			)
			( pin "J7G2.7"
				( objectStatus "@baseboard_fab2_lib.baseboard_fab2(sch_1):page189_i47:io7" )
			)
			( pin "J7G2.8"
				( objectStatus "@baseboard_fab2_lib.baseboard_fab2(sch_1):page189_i47:io8" )
			)
			( pin "CR3U1.2"
				( objectStatus "@baseboard_fab2_lib.baseboard_fab2(sch_1):page189_i49:a" )
			)
			( pin "CR3U1.1"
				( objectStatus "@baseboard_fab2_lib.baseboard_fab2(sch_1):page189_i49:c" )
			)
			( pin "R8G20.1"
				( objectStatus "@baseboard_fab2_lib.baseboard_fab2(sch_1):page189_i50:a" )
			)
			( pin "R8G20.2"
				( objectStatus "@baseboard_fab2_lib.baseboard_fab2(sch_1):page189_i50:b" )
			)
			( pin "R7G23.1"
				( objectStatus "@baseboard_fab2_lib.baseboard_fab2(sch_1):page189_i51:a" )
			)
			( pin "R7G23.2"
				( objectStatus "@baseboard_fab2_lib.baseboard_fab2(sch_1):page189_i51:b" )
			)
			( pin "R7G22.1"
				( objectStatus "@baseboard_fab2_lib.baseboard_fab2(sch_1):page189_i53:a" )
			)
			( pin "R7G22.2"
				( objectStatus "@baseboard_fab2_lib.baseboard_fab2(sch_1):page189_i53:b" )
			)
			( pin "R8G23.1"
				( objectStatus "@baseboard_fab2_lib.baseboard_fab2(sch_1):page189_i56:a" )
			)
			( pin "R8G23.2"
				( objectStatus "@baseboard_fab2_lib.baseboard_fab2(sch_1):page189_i56:b" )
			)
			( pin "R7G21.1"
				( objectStatus "@baseboard_fab2_lib.baseboard_fab2(sch_1):page189_i63:a" )
			)
			( pin "R7G21.2"
				( objectStatus "@baseboard_fab2_lib.baseboard_fab2(sch_1):page189_i63:b" )
			)
			( pin "R8G19.1"
				( objectStatus "@baseboard_fab2_lib.baseboard_fab2(sch_1):page189_i64:a" )
			)
			( pin "R8G19.2"
				( objectStatus "@baseboard_fab2_lib.baseboard_fab2(sch_1):page189_i64:b" )
			)
			( pin "R8G21.1"
				( objectStatus "@baseboard_fab2_lib.baseboard_fab2(sch_1):page189_i65:a" )
			)
			( pin "R8G21.2"
				( objectStatus "@baseboard_fab2_lib.baseboard_fab2(sch_1):page189_i65:b" )
			)
			( pin "R8G22.1"
				( objectStatus "@baseboard_fab2_lib.baseboard_fab2(sch_1):page189_i66:a" )
			)
			( pin "R8G22.2"
				( objectStatus "@baseboard_fab2_lib.baseboard_fab2(sch_1):page189_i66:b" )
			)
			( pin "R3P34.1"
				( objectStatus "@baseboard_fab2_lib.baseboard_fab2(sch_1):page190_i116:a" )
			)
			( pin "R3P34.2"
				( objectStatus "@baseboard_fab2_lib.baseboard_fab2(sch_1):page190_i116:b" )
			)
			( pin "R3P35.1"
				( objectStatus "@baseboard_fab2_lib.baseboard_fab2(sch_1):page190_i117:a" )
			)
			( pin "R3P35.2"
				( objectStatus "@baseboard_fab2_lib.baseboard_fab2(sch_1):page190_i117:b" )
			)
			( pin "U8D7.P4"
				( objectStatus "@baseboard_fab2_lib.baseboard_fab2(sch_1):page190_i179:pb3a" )
			)
			( pin "U8D7.T4"
				( objectStatus "@baseboard_fab2_lib.baseboard_fab2(sch_1):page190_i179:pb3b" )
			)
			( pin "U8D7.T2"
				( objectStatus "@baseboard_fab2_lib.baseboard_fab2(sch_1):page190_i179:pb3c" )
			)
			( pin "U8D7.R3"
				( objectStatus "@baseboard_fab2_lib.baseboard_fab2(sch_1):page190_i179:pb3d" )
			)
			( pin "U8D7.R5"
				( objectStatus "@baseboard_fab2_lib.baseboard_fab2(sch_1):page190_i179:pb5a_csspin" )
			)
			( pin "U8D7.P5"
				( objectStatus "@baseboard_fab2_lib.baseboard_fab2(sch_1):page190_i179:pb5b" )
			)
			( pin "U8D7.T5"
				( objectStatus "@baseboard_fab2_lib.baseboard_fab2(sch_1):page190_i179:pb6a" )
			)
			( pin "U8D7.R6"
				( objectStatus "@baseboard_fab2_lib.baseboard_fab2(sch_1):page190_i179:pb6b" )
			)
			( pin "U8D7.T3"
				( objectStatus "@baseboard_fab2_lib.baseboard_fab2(sch_1):page190_i179:pb6c" )
			)
			( pin "U8D7.R4"
				( objectStatus "@baseboard_fab2_lib.baseboard_fab2(sch_1):page190_i179:pb6d" )
			)
			( pin "U8D7.P6"
				( objectStatus "@baseboard_fab2_lib.baseboard_fab2(sch_1):page190_i179:pb8a_mclk_cclk" )
			)
			( pin "U8D7.T6"
				( objectStatus "@baseboard_fab2_lib.baseboard_fab2(sch_1):page190_i179:pb8b_so_spiso" )
			)
			( pin "U8D7.N6"
				( objectStatus "@baseboard_fab2_lib.baseboard_fab2(sch_1):page190_i179:pb8c" )
			)
			( pin "U8D7.L7"
				( objectStatus "@baseboard_fab2_lib.baseboard_fab2(sch_1):page190_i179:pb8d" )
			)
			( pin "U8D7.R7"
				( objectStatus "@baseboard_fab2_lib.baseboard_fab2(sch_1):page190_i179:pb9a" )
			)
			( pin "U8D7.P7"
				( objectStatus "@baseboard_fab2_lib.baseboard_fab2(sch_1):page190_i179:pb9b" )
			)
			( pin "U8D7.M7"
				( objectStatus "@baseboard_fab2_lib.baseboard_fab2(sch_1):page190_i179:pb9c" )
			)
			( pin "U8D7.N7"
				( objectStatus "@baseboard_fab2_lib.baseboard_fab2(sch_1):page190_i179:pb9d" )
			)
			( pin "U8D7.T7"
				( objectStatus "@baseboard_fab2_lib.baseboard_fab2(sch_1):page190_i179:pb11a_pclkt2_0" )
			)
			( pin "U8D7.R8"
				( objectStatus "@baseboard_fab2_lib.baseboard_fab2(sch_1):page190_i179:pb11b_pclkc2_0" )
			)
			( pin "U8D7.M6"
				( objectStatus "@baseboard_fab2_lib.baseboard_fab2(sch_1):page190_i179:pb11c" )
			)
			( pin "U8D7.L8"
				( objectStatus "@baseboard_fab2_lib.baseboard_fab2(sch_1):page190_i179:pb11d" )
			)
			( pin "U8D7.P8"
				( objectStatus "@baseboard_fab2_lib.baseboard_fab2(sch_1):page190_i179:pb12a" )
			)
			( pin "U8D7.T8"
				( objectStatus "@baseboard_fab2_lib.baseboard_fab2(sch_1):page190_i179:pb12b" )
			)
			( pin "U8D7.N8"
				( objectStatus "@baseboard_fab2_lib.baseboard_fab2(sch_1):page190_i179:pb12c" )
			)
			( pin "U8D7.L9"
				( objectStatus "@baseboard_fab2_lib.baseboard_fab2(sch_1):page190_i179:pb12d" )
			)
			( pin "U8D7.T9"
				( objectStatus "@baseboard_fab2_lib.baseboard_fab2(sch_1):page190_i179:pb16a_pclkt2_1" )
			)
			( pin "U8D7.P9"
				( objectStatus "@baseboard_fab2_lib.baseboard_fab2(sch_1):page190_i179:pb16b_pclkc2_1" )
			)
			( pin "U8D7.M8"
				( objectStatus "@baseboard_fab2_lib.baseboard_fab2(sch_1):page190_i179:pb16c" )
			)
			( pin "U8D7.N9"
				( objectStatus "@baseboard_fab2_lib.baseboard_fab2(sch_1):page190_i179:pb16d" )
			)
			( pin "U8D7.R9"
				( objectStatus "@baseboard_fab2_lib.baseboard_fab2(sch_1):page190_i179:pb18a" )
			)
			( pin "U8D7.T10"
				( objectStatus "@baseboard_fab2_lib.baseboard_fab2(sch_1):page190_i179:pb18b" )
			)
			( pin "U8D7.M9"
				( objectStatus "@baseboard_fab2_lib.baseboard_fab2(sch_1):page190_i179:pb18c" )
			)
			( pin "U8D7.L10"
				( objectStatus "@baseboard_fab2_lib.baseboard_fab2(sch_1):page190_i179:pb18d" )
			)
			( pin "U8D7.P10"
				( objectStatus "@baseboard_fab2_lib.baseboard_fab2(sch_1):page190_i179:pb19a" )
			)
			( pin "U8D7.R10"
				( objectStatus "@baseboard_fab2_lib.baseboard_fab2(sch_1):page190_i179:pb19b" )
			)
			( pin "U8D7.N10"
				( objectStatus "@baseboard_fab2_lib.baseboard_fab2(sch_1):page190_i179:pb19c" )
			)
			( pin "U8D7.M11"
				( objectStatus "@baseboard_fab2_lib.baseboard_fab2(sch_1):page190_i179:pb19d" )
			)
			( pin "U8D7.T11"
				( objectStatus "@baseboard_fab2_lib.baseboard_fab2(sch_1):page190_i179:pb21a" )
			)
			( pin "U8D7.P11"
				( objectStatus "@baseboard_fab2_lib.baseboard_fab2(sch_1):page190_i179:pb21b" )
			)
			( pin "U8D7.M10"
				( objectStatus "@baseboard_fab2_lib.baseboard_fab2(sch_1):page190_i179:pb21c" )
			)
			( pin "U8D7.N11"
				( objectStatus "@baseboard_fab2_lib.baseboard_fab2(sch_1):page190_i179:pb21d" )
			)
			( pin "U8D7.R11"
				( objectStatus "@baseboard_fab2_lib.baseboard_fab2(sch_1):page190_i179:pb22a" )
			)
			( pin "U8D7.T12"
				( objectStatus "@baseboard_fab2_lib.baseboard_fab2(sch_1):page190_i179:pb22b" )
			)
			( pin "U8D7.R13"
				( objectStatus "@baseboard_fab2_lib.baseboard_fab2(sch_1):page190_i179:pb22c" )
			)
			( pin "U8D7.T14"
				( objectStatus "@baseboard_fab2_lib.baseboard_fab2(sch_1):page190_i179:pb22d" )
			)
			( pin "U8D7.P12"
				( objectStatus "@baseboard_fab2_lib.baseboard_fab2(sch_1):page190_i179:pb24a" )
			)
			( pin "U8D7.T13"
				( objectStatus "@baseboard_fab2_lib.baseboard_fab2(sch_1):page190_i179:pb24b" )
			)
			( pin "U8D7.R12"
				( objectStatus "@baseboard_fab2_lib.baseboard_fab2(sch_1):page190_i179:pb25a_sn" )
			)
			( pin "U8D7.P13"
				( objectStatus "@baseboard_fab2_lib.baseboard_fab2(sch_1):page190_i179:pb25b_si_sispi" )
			)
			( pin "U8D7.T15"
				( objectStatus "@baseboard_fab2_lib.baseboard_fab2(sch_1):page190_i179:pb25c" )
			)
			( pin "U8D7.R14"
				( objectStatus "@baseboard_fab2_lib.baseboard_fab2(sch_1):page190_i179:pb25d" )
			)
			( pin "U8D7.D3"
				( objectStatus "@baseboard_fab2_lib.baseboard_fab2(sch_1):page190_i179:pl1a_l_gpllt_fb" )
			)
			( pin "U8D7.D1"
				( objectStatus "@baseboard_fab2_lib.baseboard_fab2(sch_1):page190_i179:pl1b_l_gpllc_fb" )
			)
			( pin "U8D7.B1"
				( objectStatus "@baseboard_fab2_lib.baseboard_fab2(sch_1):page190_i179:pl1c" )
			)
			( pin "U8D7.C2"
				( objectStatus "@baseboard_fab2_lib.baseboard_fab2(sch_1):page190_i179:pl1d" )
			)
			( pin "U8D7.E2"
				( objectStatus "@baseboard_fab2_lib.baseboard_fab2(sch_1):page190_i179:pl2a_l_gpllt_in" )
			)
			( pin "U8D7.E3"
				( objectStatus "@baseboard_fab2_lib.baseboard_fab2(sch_1):page190_i179:pl2b_l_gpllc_in" )
			)
			( pin "U8D7.C1"
				( objectStatus "@baseboard_fab2_lib.baseboard_fab2(sch_1):page190_i179:pl2c" )
			)
			( pin "U8D7.D2"
				( objectStatus "@baseboard_fab2_lib.baseboard_fab2(sch_1):page190_i179:pl2d" )
			)
			( pin "U8D7.E1"
				( objectStatus "@baseboard_fab2_lib.baseboard_fab2(sch_1):page190_i179:pl3a_pclkt5_0" )
			)
			( pin "U8D7.F2"
				( objectStatus "@baseboard_fab2_lib.baseboard_fab2(sch_1):page190_i179:pl3b_pclkc5_0" )
			)
			( pin "U8D7.F4"
				( objectStatus "@baseboard_fab2_lib.baseboard_fab2(sch_1):page190_i179:pl3c" )
			)
			( pin "U8D7.G6"
				( objectStatus "@baseboard_fab2_lib.baseboard_fab2(sch_1):page190_i179:pl3d" )
			)
			( pin "U8D7.F3"
				( objectStatus "@baseboard_fab2_lib.baseboard_fab2(sch_1):page190_i179:pl4a" )
			)
			( pin "U8D7.F1"
				( objectStatus "@baseboard_fab2_lib.baseboard_fab2(sch_1):page190_i179:pl4b" )
			)
			( pin "U8D7.G5"
				( objectStatus "@baseboard_fab2_lib.baseboard_fab2(sch_1):page190_i179:pl4c" )
			)
			( pin "U8D7.G4"
				( objectStatus "@baseboard_fab2_lib.baseboard_fab2(sch_1):page190_i179:pl4d" )
			)
			( pin "U8D7.G2"
				( objectStatus "@baseboard_fab2_lib.baseboard_fab2(sch_1):page190_i179:pl5a" )
			)
			( pin "U8D7.G3"
				( objectStatus "@baseboard_fab2_lib.baseboard_fab2(sch_1):page190_i179:pl5b" )
			)
			( pin "U8D7.F5"
				( objectStatus "@baseboard_fab2_lib.baseboard_fab2(sch_1):page190_i179:pl5c" )
			)
			( pin "U8D7.H6"
				( objectStatus "@baseboard_fab2_lib.baseboard_fab2(sch_1):page190_i179:pl5d" )
			)
			( pin "U8D7.G1"
				( objectStatus "@baseboard_fab2_lib.baseboard_fab2(sch_1):page190_i179:pl6a" )
			)
			( pin "U8D7.H2"
				( objectStatus "@baseboard_fab2_lib.baseboard_fab2(sch_1):page190_i179:pl6b" )
			)
			( pin "U8D7.H4"
				( objectStatus "@baseboard_fab2_lib.baseboard_fab2(sch_1):page190_i179:pl6c" )
			)
			( pin "U8D7.J6"
				( objectStatus "@baseboard_fab2_lib.baseboard_fab2(sch_1):page190_i179:pl6d" )
			)
			( pin "U8D7.H3"
				( objectStatus "@baseboard_fab2_lib.baseboard_fab2(sch_1):page190_i179:pl7a" )
			)
			( pin "U8D7.H1"
				( objectStatus "@baseboard_fab2_lib.baseboard_fab2(sch_1):page190_i179:pl7b" )
			)
			( pin "U8D7.J1"
				( objectStatus "@baseboard_fab2_lib.baseboard_fab2(sch_1):page190_i179:pl7c_pclkt4_0" )
			)
			( pin "U8D7.J3"
				( objectStatus "@baseboard_fab2_lib.baseboard_fab2(sch_1):page190_i179:pl7d_pclkc4_0" )
			)
			( pin "U8D7.J2"
				( objectStatus "@baseboard_fab2_lib.baseboard_fab2(sch_1):page190_i179:pl9a" )
			)
			( pin "U8D7.K1"
				( objectStatus "@baseboard_fab2_lib.baseboard_fab2(sch_1):page190_i179:pl9b" )
			)
			( pin "U8D7.H5"
				( objectStatus "@baseboard_fab2_lib.baseboard_fab2(sch_1):page190_i179:pl9c" )
			)
			( pin "U8D7.J4"
				( objectStatus "@baseboard_fab2_lib.baseboard_fab2(sch_1):page190_i179:pl9d" )
			)
			( pin "U8D7.K3"
				( objectStatus "@baseboard_fab2_lib.baseboard_fab2(sch_1):page190_i179:pl10a" )
			)
			( pin "U8D7.K2"
				( objectStatus "@baseboard_fab2_lib.baseboard_fab2(sch_1):page190_i179:pl10b" )
			)
			( pin "U8D7.J5"
				( objectStatus "@baseboard_fab2_lib.baseboard_fab2(sch_1):page190_i179:pl10c" )
			)
			( pin "U8D7.K6"
				( objectStatus "@baseboard_fab2_lib.baseboard_fab2(sch_1):page190_i179:pl10d" )
			)
			( pin "U8D7.L1"
				( objectStatus "@baseboard_fab2_lib.baseboard_fab2(sch_1):page190_i179:pl11a" )
			)
			( pin "U8D7.L3"
				( objectStatus "@baseboard_fab2_lib.baseboard_fab2(sch_1):page190_i179:pl11b" )
			)
			( pin "U8D7.K4"
				( objectStatus "@baseboard_fab2_lib.baseboard_fab2(sch_1):page190_i179:pl11c" )
			)
			( pin "U8D7.L5"
				( objectStatus "@baseboard_fab2_lib.baseboard_fab2(sch_1):page190_i179:pl11d" )
			)
			( pin "U8D7.L2"
				( objectStatus "@baseboard_fab2_lib.baseboard_fab2(sch_1):page190_i179:pl12a_pclkt3_0" )
			)
			( pin "U8D7.M1"
				( objectStatus "@baseboard_fab2_lib.baseboard_fab2(sch_1):page190_i179:pl12b_pclkc3_0" )
			)
			( pin "U8D7.K5"
				( objectStatus "@baseboard_fab2_lib.baseboard_fab2(sch_1):page190_i179:pl12c" )
			)
			( pin "U8D7.L4"
				( objectStatus "@baseboard_fab2_lib.baseboard_fab2(sch_1):page190_i179:pl12d" )
			)
			( pin "U8D7.M3"
				( objectStatus "@baseboard_fab2_lib.baseboard_fab2(sch_1):page190_i179:pl13a" )
			)
			( pin "U8D7.N1"
				( objectStatus "@baseboard_fab2_lib.baseboard_fab2(sch_1):page190_i179:pl13b" )
			)
			( pin "U8D7.N2"
				( objectStatus "@baseboard_fab2_lib.baseboard_fab2(sch_1):page190_i179:pl13c" )
			)
			( pin "U8D7.P1"
				( objectStatus "@baseboard_fab2_lib.baseboard_fab2(sch_1):page190_i179:pl13d" )
			)
			( pin "U8D7.M2"
				( objectStatus "@baseboard_fab2_lib.baseboard_fab2(sch_1):page190_i179:pl14a" )
			)
			( pin "U8D7.N3"
				( objectStatus "@baseboard_fab2_lib.baseboard_fab2(sch_1):page190_i179:pl14b" )
			)
			( pin "U8D7.R1"
				( objectStatus "@baseboard_fab2_lib.baseboard_fab2(sch_1):page190_i179:pl14c" )
			)
			( pin "U8D7.P2"
				( objectStatus "@baseboard_fab2_lib.baseboard_fab2(sch_1):page190_i179:pl14d" )
			)
			( pin "R2R2.1"
				( objectStatus "@baseboard_fab2_lib.baseboard_fab2(sch_1):page190_i338:a" )
			)
			( pin "R2R2.2"
				( objectStatus "@baseboard_fab2_lib.baseboard_fab2(sch_1):page190_i338:b" )
			)
			( pin "U8D7.D14"
				( objectStatus "@baseboard_fab2_lib.baseboard_fab2(sch_1):page191_i59:pr1a" )
			)
			( pin "U8D7.E15"
				( objectStatus "@baseboard_fab2_lib.baseboard_fab2(sch_1):page191_i59:pr1b" )
			)
			( pin "U8D7.C15"
				( objectStatus "@baseboard_fab2_lib.baseboard_fab2(sch_1):page191_i59:pr1c" )
			)
			( pin "U8D7.B16"
				( objectStatus "@baseboard_fab2_lib.baseboard_fab2(sch_1):page191_i59:pr1d" )
			)
			( pin "U8D7.D16"
				( objectStatus "@baseboard_fab2_lib.baseboard_fab2(sch_1):page191_i59:pr2a" )
			)
			( pin "U8D7.E14"
				( objectStatus "@baseboard_fab2_lib.baseboard_fab2(sch_1):page191_i59:pr2b" )
			)
			( pin "U8D7.C16"
				( objectStatus "@baseboard_fab2_lib.baseboard_fab2(sch_1):page191_i59:pr2c" )
			)
			( pin "U8D7.D15"
				( objectStatus "@baseboard_fab2_lib.baseboard_fab2(sch_1):page191_i59:pr2d" )
			)
			( pin "U8D7.E16"
				( objectStatus "@baseboard_fab2_lib.baseboard_fab2(sch_1):page191_i59:pr3a" )
			)
			( pin "U8D7.F15"
				( objectStatus "@baseboard_fab2_lib.baseboard_fab2(sch_1):page191_i59:pr3b" )
			)
			( pin "U8D7.F13"
				( objectStatus "@baseboard_fab2_lib.baseboard_fab2(sch_1):page191_i59:pr3c" )
			)
			( pin "U8D7.G12"
				( objectStatus "@baseboard_fab2_lib.baseboard_fab2(sch_1):page191_i59:pr3d" )
			)
			( pin "U8D7.F14"
				( objectStatus "@baseboard_fab2_lib.baseboard_fab2(sch_1):page191_i59:pr4a" )
			)
			( pin "U8D7.F16"
				( objectStatus "@baseboard_fab2_lib.baseboard_fab2(sch_1):page191_i59:pr4b" )
			)
			( pin "U8D7.F12"
				( objectStatus "@baseboard_fab2_lib.baseboard_fab2(sch_1):page191_i59:pr4c" )
			)
			( pin "U8D7.G13"
				( objectStatus "@baseboard_fab2_lib.baseboard_fab2(sch_1):page191_i59:pr4d" )
			)
			( pin "U8D7.G15"
				( objectStatus "@baseboard_fab2_lib.baseboard_fab2(sch_1):page191_i59:pr5a" )
			)
			( pin "U8D7.G14"
				( objectStatus "@baseboard_fab2_lib.baseboard_fab2(sch_1):page191_i59:pr5b" )
			)
			( pin "U8D7.G11"
				( objectStatus "@baseboard_fab2_lib.baseboard_fab2(sch_1):page191_i59:pr5c" )
			)
			( pin "U8D7.H12"
				( objectStatus "@baseboard_fab2_lib.baseboard_fab2(sch_1):page191_i59:pr5d" )
			)
			( pin "U8D7.G16"
				( objectStatus "@baseboard_fab2_lib.baseboard_fab2(sch_1):page191_i59:pr6a" )
			)
			( pin "U8D7.H15"
				( objectStatus "@baseboard_fab2_lib.baseboard_fab2(sch_1):page191_i59:pr6b" )
			)
			( pin "U8D7.H13"
				( objectStatus "@baseboard_fab2_lib.baseboard_fab2(sch_1):page191_i59:pr6c" )
			)
			( pin "U8D7.J12"
				( objectStatus "@baseboard_fab2_lib.baseboard_fab2(sch_1):page191_i59:pr6d" )
			)
			( pin "U8D7.H14"
				( objectStatus "@baseboard_fab2_lib.baseboard_fab2(sch_1):page191_i59:pr7a_pclkt1_0" )
			)
			( pin "U8D7.H16"
				( objectStatus "@baseboard_fab2_lib.baseboard_fab2(sch_1):page191_i59:pr7b_pclkc1_0" )
			)
			( pin "U8D7.J16"
				( objectStatus "@baseboard_fab2_lib.baseboard_fab2(sch_1):page191_i59:pr7c" )
			)
			( pin "U8D7.J14"
				( objectStatus "@baseboard_fab2_lib.baseboard_fab2(sch_1):page191_i59:pr7d" )
			)
			( pin "U8D7.J15"
				( objectStatus "@baseboard_fab2_lib.baseboard_fab2(sch_1):page191_i59:pr9a" )
			)
			( pin "U8D7.K16"
				( objectStatus "@baseboard_fab2_lib.baseboard_fab2(sch_1):page191_i59:pr9b" )
			)
			( pin "U8D7.H11"
				( objectStatus "@baseboard_fab2_lib.baseboard_fab2(sch_1):page191_i59:pr9c" )
			)
			( pin "U8D7.J13"
				( objectStatus "@baseboard_fab2_lib.baseboard_fab2(sch_1):page191_i59:pr9d" )
			)
			( pin "U8D7.K14"
				( objectStatus "@baseboard_fab2_lib.baseboard_fab2(sch_1):page191_i59:pr10a" )
			)
			( pin "U8D7.K15"
				( objectStatus "@baseboard_fab2_lib.baseboard_fab2(sch_1):page191_i59:pr10b" )
			)
			( pin "U8D7.J11"
				( objectStatus "@baseboard_fab2_lib.baseboard_fab2(sch_1):page191_i59:pr10c" )
			)
			( pin "U8D7.L12"
				( objectStatus "@baseboard_fab2_lib.baseboard_fab2(sch_1):page191_i59:pr10d" )
			)
			( pin "U8D7.L16"
				( objectStatus "@baseboard_fab2_lib.baseboard_fab2(sch_1):page191_i59:pr11a" )
			)
			( pin "U8D7.L14"
				( objectStatus "@baseboard_fab2_lib.baseboard_fab2(sch_1):page191_i59:pr11b" )
			)
			( pin "U8D7.K13"
				( objectStatus "@baseboard_fab2_lib.baseboard_fab2(sch_1):page191_i59:pr11c" )
			)
			( pin "U8D7.K12"
				( objectStatus "@baseboard_fab2_lib.baseboard_fab2(sch_1):page191_i59:pr11d" )
			)
			( pin "U8D7.L15"
				( objectStatus "@baseboard_fab2_lib.baseboard_fab2(sch_1):page191_i59:pr12a" )
			)
			( pin "U8D7.M16"
				( objectStatus "@baseboard_fab2_lib.baseboard_fab2(sch_1):page191_i59:pr12b" )
			)
			( pin "U8D7.K11"
				( objectStatus "@baseboard_fab2_lib.baseboard_fab2(sch_1):page191_i59:pr12c" )
			)
			( pin "U8D7.L13"
				( objectStatus "@baseboard_fab2_lib.baseboard_fab2(sch_1):page191_i59:pr12d" )
			)
			( pin "U8D7.M14"
				( objectStatus "@baseboard_fab2_lib.baseboard_fab2(sch_1):page191_i59:pr13a" )
			)
			( pin "U8D7.M15"
				( objectStatus "@baseboard_fab2_lib.baseboard_fab2(sch_1):page191_i59:pr13b" )
			)
			( pin "U8D7.N15"
				( objectStatus "@baseboard_fab2_lib.baseboard_fab2(sch_1):page191_i59:pr13c" )
			)
			( pin "U8D7.P16"
				( objectStatus "@baseboard_fab2_lib.baseboard_fab2(sch_1):page191_i59:pr13d" )
			)
			( pin "U8D7.N16"
				( objectStatus "@baseboard_fab2_lib.baseboard_fab2(sch_1):page191_i59:pr14a" )
			)
			( pin "U8D7.N14"
				( objectStatus "@baseboard_fab2_lib.baseboard_fab2(sch_1):page191_i59:pr14b" )
			)
			( pin "U8D7.P15"
				( objectStatus "@baseboard_fab2_lib.baseboard_fab2(sch_1):page191_i59:pr14c" )
			)
			( pin "U8D7.R16"
				( objectStatus "@baseboard_fab2_lib.baseboard_fab2(sch_1):page191_i59:pr14d" )
			)
			( pin "U8D7.C4"
				( objectStatus "@baseboard_fab2_lib.baseboard_fab2(sch_1):page191_i59:pt9a" )
			)
			( pin "U8D7.B5"
				( objectStatus "@baseboard_fab2_lib.baseboard_fab2(sch_1):page191_i59:pt9b" )
			)
			( pin "U8D7.B3"
				( objectStatus "@baseboard_fab2_lib.baseboard_fab2(sch_1):page191_i59:pt9c" )
			)
			( pin "U8D7.A4"
				( objectStatus "@baseboard_fab2_lib.baseboard_fab2(sch_1):page191_i59:pt10a" )
			)
			( pin "U8D7.C5"
				( objectStatus "@baseboard_fab2_lib.baseboard_fab2(sch_1):page191_i59:pt10b" )
			)
			( pin "U8D7.A5"
				( objectStatus "@baseboard_fab2_lib.baseboard_fab2(sch_1):page191_i59:pt11a" )
			)
			( pin "U8D7.B6"
				( objectStatus "@baseboard_fab2_lib.baseboard_fab2(sch_1):page191_i59:pt11b" )
			)
			( pin "U8D7.A3"
				( objectStatus "@baseboard_fab2_lib.baseboard_fab2(sch_1):page191_i59:pt11c" )
			)
			( pin "U8D7.B4"
				( objectStatus "@baseboard_fab2_lib.baseboard_fab2(sch_1):page191_i59:pt11d" )
			)
			( pin "U8D7.D6"
				( objectStatus "@baseboard_fab2_lib.baseboard_fab2(sch_1):page191_i59:pt12a" )
			)
			( pin "U8D7.E7"
				( objectStatus "@baseboard_fab2_lib.baseboard_fab2(sch_1):page191_i59:pt12b" )
			)
			( pin "U8D7.C6"
				( objectStatus "@baseboard_fab2_lib.baseboard_fab2(sch_1):page191_i59:pt12c_tdo" )
			)
			( pin "U8D7.A6"
				( objectStatus "@baseboard_fab2_lib.baseboard_fab2(sch_1):page191_i59:pt12d_tdi" )
			)
			( pin "U8D7.B7"
				( objectStatus "@baseboard_fab2_lib.baseboard_fab2(sch_1):page191_i59:pt13a" )
			)
			( pin "U8D7.C7"
				( objectStatus "@baseboard_fab2_lib.baseboard_fab2(sch_1):page191_i59:pt13b" )
			)
			( pin "U8D7.E6"
				( objectStatus "@baseboard_fab2_lib.baseboard_fab2(sch_1):page191_i59:pt13c" )
			)
			( pin "U8D7.D7"
				( objectStatus "@baseboard_fab2_lib.baseboard_fab2(sch_1):page191_i59:pt13d" )
			)
			( pin "U8D7.F7"
				( objectStatus "@baseboard_fab2_lib.baseboard_fab2(sch_1):page191_i59:pt16a" )
			)
			( pin "U8D7.E8"
				( objectStatus "@baseboard_fab2_lib.baseboard_fab2(sch_1):page191_i59:pt16b" )
			)
			( pin "U8D7.A7"
				( objectStatus "@baseboard_fab2_lib.baseboard_fab2(sch_1):page191_i59:pt16c_tck" )
			)
			( pin "U8D7.B8"
				( objectStatus "@baseboard_fab2_lib.baseboard_fab2(sch_1):page191_i59:pt16d_tms" )
			)
			( pin "U8D7.C8"
				( objectStatus "@baseboard_fab2_lib.baseboard_fab2(sch_1):page191_i59:pt17a_pclkt0_1" )
			)
			( pin "U8D7.A8"
				( objectStatus "@baseboard_fab2_lib.baseboard_fab2(sch_1):page191_i59:pt17b_pclkc0_1" )
			)
			( pin "U8D7.D8"
				( objectStatus "@baseboard_fab2_lib.baseboard_fab2(sch_1):page191_i59:pt17c" )
			)
			( pin "U8D7.E9"
				( objectStatus "@baseboard_fab2_lib.baseboard_fab2(sch_1):page191_i59:pt17d" )
			)
			( pin "U8D7.F8"
				( objectStatus "@baseboard_fab2_lib.baseboard_fab2(sch_1):page191_i59:pt18a" )
			)
			( pin "U8D7.D9"
				( objectStatus "@baseboard_fab2_lib.baseboard_fab2(sch_1):page191_i59:pt18b" )
			)
			( pin "U8D7.A9"
				( objectStatus "@baseboard_fab2_lib.baseboard_fab2(sch_1):page191_i59:pt18c_scl_pclkt0_0" )
			)
			( pin "U8D7.C9"
				( objectStatus "@baseboard_fab2_lib.baseboard_fab2(sch_1):page191_i59:pt18d_sda_pclkc0_0" )
			)
			( pin "U8D7.B9"
				( objectStatus "@baseboard_fab2_lib.baseboard_fab2(sch_1):page191_i59:pt19a" )
			)
			( pin "U8D7.A10"
				( objectStatus "@baseboard_fab2_lib.baseboard_fab2(sch_1):page191_i59:pt19b" )
			)
			( pin "U8D7.F9"
				( objectStatus "@baseboard_fab2_lib.baseboard_fab2(sch_1):page191_i59:pt19c" )
			)
			( pin "U8D7.E11"
				( objectStatus "@baseboard_fab2_lib.baseboard_fab2(sch_1):page191_i59:pt19d" )
			)
			( pin "U8D7.D10"
				( objectStatus "@baseboard_fab2_lib.baseboard_fab2(sch_1):page191_i59:pt20a" )
			)
			( pin "U8D7.E10"
				( objectStatus "@baseboard_fab2_lib.baseboard_fab2(sch_1):page191_i59:pt20b" )
			)
			( pin "U8D7.C10"
				( objectStatus "@baseboard_fab2_lib.baseboard_fab2(sch_1):page191_i59:pt20c_jtagenb" )
			)
			( pin "U8D7.B10"
				( objectStatus "@baseboard_fab2_lib.baseboard_fab2(sch_1):page191_i59:pt20d_programn" )
			)
			( pin "U8D7.A11"
				( objectStatus "@baseboard_fab2_lib.baseboard_fab2(sch_1):page191_i59:pt21a" )
			)
			( pin "U8D7.C11"
				( objectStatus "@baseboard_fab2_lib.baseboard_fab2(sch_1):page191_i59:pt21b" )
			)
			( pin "U8D7.F10"
				( objectStatus "@baseboard_fab2_lib.baseboard_fab2(sch_1):page191_i59:pt21c" )
			)
			( pin "U8D7.D11"
				( objectStatus "@baseboard_fab2_lib.baseboard_fab2(sch_1):page191_i59:pt21d" )
			)
			( pin "U8D7.B11"
				( objectStatus "@baseboard_fab2_lib.baseboard_fab2(sch_1):page191_i59:pt22a" )
			)
			( pin "U8D7.A12"
				( objectStatus "@baseboard_fab2_lib.baseboard_fab2(sch_1):page191_i59:pt22b" )
			)
			( pin "U8D7.B13"
				( objectStatus "@baseboard_fab2_lib.baseboard_fab2(sch_1):page191_i59:pt22c" )
			)
			( pin "U8D7.A14"
				( objectStatus "@baseboard_fab2_lib.baseboard_fab2(sch_1):page191_i59:pt22d" )
			)
			( pin "U8D7.C12"
				( objectStatus "@baseboard_fab2_lib.baseboard_fab2(sch_1):page191_i59:pt23a" )
			)
			( pin "U8D7.B12"
				( objectStatus "@baseboard_fab2_lib.baseboard_fab2(sch_1):page191_i59:pt23b" )
			)
			( pin "U8D7.B14"
				( objectStatus "@baseboard_fab2_lib.baseboard_fab2(sch_1):page191_i59:pt24a" )
			)
			( pin "U8D7.A15"
				( objectStatus "@baseboard_fab2_lib.baseboard_fab2(sch_1):page191_i59:pt24b" )
			)
			( pin "U8D7.A13"
				( objectStatus "@baseboard_fab2_lib.baseboard_fab2(sch_1):page191_i59:pt24c_initn" )
			)
			( pin "U8D7.C13"
				( objectStatus "@baseboard_fab2_lib.baseboard_fab2(sch_1):page191_i59:pt24d_done" )
			)
			( pin "R2R6.1"
				( objectStatus "@baseboard_fab2_lib.baseboard_fab2(sch_1):page191_i166:a" )
			)
			( pin "R2R6.2"
				( objectStatus "@baseboard_fab2_lib.baseboard_fab2(sch_1):page191_i166:b" )
			)
			( pin "R2R7.1"
				( objectStatus "@baseboard_fab2_lib.baseboard_fab2(sch_1):page191_i172:a" )
			)
			( pin "R2R7.2"
				( objectStatus "@baseboard_fab2_lib.baseboard_fab2(sch_1):page191_i172:b" )
			)
			( pin "R2R4.1"
				( objectStatus "@baseboard_fab2_lib.baseboard_fab2(sch_1):page191_i184:a" )
			)
			( pin "R2R4.2"
				( objectStatus "@baseboard_fab2_lib.baseboard_fab2(sch_1):page191_i184:b" )
			)
			( pin "R7D42.1"
				( objectStatus "@baseboard_fab2_lib.baseboard_fab2(sch_1):page191_i193:a" )
			)
			( pin "R7D42.2"
				( objectStatus "@baseboard_fab2_lib.baseboard_fab2(sch_1):page191_i193:b" )
			)
			( pin "C2P8.1"
				( objectStatus "@baseboard_fab2_lib.baseboard_fab2(sch_1):page192_i1:a" )
			)
			( pin "C2P8.2"
				( objectStatus "@baseboard_fab2_lib.baseboard_fab2(sch_1):page192_i1:b" )
			)
			( pin "C2P5.1"
				( objectStatus "@baseboard_fab2_lib.baseboard_fab2(sch_1):page192_i3:a" )
			)
			( pin "C2P5.2"
				( objectStatus "@baseboard_fab2_lib.baseboard_fab2(sch_1):page192_i3:b" )
			)
			( pin "C3R1.1"
				( objectStatus "@baseboard_fab2_lib.baseboard_fab2(sch_1):page192_i4:a" )
			)
			( pin "C3R1.2"
				( objectStatus "@baseboard_fab2_lib.baseboard_fab2(sch_1):page192_i4:b" )
			)
			( pin "C3P43.1"
				( objectStatus "@baseboard_fab2_lib.baseboard_fab2(sch_1):page192_i6:a" )
			)
			( pin "C3P43.2"
				( objectStatus "@baseboard_fab2_lib.baseboard_fab2(sch_1):page192_i6:b" )
			)
			( pin "C3R3.1"
				( objectStatus "@baseboard_fab2_lib.baseboard_fab2(sch_1):page192_i7:a" )
			)
			( pin "C3R3.2"
				( objectStatus "@baseboard_fab2_lib.baseboard_fab2(sch_1):page192_i7:b" )
			)
			( pin "C2R1.1"
				( objectStatus "@baseboard_fab2_lib.baseboard_fab2(sch_1):page192_i8:a" )
			)
			( pin "C2R1.2"
				( objectStatus "@baseboard_fab2_lib.baseboard_fab2(sch_1):page192_i8:b" )
			)
			( pin "C2P2.1"
				( objectStatus "@baseboard_fab2_lib.baseboard_fab2(sch_1):page192_i9:a" )
			)
			( pin "C2P2.2"
				( objectStatus "@baseboard_fab2_lib.baseboard_fab2(sch_1):page192_i9:b" )
			)
			( pin "C3R2.1"
				( objectStatus "@baseboard_fab2_lib.baseboard_fab2(sch_1):page192_i10:a" )
			)
			( pin "C3R2.2"
				( objectStatus "@baseboard_fab2_lib.baseboard_fab2(sch_1):page192_i10:b" )
			)
			( pin "C3P51.1"
				( objectStatus "@baseboard_fab2_lib.baseboard_fab2(sch_1):page192_i11:a" )
			)
			( pin "C3P51.2"
				( objectStatus "@baseboard_fab2_lib.baseboard_fab2(sch_1):page192_i11:b" )
			)
			( pin "C3P47.1"
				( objectStatus "@baseboard_fab2_lib.baseboard_fab2(sch_1):page192_i12:a" )
			)
			( pin "C3P47.2"
				( objectStatus "@baseboard_fab2_lib.baseboard_fab2(sch_1):page192_i12:b" )
			)
			( pin "U8D7.B2"
				( objectStatus "@baseboard_fab2_lib.baseboard_fab2(sch_1):page192_i14:gnd(0)" )
			)
			( pin "U8D7.B15"
				( objectStatus "@baseboard_fab2_lib.baseboard_fab2(sch_1):page192_i14:gnd(1)" )
			)
			( pin "U8D7.C3"
				( objectStatus "@baseboard_fab2_lib.baseboard_fab2(sch_1):page192_i14:gnd(2)" )
			)
			( pin "U8D7.C14"
				( objectStatus "@baseboard_fab2_lib.baseboard_fab2(sch_1):page192_i14:gnd(3)" )
			)
			( pin "U8D7.D4"
				( objectStatus "@baseboard_fab2_lib.baseboard_fab2(sch_1):page192_i14:gnd(4)" )
			)
			( pin "U8D7.D13"
				( objectStatus "@baseboard_fab2_lib.baseboard_fab2(sch_1):page192_i14:gnd(5)" )
			)
			( pin "U8D7.E5"
				( objectStatus "@baseboard_fab2_lib.baseboard_fab2(sch_1):page192_i14:gnd(6)" )
			)
			( pin "U8D7.E12"
				( objectStatus "@baseboard_fab2_lib.baseboard_fab2(sch_1):page192_i14:gnd(7)" )
			)
			( pin "U8D7.F6"
				( objectStatus "@baseboard_fab2_lib.baseboard_fab2(sch_1):page192_i14:gnd(8)" )
			)
			( pin "U8D7.F11"
				( objectStatus "@baseboard_fab2_lib.baseboard_fab2(sch_1):page192_i14:gnd(9)" )
			)
			( pin "U8D7.H8"
				( objectStatus "@baseboard_fab2_lib.baseboard_fab2(sch_1):page192_i14:gnd(10)" )
			)
			( pin "U8D7.H9"
				( objectStatus "@baseboard_fab2_lib.baseboard_fab2(sch_1):page192_i14:gnd(11)" )
			)
			( pin "U8D7.J8"
				( objectStatus "@baseboard_fab2_lib.baseboard_fab2(sch_1):page192_i14:gnd(12)" )
			)
			( pin "U8D7.J9"
				( objectStatus "@baseboard_fab2_lib.baseboard_fab2(sch_1):page192_i14:gnd(13)" )
			)
			( pin "U8D7.L6"
				( objectStatus "@baseboard_fab2_lib.baseboard_fab2(sch_1):page192_i14:gnd(14)" )
			)
			( pin "U8D7.L11"
				( objectStatus "@baseboard_fab2_lib.baseboard_fab2(sch_1):page192_i14:gnd(15)" )
			)
			( pin "U8D7.M5"
				( objectStatus "@baseboard_fab2_lib.baseboard_fab2(sch_1):page192_i14:gnd(16)" )
			)
			( pin "U8D7.M12"
				( objectStatus "@baseboard_fab2_lib.baseboard_fab2(sch_1):page192_i14:gnd(17)" )
			)
			( pin "U8D7.N4"
				( objectStatus "@baseboard_fab2_lib.baseboard_fab2(sch_1):page192_i14:gnd(18)" )
			)
			( pin "U8D7.N13"
				( objectStatus "@baseboard_fab2_lib.baseboard_fab2(sch_1):page192_i14:gnd(19)" )
			)
			( pin "U8D7.P3"
				( objectStatus "@baseboard_fab2_lib.baseboard_fab2(sch_1):page192_i14:gnd(20)" )
			)
			( pin "U8D7.P14"
				( objectStatus "@baseboard_fab2_lib.baseboard_fab2(sch_1):page192_i14:gnd(21)" )
			)
			( pin "U8D7.R2"
				( objectStatus "@baseboard_fab2_lib.baseboard_fab2(sch_1):page192_i14:gnd(22)" )
			)
			( pin "U8D7.R15"
				( objectStatus "@baseboard_fab2_lib.baseboard_fab2(sch_1):page192_i14:gnd(23)" )
			)
			( pin "U8D7.A2"
				( objectStatus "@baseboard_fab2_lib.baseboard_fab2(sch_1):page192_i14:nc(0)" )
			)
			( pin "U8D7.A1"
				( objectStatus "@baseboard_fab2_lib.baseboard_fab2(sch_1):page192_i14:vcc(0)" )
			)
			( pin "U8D7.A16"
				( objectStatus "@baseboard_fab2_lib.baseboard_fab2(sch_1):page192_i14:vcc(1)" )
			)
			( pin "U8D7.T1"
				( objectStatus "@baseboard_fab2_lib.baseboard_fab2(sch_1):page192_i14:vcc(2)" )
			)
			( pin "U8D7.T16"
				( objectStatus "@baseboard_fab2_lib.baseboard_fab2(sch_1):page192_i14:vcc(3)" )
			)
			( pin "U8D7.G7"
				( objectStatus "@baseboard_fab2_lib.baseboard_fab2(sch_1):page192_i14:vcc(4)" )
			)
			( pin "U8D7.G10"
				( objectStatus "@baseboard_fab2_lib.baseboard_fab2(sch_1):page192_i14:vcc(5)" )
			)
			( pin "U8D7.K7"
				( objectStatus "@baseboard_fab2_lib.baseboard_fab2(sch_1):page192_i14:vcc(6)" )
			)
			( pin "U8D7.K10"
				( objectStatus "@baseboard_fab2_lib.baseboard_fab2(sch_1):page192_i14:vcc(7)" )
			)
			( pin "U8D7.G8"
				( objectStatus "@baseboard_fab2_lib.baseboard_fab2(sch_1):page192_i14:vccio0(0)" )
			)
			( pin "U8D7.D12"
				( objectStatus "@baseboard_fab2_lib.baseboard_fab2(sch_1):page192_i14:vccio0(1)" )
			)
			( pin "U8D7.G9"
				( objectStatus "@baseboard_fab2_lib.baseboard_fab2(sch_1):page192_i14:vccio0(2)" )
			)
			( pin "U8D7.D5"
				( objectStatus "@baseboard_fab2_lib.baseboard_fab2(sch_1):page192_i14:vccio0(3)" )
			)
			( pin "U8D7.E13"
				( objectStatus "@baseboard_fab2_lib.baseboard_fab2(sch_1):page192_i14:vccio1(0)" )
			)
			( pin "U8D7.H10"
				( objectStatus "@baseboard_fab2_lib.baseboard_fab2(sch_1):page192_i14:vccio1(1)" )
			)
			( pin "U8D7.J10"
				( objectStatus "@baseboard_fab2_lib.baseboard_fab2(sch_1):page192_i14:vccio1(2)" )
			)
			( pin "U8D7.M13"
				( objectStatus "@baseboard_fab2_lib.baseboard_fab2(sch_1):page192_i14:vccio1(3)" )
			)
			( pin "U8D7.K9"
				( objectStatus "@baseboard_fab2_lib.baseboard_fab2(sch_1):page192_i14:vccio2(0)" )
			)
			( pin "U8D7.N12"
				( objectStatus "@baseboard_fab2_lib.baseboard_fab2(sch_1):page192_i14:vccio2(1)" )
			)
			( pin "U8D7.K8"
				( objectStatus "@baseboard_fab2_lib.baseboard_fab2(sch_1):page192_i14:vccio2(2)" )
			)
			( pin "U8D7.N5"
				( objectStatus "@baseboard_fab2_lib.baseboard_fab2(sch_1):page192_i14:vccio2(3)" )
			)
			( pin "U8D7.M4"
				( objectStatus "@baseboard_fab2_lib.baseboard_fab2(sch_1):page192_i14:vccio3(0)" )
			)
			( pin "U8D7.J7"
				( objectStatus "@baseboard_fab2_lib.baseboard_fab2(sch_1):page192_i14:vccio4(0)" )
			)
			( pin "U8D7.H7"
				( objectStatus "@baseboard_fab2_lib.baseboard_fab2(sch_1):page192_i14:vccio4(1)" )
			)
			( pin "U8D7.E4"
				( objectStatus "@baseboard_fab2_lib.baseboard_fab2(sch_1):page192_i14:vccio5(0)" )
			)
			( pin "C2R5.1"
				( objectStatus "@baseboard_fab2_lib.baseboard_fab2(sch_1):page192_i15:a" )
			)
			( pin "C2R5.2"
				( objectStatus "@baseboard_fab2_lib.baseboard_fab2(sch_1):page192_i15:b" )
			)
			( pin "C2P4.1"
				( objectStatus "@baseboard_fab2_lib.baseboard_fab2(sch_1):page192_i16:a" )
			)
			( pin "C2P4.2"
				( objectStatus "@baseboard_fab2_lib.baseboard_fab2(sch_1):page192_i16:b" )
			)
			( pin "C3P52.1"
				( objectStatus "@baseboard_fab2_lib.baseboard_fab2(sch_1):page192_i17:a" )
			)
			( pin "C3P52.2"
				( objectStatus "@baseboard_fab2_lib.baseboard_fab2(sch_1):page192_i17:b" )
			)
			( pin "C2P6.1"
				( objectStatus "@baseboard_fab2_lib.baseboard_fab2(sch_1):page192_i18:a" )
			)
			( pin "C2P6.2"
				( objectStatus "@baseboard_fab2_lib.baseboard_fab2(sch_1):page192_i18:b" )
			)
			( pin "C2R3.1"
				( objectStatus "@baseboard_fab2_lib.baseboard_fab2(sch_1):page192_i19:a" )
			)
			( pin "C2R3.2"
				( objectStatus "@baseboard_fab2_lib.baseboard_fab2(sch_1):page192_i19:b" )
			)
			( pin "C2P7.1"
				( objectStatus "@baseboard_fab2_lib.baseboard_fab2(sch_1):page192_i20:a" )
			)
			( pin "C2P7.2"
				( objectStatus "@baseboard_fab2_lib.baseboard_fab2(sch_1):page192_i20:b" )
			)
			( pin "C2R4.1"
				( objectStatus "@baseboard_fab2_lib.baseboard_fab2(sch_1):page192_i21:a" )
			)
			( pin "C2R4.2"
				( objectStatus "@baseboard_fab2_lib.baseboard_fab2(sch_1):page192_i21:b" )
			)
			( pin "C2P3.1"
				( objectStatus "@baseboard_fab2_lib.baseboard_fab2(sch_1):page192_i22:a" )
			)
			( pin "C2P3.2"
				( objectStatus "@baseboard_fab2_lib.baseboard_fab2(sch_1):page192_i22:b" )
			)
			( pin "C3P44.1"
				( objectStatus "@baseboard_fab2_lib.baseboard_fab2(sch_1):page192_i23:a" )
			)
			( pin "C3P44.2"
				( objectStatus "@baseboard_fab2_lib.baseboard_fab2(sch_1):page192_i23:b" )
			)
			( pin "C3P48.1"
				( objectStatus "@baseboard_fab2_lib.baseboard_fab2(sch_1):page192_i25:a" )
			)
			( pin "C3P48.2"
				( objectStatus "@baseboard_fab2_lib.baseboard_fab2(sch_1):page192_i25:b" )
			)
			( pin "C2R2.1"
				( objectStatus "@baseboard_fab2_lib.baseboard_fab2(sch_1):page192_i28:a" )
			)
			( pin "C2R2.2"
				( objectStatus "@baseboard_fab2_lib.baseboard_fab2(sch_1):page192_i28:b" )
			)
			( pin "R7E6.1"
				( objectStatus "@baseboard_fab2_lib.baseboard_fab2(sch_1):page192_i33:a" )
			)
			( pin "R7E6.2"
				( objectStatus "@baseboard_fab2_lib.baseboard_fab2(sch_1):page192_i33:b" )
			)
			( pin "R2R1.1"
				( objectStatus "@baseboard_fab2_lib.baseboard_fab2(sch_1):page192_i34:a" )
			)
			( pin "R2R1.2"
				( objectStatus "@baseboard_fab2_lib.baseboard_fab2(sch_1):page192_i34:b" )
			)
			( pin "R7E5.1"
				( objectStatus "@baseboard_fab2_lib.baseboard_fab2(sch_1):page192_i38:a" )
			)
			( pin "R7E5.2"
				( objectStatus "@baseboard_fab2_lib.baseboard_fab2(sch_1):page192_i38:b" )
			)
			( pin "R2R3.1"
				( objectStatus "@baseboard_fab2_lib.baseboard_fab2(sch_1):page192_i41:a" )
			)
			( pin "R2R3.2"
				( objectStatus "@baseboard_fab2_lib.baseboard_fab2(sch_1):page192_i41:b" )
			)
			( pin "R3R16.1"
				( objectStatus "@baseboard_fab2_lib.baseboard_fab2(sch_1):page192_i48:a" )
			)
			( pin "R3R16.2"
				( objectStatus "@baseboard_fab2_lib.baseboard_fab2(sch_1):page192_i48:b" )
			)
			( pin "R6M9.1"
				( objectStatus "@baseboard_fab2_lib.baseboard_fab2(sch_1):page192_i49:a" )
			)
			( pin "R6M9.2"
				( objectStatus "@baseboard_fab2_lib.baseboard_fab2(sch_1):page192_i49:b" )
			)
			( pin "R7E18.1"
				( objectStatus "@baseboard_fab2_lib.baseboard_fab2(sch_1):page192_i55:a" )
			)
			( pin "R7E18.2"
				( objectStatus "@baseboard_fab2_lib.baseboard_fab2(sch_1):page192_i55:b" )
			)
			( pin "R7E19.1"
				( objectStatus "@baseboard_fab2_lib.baseboard_fab2(sch_1):page192_i57:a" )
			)
			( pin "R7E19.2"
				( objectStatus "@baseboard_fab2_lib.baseboard_fab2(sch_1):page192_i57:b" )
			)
			( pin "R7E20.1"
				( objectStatus "@baseboard_fab2_lib.baseboard_fab2(sch_1):page192_i59:a" )
			)
			( pin "R7E20.2"
				( objectStatus "@baseboard_fab2_lib.baseboard_fab2(sch_1):page192_i59:b" )
			)
			( pin "C4C1.1"
				( objectStatus "@baseboard_fab2_lib.baseboard_fab2(sch_1):page193_i29:a" )
			)
			( pin "C4C1.2"
				( objectStatus "@baseboard_fab2_lib.baseboard_fab2(sch_1):page193_i29:b" )
			)
			( pin "C3C2.1"
				( objectStatus "@baseboard_fab2_lib.baseboard_fab2(sch_1):page193_i31:a" )
			)
			( pin "C3C2.2"
				( objectStatus "@baseboard_fab2_lib.baseboard_fab2(sch_1):page193_i31:b" )
			)
			( pin "C3C1.1"
				( objectStatus "@baseboard_fab2_lib.baseboard_fab2(sch_1):page193_i38:a" )
			)
			( pin "C3C1.2"
				( objectStatus "@baseboard_fab2_lib.baseboard_fab2(sch_1):page193_i38:b" )
			)
			( pin "J4E1.A1"
				( objectStatus "@baseboard_fab2_lib.baseboard_fab2(sch_1):page193_i45:ioa1" )
			)
			( pin "J4E1.A2"
				( objectStatus "@baseboard_fab2_lib.baseboard_fab2(sch_1):page193_i45:ioa2" )
			)
			( pin "J4E1.A3"
				( objectStatus "@baseboard_fab2_lib.baseboard_fab2(sch_1):page193_i45:ioa3" )
			)
			( pin "J4E1.A4"
				( objectStatus "@baseboard_fab2_lib.baseboard_fab2(sch_1):page193_i45:ioa4" )
			)
			( pin "J4E1.A5"
				( objectStatus "@baseboard_fab2_lib.baseboard_fab2(sch_1):page193_i45:ioa5" )
			)
			( pin "J4E1.A6"
				( objectStatus "@baseboard_fab2_lib.baseboard_fab2(sch_1):page193_i45:ioa6" )
			)
			( pin "J4E1.A7"
				( objectStatus "@baseboard_fab2_lib.baseboard_fab2(sch_1):page193_i45:ioa7" )
			)
			( pin "J4E1.A8"
				( objectStatus "@baseboard_fab2_lib.baseboard_fab2(sch_1):page193_i45:ioa8" )
			)
			( pin "J4E1.A9"
				( objectStatus "@baseboard_fab2_lib.baseboard_fab2(sch_1):page193_i45:ioa9" )
			)
			( pin "J4E1.A10"
				( objectStatus "@baseboard_fab2_lib.baseboard_fab2(sch_1):page193_i45:ioa10" )
			)
			( pin "J4E1.A11"
				( objectStatus "@baseboard_fab2_lib.baseboard_fab2(sch_1):page193_i45:ioa11" )
			)
			( pin "J4E1.A12"
				( objectStatus "@baseboard_fab2_lib.baseboard_fab2(sch_1):page193_i45:ioa12" )
			)
			( pin "J4E1.A13"
				( objectStatus "@baseboard_fab2_lib.baseboard_fab2(sch_1):page193_i45:ioa13" )
			)
			( pin "J4E1.A14"
				( objectStatus "@baseboard_fab2_lib.baseboard_fab2(sch_1):page193_i45:ioa14" )
			)
			( pin "J4E1.A15"
				( objectStatus "@baseboard_fab2_lib.baseboard_fab2(sch_1):page193_i45:ioa15" )
			)
			( pin "J4E1.A16"
				( objectStatus "@baseboard_fab2_lib.baseboard_fab2(sch_1):page193_i45:ioa16" )
			)
			( pin "J4E1.A17"
				( objectStatus "@baseboard_fab2_lib.baseboard_fab2(sch_1):page193_i45:ioa17" )
			)
			( pin "J4E1.A18"
				( objectStatus "@baseboard_fab2_lib.baseboard_fab2(sch_1):page193_i45:ioa18" )
			)
			( pin "J4E1.A19"
				( objectStatus "@baseboard_fab2_lib.baseboard_fab2(sch_1):page193_i45:ioa19" )
			)
			( pin "J4E1.A20"
				( objectStatus "@baseboard_fab2_lib.baseboard_fab2(sch_1):page193_i45:ioa20" )
			)
			( pin "J4E1.B1"
				( objectStatus "@baseboard_fab2_lib.baseboard_fab2(sch_1):page193_i45:iob1" )
			)
			( pin "J4E1.B2"
				( objectStatus "@baseboard_fab2_lib.baseboard_fab2(sch_1):page193_i45:iob2" )
			)
			( pin "J4E1.B3"
				( objectStatus "@baseboard_fab2_lib.baseboard_fab2(sch_1):page193_i45:iob3" )
			)
			( pin "J4E1.B4"
				( objectStatus "@baseboard_fab2_lib.baseboard_fab2(sch_1):page193_i45:iob4" )
			)
			( pin "J4E1.B5"
				( objectStatus "@baseboard_fab2_lib.baseboard_fab2(sch_1):page193_i45:iob5" )
			)
			( pin "J4E1.B6"
				( objectStatus "@baseboard_fab2_lib.baseboard_fab2(sch_1):page193_i45:iob6" )
			)
			( pin "J4E1.B7"
				( objectStatus "@baseboard_fab2_lib.baseboard_fab2(sch_1):page193_i45:iob7" )
			)
			( pin "J4E1.B8"
				( objectStatus "@baseboard_fab2_lib.baseboard_fab2(sch_1):page193_i45:iob8" )
			)
			( pin "J4E1.B9"
				( objectStatus "@baseboard_fab2_lib.baseboard_fab2(sch_1):page193_i45:iob9" )
			)
			( pin "J4E1.B10"
				( objectStatus "@baseboard_fab2_lib.baseboard_fab2(sch_1):page193_i45:iob10" )
			)
			( pin "J4E1.B11"
				( objectStatus "@baseboard_fab2_lib.baseboard_fab2(sch_1):page193_i45:iob11" )
			)
			( pin "J4E1.B12"
				( objectStatus "@baseboard_fab2_lib.baseboard_fab2(sch_1):page193_i45:iob12" )
			)
			( pin "J4E1.B13"
				( objectStatus "@baseboard_fab2_lib.baseboard_fab2(sch_1):page193_i45:iob13" )
			)
			( pin "J4E1.B14"
				( objectStatus "@baseboard_fab2_lib.baseboard_fab2(sch_1):page193_i45:iob14" )
			)
			( pin "J4E1.B15"
				( objectStatus "@baseboard_fab2_lib.baseboard_fab2(sch_1):page193_i45:iob15" )
			)
			( pin "J4E1.B16"
				( objectStatus "@baseboard_fab2_lib.baseboard_fab2(sch_1):page193_i45:iob16" )
			)
			( pin "J4E1.B17"
				( objectStatus "@baseboard_fab2_lib.baseboard_fab2(sch_1):page193_i45:iob17" )
			)
			( pin "J4E1.B18"
				( objectStatus "@baseboard_fab2_lib.baseboard_fab2(sch_1):page193_i45:iob18" )
			)
			( pin "J4E1.B19"
				( objectStatus "@baseboard_fab2_lib.baseboard_fab2(sch_1):page193_i45:iob19" )
			)
			( pin "J4E1.B20"
				( objectStatus "@baseboard_fab2_lib.baseboard_fab2(sch_1):page193_i45:iob20" )
			)
			( pin "J4E1.C1"
				( objectStatus "@baseboard_fab2_lib.baseboard_fab2(sch_1):page193_i45:ioc1" )
			)
			( pin "J4E1.C2"
				( objectStatus "@baseboard_fab2_lib.baseboard_fab2(sch_1):page193_i45:ioc2" )
			)
			( pin "J4E1.C3"
				( objectStatus "@baseboard_fab2_lib.baseboard_fab2(sch_1):page193_i45:ioc3" )
			)
			( pin "J4E1.C4"
				( objectStatus "@baseboard_fab2_lib.baseboard_fab2(sch_1):page193_i45:ioc4" )
			)
			( pin "J4E1.C5"
				( objectStatus "@baseboard_fab2_lib.baseboard_fab2(sch_1):page193_i45:ioc5" )
			)
			( pin "J4E1.C6"
				( objectStatus "@baseboard_fab2_lib.baseboard_fab2(sch_1):page193_i45:ioc6" )
			)
			( pin "J4E1.C7"
				( objectStatus "@baseboard_fab2_lib.baseboard_fab2(sch_1):page193_i45:ioc7" )
			)
			( pin "J4E1.C8"
				( objectStatus "@baseboard_fab2_lib.baseboard_fab2(sch_1):page193_i45:ioc8" )
			)
			( pin "J4E1.C9"
				( objectStatus "@baseboard_fab2_lib.baseboard_fab2(sch_1):page193_i45:ioc9" )
			)
			( pin "J4E1.C10"
				( objectStatus "@baseboard_fab2_lib.baseboard_fab2(sch_1):page193_i45:ioc10" )
			)
			( pin "J4E1.C11"
				( objectStatus "@baseboard_fab2_lib.baseboard_fab2(sch_1):page193_i45:ioc11" )
			)
			( pin "J4E1.C12"
				( objectStatus "@baseboard_fab2_lib.baseboard_fab2(sch_1):page193_i45:ioc12" )
			)
			( pin "J4E1.C13"
				( objectStatus "@baseboard_fab2_lib.baseboard_fab2(sch_1):page193_i45:ioc13" )
			)
			( pin "J4E1.C14"
				( objectStatus "@baseboard_fab2_lib.baseboard_fab2(sch_1):page193_i45:ioc14" )
			)
			( pin "J4E1.C15"
				( objectStatus "@baseboard_fab2_lib.baseboard_fab2(sch_1):page193_i45:ioc15" )
			)
			( pin "J4E1.C16"
				( objectStatus "@baseboard_fab2_lib.baseboard_fab2(sch_1):page193_i45:ioc16" )
			)
			( pin "J4E1.C17"
				( objectStatus "@baseboard_fab2_lib.baseboard_fab2(sch_1):page193_i45:ioc17" )
			)
			( pin "J4E1.C18"
				( objectStatus "@baseboard_fab2_lib.baseboard_fab2(sch_1):page193_i45:ioc18" )
			)
			( pin "J4E1.C19"
				( objectStatus "@baseboard_fab2_lib.baseboard_fab2(sch_1):page193_i45:ioc19" )
			)
			( pin "J4E1.C20"
				( objectStatus "@baseboard_fab2_lib.baseboard_fab2(sch_1):page193_i45:ioc20" )
			)
			( pin "J4E1.D1"
				( objectStatus "@baseboard_fab2_lib.baseboard_fab2(sch_1):page193_i45:iod1" )
			)
			( pin "J4E1.D2"
				( objectStatus "@baseboard_fab2_lib.baseboard_fab2(sch_1):page193_i45:iod2" )
			)
			( pin "J4E1.D3"
				( objectStatus "@baseboard_fab2_lib.baseboard_fab2(sch_1):page193_i45:iod3" )
			)
			( pin "J4E1.D4"
				( objectStatus "@baseboard_fab2_lib.baseboard_fab2(sch_1):page193_i45:iod4" )
			)
			( pin "J4E1.D5"
				( objectStatus "@baseboard_fab2_lib.baseboard_fab2(sch_1):page193_i45:iod5" )
			)
			( pin "J4E1.D6"
				( objectStatus "@baseboard_fab2_lib.baseboard_fab2(sch_1):page193_i45:iod6" )
			)
			( pin "J4E1.D7"
				( objectStatus "@baseboard_fab2_lib.baseboard_fab2(sch_1):page193_i45:iod7" )
			)
			( pin "J4E1.D8"
				( objectStatus "@baseboard_fab2_lib.baseboard_fab2(sch_1):page193_i45:iod8" )
			)
			( pin "J4E1.D9"
				( objectStatus "@baseboard_fab2_lib.baseboard_fab2(sch_1):page193_i45:iod9" )
			)
			( pin "J4E1.D10"
				( objectStatus "@baseboard_fab2_lib.baseboard_fab2(sch_1):page193_i45:iod10" )
			)
			( pin "J4E1.D11"
				( objectStatus "@baseboard_fab2_lib.baseboard_fab2(sch_1):page193_i45:iod11" )
			)
			( pin "J4E1.D12"
				( objectStatus "@baseboard_fab2_lib.baseboard_fab2(sch_1):page193_i45:iod12" )
			)
			( pin "J4E1.D13"
				( objectStatus "@baseboard_fab2_lib.baseboard_fab2(sch_1):page193_i45:iod13" )
			)
			( pin "J4E1.D14"
				( objectStatus "@baseboard_fab2_lib.baseboard_fab2(sch_1):page193_i45:iod14" )
			)
			( pin "J4E1.D15"
				( objectStatus "@baseboard_fab2_lib.baseboard_fab2(sch_1):page193_i45:iod15" )
			)
			( pin "J4E1.D16"
				( objectStatus "@baseboard_fab2_lib.baseboard_fab2(sch_1):page193_i45:iod16" )
			)
			( pin "J4E1.D17"
				( objectStatus "@baseboard_fab2_lib.baseboard_fab2(sch_1):page193_i45:iod17" )
			)
			( pin "J4E1.D18"
				( objectStatus "@baseboard_fab2_lib.baseboard_fab2(sch_1):page193_i45:iod18" )
			)
			( pin "J4E1.D19"
				( objectStatus "@baseboard_fab2_lib.baseboard_fab2(sch_1):page193_i45:iod19" )
			)
			( pin "J4E1.D20"
				( objectStatus "@baseboard_fab2_lib.baseboard_fab2(sch_1):page193_i45:iod20" )
			)
			( pin "J4E1.E1"
				( objectStatus "@baseboard_fab2_lib.baseboard_fab2(sch_1):page193_i45:ioe1" )
			)
			( pin "J4E1.E2"
				( objectStatus "@baseboard_fab2_lib.baseboard_fab2(sch_1):page193_i45:ioe2" )
			)
			( pin "J4E1.E3"
				( objectStatus "@baseboard_fab2_lib.baseboard_fab2(sch_1):page193_i45:ioe3" )
			)
			( pin "J4E1.E4"
				( objectStatus "@baseboard_fab2_lib.baseboard_fab2(sch_1):page193_i45:ioe4" )
			)
			( pin "J4E1.E5"
				( objectStatus "@baseboard_fab2_lib.baseboard_fab2(sch_1):page193_i45:ioe5" )
			)
			( pin "J4E1.E6"
				( objectStatus "@baseboard_fab2_lib.baseboard_fab2(sch_1):page193_i45:ioe6" )
			)
			( pin "J4E1.E7"
				( objectStatus "@baseboard_fab2_lib.baseboard_fab2(sch_1):page193_i45:ioe7" )
			)
			( pin "J4E1.E8"
				( objectStatus "@baseboard_fab2_lib.baseboard_fab2(sch_1):page193_i45:ioe8" )
			)
			( pin "J4E1.E9"
				( objectStatus "@baseboard_fab2_lib.baseboard_fab2(sch_1):page193_i45:ioe9" )
			)
			( pin "J4E1.E10"
				( objectStatus "@baseboard_fab2_lib.baseboard_fab2(sch_1):page193_i45:ioe10" )
			)
			( pin "J4E1.E11"
				( objectStatus "@baseboard_fab2_lib.baseboard_fab2(sch_1):page193_i45:ioe11" )
			)
			( pin "J4E1.E12"
				( objectStatus "@baseboard_fab2_lib.baseboard_fab2(sch_1):page193_i45:ioe12" )
			)
			( pin "J4E1.E13"
				( objectStatus "@baseboard_fab2_lib.baseboard_fab2(sch_1):page193_i45:ioe13" )
			)
			( pin "J4E1.E14"
				( objectStatus "@baseboard_fab2_lib.baseboard_fab2(sch_1):page193_i45:ioe14" )
			)
			( pin "J4E1.E15"
				( objectStatus "@baseboard_fab2_lib.baseboard_fab2(sch_1):page193_i45:ioe15" )
			)
			( pin "J4E1.E16"
				( objectStatus "@baseboard_fab2_lib.baseboard_fab2(sch_1):page193_i45:ioe16" )
			)
			( pin "J4E1.E17"
				( objectStatus "@baseboard_fab2_lib.baseboard_fab2(sch_1):page193_i45:ioe17" )
			)
			( pin "J4E1.E18"
				( objectStatus "@baseboard_fab2_lib.baseboard_fab2(sch_1):page193_i45:ioe18" )
			)
			( pin "J4E1.E19"
				( objectStatus "@baseboard_fab2_lib.baseboard_fab2(sch_1):page193_i45:ioe19" )
			)
			( pin "J4E1.E20"
				( objectStatus "@baseboard_fab2_lib.baseboard_fab2(sch_1):page193_i45:ioe20" )
			)
			( pin "J4E1.F1"
				( objectStatus "@baseboard_fab2_lib.baseboard_fab2(sch_1):page193_i45:iof1" )
			)
			( pin "J4E1.F2"
				( objectStatus "@baseboard_fab2_lib.baseboard_fab2(sch_1):page193_i45:iof2" )
			)
			( pin "J4E1.F3"
				( objectStatus "@baseboard_fab2_lib.baseboard_fab2(sch_1):page193_i45:iof3" )
			)
			( pin "J4E1.F4"
				( objectStatus "@baseboard_fab2_lib.baseboard_fab2(sch_1):page193_i45:iof4" )
			)
			( pin "J4E1.F5"
				( objectStatus "@baseboard_fab2_lib.baseboard_fab2(sch_1):page193_i45:iof5" )
			)
			( pin "J4E1.F6"
				( objectStatus "@baseboard_fab2_lib.baseboard_fab2(sch_1):page193_i45:iof6" )
			)
			( pin "J4E1.F7"
				( objectStatus "@baseboard_fab2_lib.baseboard_fab2(sch_1):page193_i45:iof7" )
			)
			( pin "J4E1.F8"
				( objectStatus "@baseboard_fab2_lib.baseboard_fab2(sch_1):page193_i45:iof8" )
			)
			( pin "J4E1.F9"
				( objectStatus "@baseboard_fab2_lib.baseboard_fab2(sch_1):page193_i45:iof9" )
			)
			( pin "J4E1.F10"
				( objectStatus "@baseboard_fab2_lib.baseboard_fab2(sch_1):page193_i45:iof10" )
			)
			( pin "J4E1.F11"
				( objectStatus "@baseboard_fab2_lib.baseboard_fab2(sch_1):page193_i45:iof11" )
			)
			( pin "J4E1.F12"
				( objectStatus "@baseboard_fab2_lib.baseboard_fab2(sch_1):page193_i45:iof12" )
			)
			( pin "J4E1.F13"
				( objectStatus "@baseboard_fab2_lib.baseboard_fab2(sch_1):page193_i45:iof13" )
			)
			( pin "J4E1.F14"
				( objectStatus "@baseboard_fab2_lib.baseboard_fab2(sch_1):page193_i45:iof14" )
			)
			( pin "J4E1.F15"
				( objectStatus "@baseboard_fab2_lib.baseboard_fab2(sch_1):page193_i45:iof15" )
			)
			( pin "J4E1.F16"
				( objectStatus "@baseboard_fab2_lib.baseboard_fab2(sch_1):page193_i45:iof16" )
			)
			( pin "J4E1.F17"
				( objectStatus "@baseboard_fab2_lib.baseboard_fab2(sch_1):page193_i45:iof17" )
			)
			( pin "J4E1.F18"
				( objectStatus "@baseboard_fab2_lib.baseboard_fab2(sch_1):page193_i45:iof18" )
			)
			( pin "J4E1.F19"
				( objectStatus "@baseboard_fab2_lib.baseboard_fab2(sch_1):page193_i45:iof19" )
			)
			( pin "J4E1.F20"
				( objectStatus "@baseboard_fab2_lib.baseboard_fab2(sch_1):page193_i45:iof20" )
			)
			( pin "J4B2.A1"
				( objectStatus "@baseboard_fab2_lib.baseboard_fab2(sch_1):page193_i46:ioa1" )
			)
			( pin "J4B2.A2"
				( objectStatus "@baseboard_fab2_lib.baseboard_fab2(sch_1):page193_i46:ioa2" )
			)
			( pin "J4B2.A3"
				( objectStatus "@baseboard_fab2_lib.baseboard_fab2(sch_1):page193_i46:ioa3" )
			)
			( pin "J4B2.A4"
				( objectStatus "@baseboard_fab2_lib.baseboard_fab2(sch_1):page193_i46:ioa4" )
			)
			( pin "J4B2.A5"
				( objectStatus "@baseboard_fab2_lib.baseboard_fab2(sch_1):page193_i46:ioa5" )
			)
			( pin "J4B2.A6"
				( objectStatus "@baseboard_fab2_lib.baseboard_fab2(sch_1):page193_i46:ioa6" )
			)
			( pin "J4B2.A7"
				( objectStatus "@baseboard_fab2_lib.baseboard_fab2(sch_1):page193_i46:ioa7" )
			)
			( pin "J4B2.A8"
				( objectStatus "@baseboard_fab2_lib.baseboard_fab2(sch_1):page193_i46:ioa8" )
			)
			( pin "J4B2.A9"
				( objectStatus "@baseboard_fab2_lib.baseboard_fab2(sch_1):page193_i46:ioa9" )
			)
			( pin "J4B2.A10"
				( objectStatus "@baseboard_fab2_lib.baseboard_fab2(sch_1):page193_i46:ioa10" )
			)
			( pin "J4B2.A11"
				( objectStatus "@baseboard_fab2_lib.baseboard_fab2(sch_1):page193_i46:ioa11" )
			)
			( pin "J4B2.A12"
				( objectStatus "@baseboard_fab2_lib.baseboard_fab2(sch_1):page193_i46:ioa12" )
			)
			( pin "J4B2.A13"
				( objectStatus "@baseboard_fab2_lib.baseboard_fab2(sch_1):page193_i46:ioa13" )
			)
			( pin "J4B2.A14"
				( objectStatus "@baseboard_fab2_lib.baseboard_fab2(sch_1):page193_i46:ioa14" )
			)
			( pin "J4B2.A15"
				( objectStatus "@baseboard_fab2_lib.baseboard_fab2(sch_1):page193_i46:ioa15" )
			)
			( pin "J4B2.A16"
				( objectStatus "@baseboard_fab2_lib.baseboard_fab2(sch_1):page193_i46:ioa16" )
			)
			( pin "J4B2.A17"
				( objectStatus "@baseboard_fab2_lib.baseboard_fab2(sch_1):page193_i46:ioa17" )
			)
			( pin "J4B2.A18"
				( objectStatus "@baseboard_fab2_lib.baseboard_fab2(sch_1):page193_i46:ioa18" )
			)
			( pin "J4B2.A19"
				( objectStatus "@baseboard_fab2_lib.baseboard_fab2(sch_1):page193_i46:ioa19" )
			)
			( pin "J4B2.A20"
				( objectStatus "@baseboard_fab2_lib.baseboard_fab2(sch_1):page193_i46:ioa20" )
			)
			( pin "J4B2.B1"
				( objectStatus "@baseboard_fab2_lib.baseboard_fab2(sch_1):page193_i46:iob1" )
			)
			( pin "J4B2.B2"
				( objectStatus "@baseboard_fab2_lib.baseboard_fab2(sch_1):page193_i46:iob2" )
			)
			( pin "J4B2.B3"
				( objectStatus "@baseboard_fab2_lib.baseboard_fab2(sch_1):page193_i46:iob3" )
			)
			( pin "J4B2.B4"
				( objectStatus "@baseboard_fab2_lib.baseboard_fab2(sch_1):page193_i46:iob4" )
			)
			( pin "J4B2.B5"
				( objectStatus "@baseboard_fab2_lib.baseboard_fab2(sch_1):page193_i46:iob5" )
			)
			( pin "J4B2.B6"
				( objectStatus "@baseboard_fab2_lib.baseboard_fab2(sch_1):page193_i46:iob6" )
			)
			( pin "J4B2.B7"
				( objectStatus "@baseboard_fab2_lib.baseboard_fab2(sch_1):page193_i46:iob7" )
			)
			( pin "J4B2.B8"
				( objectStatus "@baseboard_fab2_lib.baseboard_fab2(sch_1):page193_i46:iob8" )
			)
			( pin "J4B2.B9"
				( objectStatus "@baseboard_fab2_lib.baseboard_fab2(sch_1):page193_i46:iob9" )
			)
			( pin "J4B2.B10"
				( objectStatus "@baseboard_fab2_lib.baseboard_fab2(sch_1):page193_i46:iob10" )
			)
			( pin "J4B2.B11"
				( objectStatus "@baseboard_fab2_lib.baseboard_fab2(sch_1):page193_i46:iob11" )
			)
			( pin "J4B2.B12"
				( objectStatus "@baseboard_fab2_lib.baseboard_fab2(sch_1):page193_i46:iob12" )
			)
			( pin "J4B2.B13"
				( objectStatus "@baseboard_fab2_lib.baseboard_fab2(sch_1):page193_i46:iob13" )
			)
			( pin "J4B2.B14"
				( objectStatus "@baseboard_fab2_lib.baseboard_fab2(sch_1):page193_i46:iob14" )
			)
			( pin "J4B2.B15"
				( objectStatus "@baseboard_fab2_lib.baseboard_fab2(sch_1):page193_i46:iob15" )
			)
			( pin "J4B2.B16"
				( objectStatus "@baseboard_fab2_lib.baseboard_fab2(sch_1):page193_i46:iob16" )
			)
			( pin "J4B2.B17"
				( objectStatus "@baseboard_fab2_lib.baseboard_fab2(sch_1):page193_i46:iob17" )
			)
			( pin "J4B2.B18"
				( objectStatus "@baseboard_fab2_lib.baseboard_fab2(sch_1):page193_i46:iob18" )
			)
			( pin "J4B2.B19"
				( objectStatus "@baseboard_fab2_lib.baseboard_fab2(sch_1):page193_i46:iob19" )
			)
			( pin "J4B2.B20"
				( objectStatus "@baseboard_fab2_lib.baseboard_fab2(sch_1):page193_i46:iob20" )
			)
			( pin "J4B2.C1"
				( objectStatus "@baseboard_fab2_lib.baseboard_fab2(sch_1):page193_i46:ioc1" )
			)
			( pin "J4B2.C2"
				( objectStatus "@baseboard_fab2_lib.baseboard_fab2(sch_1):page193_i46:ioc2" )
			)
			( pin "J4B2.C3"
				( objectStatus "@baseboard_fab2_lib.baseboard_fab2(sch_1):page193_i46:ioc3" )
			)
			( pin "J4B2.C4"
				( objectStatus "@baseboard_fab2_lib.baseboard_fab2(sch_1):page193_i46:ioc4" )
			)
			( pin "J4B2.C5"
				( objectStatus "@baseboard_fab2_lib.baseboard_fab2(sch_1):page193_i46:ioc5" )
			)
			( pin "J4B2.C6"
				( objectStatus "@baseboard_fab2_lib.baseboard_fab2(sch_1):page193_i46:ioc6" )
			)
			( pin "J4B2.C7"
				( objectStatus "@baseboard_fab2_lib.baseboard_fab2(sch_1):page193_i46:ioc7" )
			)
			( pin "J4B2.C8"
				( objectStatus "@baseboard_fab2_lib.baseboard_fab2(sch_1):page193_i46:ioc8" )
			)
			( pin "J4B2.C9"
				( objectStatus "@baseboard_fab2_lib.baseboard_fab2(sch_1):page193_i46:ioc9" )
			)
			( pin "J4B2.C10"
				( objectStatus "@baseboard_fab2_lib.baseboard_fab2(sch_1):page193_i46:ioc10" )
			)
			( pin "J4B2.C11"
				( objectStatus "@baseboard_fab2_lib.baseboard_fab2(sch_1):page193_i46:ioc11" )
			)
			( pin "J4B2.C12"
				( objectStatus "@baseboard_fab2_lib.baseboard_fab2(sch_1):page193_i46:ioc12" )
			)
			( pin "J4B2.C13"
				( objectStatus "@baseboard_fab2_lib.baseboard_fab2(sch_1):page193_i46:ioc13" )
			)
			( pin "J4B2.C14"
				( objectStatus "@baseboard_fab2_lib.baseboard_fab2(sch_1):page193_i46:ioc14" )
			)
			( pin "J4B2.C15"
				( objectStatus "@baseboard_fab2_lib.baseboard_fab2(sch_1):page193_i46:ioc15" )
			)
			( pin "J4B2.C16"
				( objectStatus "@baseboard_fab2_lib.baseboard_fab2(sch_1):page193_i46:ioc16" )
			)
			( pin "J4B2.C17"
				( objectStatus "@baseboard_fab2_lib.baseboard_fab2(sch_1):page193_i46:ioc17" )
			)
			( pin "J4B2.C18"
				( objectStatus "@baseboard_fab2_lib.baseboard_fab2(sch_1):page193_i46:ioc18" )
			)
			( pin "J4B2.C19"
				( objectStatus "@baseboard_fab2_lib.baseboard_fab2(sch_1):page193_i46:ioc19" )
			)
			( pin "J4B2.C20"
				( objectStatus "@baseboard_fab2_lib.baseboard_fab2(sch_1):page193_i46:ioc20" )
			)
			( pin "J4B2.D1"
				( objectStatus "@baseboard_fab2_lib.baseboard_fab2(sch_1):page193_i46:iod1" )
			)
			( pin "J4B2.D2"
				( objectStatus "@baseboard_fab2_lib.baseboard_fab2(sch_1):page193_i46:iod2" )
			)
			( pin "J4B2.D3"
				( objectStatus "@baseboard_fab2_lib.baseboard_fab2(sch_1):page193_i46:iod3" )
			)
			( pin "J4B2.D4"
				( objectStatus "@baseboard_fab2_lib.baseboard_fab2(sch_1):page193_i46:iod4" )
			)
			( pin "J4B2.D5"
				( objectStatus "@baseboard_fab2_lib.baseboard_fab2(sch_1):page193_i46:iod5" )
			)
			( pin "J4B2.D6"
				( objectStatus "@baseboard_fab2_lib.baseboard_fab2(sch_1):page193_i46:iod6" )
			)
			( pin "J4B2.D7"
				( objectStatus "@baseboard_fab2_lib.baseboard_fab2(sch_1):page193_i46:iod7" )
			)
			( pin "J4B2.D8"
				( objectStatus "@baseboard_fab2_lib.baseboard_fab2(sch_1):page193_i46:iod8" )
			)
			( pin "J4B2.D9"
				( objectStatus "@baseboard_fab2_lib.baseboard_fab2(sch_1):page193_i46:iod9" )
			)
			( pin "J4B2.D10"
				( objectStatus "@baseboard_fab2_lib.baseboard_fab2(sch_1):page193_i46:iod10" )
			)
			( pin "J4B2.D11"
				( objectStatus "@baseboard_fab2_lib.baseboard_fab2(sch_1):page193_i46:iod11" )
			)
			( pin "J4B2.D12"
				( objectStatus "@baseboard_fab2_lib.baseboard_fab2(sch_1):page193_i46:iod12" )
			)
			( pin "J4B2.D13"
				( objectStatus "@baseboard_fab2_lib.baseboard_fab2(sch_1):page193_i46:iod13" )
			)
			( pin "J4B2.D14"
				( objectStatus "@baseboard_fab2_lib.baseboard_fab2(sch_1):page193_i46:iod14" )
			)
			( pin "J4B2.D15"
				( objectStatus "@baseboard_fab2_lib.baseboard_fab2(sch_1):page193_i46:iod15" )
			)
			( pin "J4B2.D16"
				( objectStatus "@baseboard_fab2_lib.baseboard_fab2(sch_1):page193_i46:iod16" )
			)
			( pin "J4B2.D17"
				( objectStatus "@baseboard_fab2_lib.baseboard_fab2(sch_1):page193_i46:iod17" )
			)
			( pin "J4B2.D18"
				( objectStatus "@baseboard_fab2_lib.baseboard_fab2(sch_1):page193_i46:iod18" )
			)
			( pin "J4B2.D19"
				( objectStatus "@baseboard_fab2_lib.baseboard_fab2(sch_1):page193_i46:iod19" )
			)
			( pin "J4B2.D20"
				( objectStatus "@baseboard_fab2_lib.baseboard_fab2(sch_1):page193_i46:iod20" )
			)
			( pin "J4B2.E1"
				( objectStatus "@baseboard_fab2_lib.baseboard_fab2(sch_1):page193_i46:ioe1" )
			)
			( pin "J4B2.E2"
				( objectStatus "@baseboard_fab2_lib.baseboard_fab2(sch_1):page193_i46:ioe2" )
			)
			( pin "J4B2.E3"
				( objectStatus "@baseboard_fab2_lib.baseboard_fab2(sch_1):page193_i46:ioe3" )
			)
			( pin "J4B2.E4"
				( objectStatus "@baseboard_fab2_lib.baseboard_fab2(sch_1):page193_i46:ioe4" )
			)
			( pin "J4B2.E5"
				( objectStatus "@baseboard_fab2_lib.baseboard_fab2(sch_1):page193_i46:ioe5" )
			)
			( pin "J4B2.E6"
				( objectStatus "@baseboard_fab2_lib.baseboard_fab2(sch_1):page193_i46:ioe6" )
			)
			( pin "J4B2.E7"
				( objectStatus "@baseboard_fab2_lib.baseboard_fab2(sch_1):page193_i46:ioe7" )
			)
			( pin "J4B2.E8"
				( objectStatus "@baseboard_fab2_lib.baseboard_fab2(sch_1):page193_i46:ioe8" )
			)
			( pin "J4B2.E9"
				( objectStatus "@baseboard_fab2_lib.baseboard_fab2(sch_1):page193_i46:ioe9" )
			)
			( pin "J4B2.E10"
				( objectStatus "@baseboard_fab2_lib.baseboard_fab2(sch_1):page193_i46:ioe10" )
			)
			( pin "J4B2.E11"
				( objectStatus "@baseboard_fab2_lib.baseboard_fab2(sch_1):page193_i46:ioe11" )
			)
			( pin "J4B2.E12"
				( objectStatus "@baseboard_fab2_lib.baseboard_fab2(sch_1):page193_i46:ioe12" )
			)
			( pin "J4B2.E13"
				( objectStatus "@baseboard_fab2_lib.baseboard_fab2(sch_1):page193_i46:ioe13" )
			)
			( pin "J4B2.E14"
				( objectStatus "@baseboard_fab2_lib.baseboard_fab2(sch_1):page193_i46:ioe14" )
			)
			( pin "J4B2.E15"
				( objectStatus "@baseboard_fab2_lib.baseboard_fab2(sch_1):page193_i46:ioe15" )
			)
			( pin "J4B2.E16"
				( objectStatus "@baseboard_fab2_lib.baseboard_fab2(sch_1):page193_i46:ioe16" )
			)
			( pin "J4B2.E17"
				( objectStatus "@baseboard_fab2_lib.baseboard_fab2(sch_1):page193_i46:ioe17" )
			)
			( pin "J4B2.E18"
				( objectStatus "@baseboard_fab2_lib.baseboard_fab2(sch_1):page193_i46:ioe18" )
			)
			( pin "J4B2.E19"
				( objectStatus "@baseboard_fab2_lib.baseboard_fab2(sch_1):page193_i46:ioe19" )
			)
			( pin "J4B2.E20"
				( objectStatus "@baseboard_fab2_lib.baseboard_fab2(sch_1):page193_i46:ioe20" )
			)
			( pin "J4B2.F1"
				( objectStatus "@baseboard_fab2_lib.baseboard_fab2(sch_1):page193_i46:iof1" )
			)
			( pin "J4B2.F2"
				( objectStatus "@baseboard_fab2_lib.baseboard_fab2(sch_1):page193_i46:iof2" )
			)
			( pin "J4B2.F3"
				( objectStatus "@baseboard_fab2_lib.baseboard_fab2(sch_1):page193_i46:iof3" )
			)
			( pin "J4B2.F4"
				( objectStatus "@baseboard_fab2_lib.baseboard_fab2(sch_1):page193_i46:iof4" )
			)
			( pin "J4B2.F5"
				( objectStatus "@baseboard_fab2_lib.baseboard_fab2(sch_1):page193_i46:iof5" )
			)
			( pin "J4B2.F6"
				( objectStatus "@baseboard_fab2_lib.baseboard_fab2(sch_1):page193_i46:iof6" )
			)
			( pin "J4B2.F7"
				( objectStatus "@baseboard_fab2_lib.baseboard_fab2(sch_1):page193_i46:iof7" )
			)
			( pin "J4B2.F8"
				( objectStatus "@baseboard_fab2_lib.baseboard_fab2(sch_1):page193_i46:iof8" )
			)
			( pin "J4B2.F9"
				( objectStatus "@baseboard_fab2_lib.baseboard_fab2(sch_1):page193_i46:iof9" )
			)
			( pin "J4B2.F10"
				( objectStatus "@baseboard_fab2_lib.baseboard_fab2(sch_1):page193_i46:iof10" )
			)
			( pin "J4B2.F11"
				( objectStatus "@baseboard_fab2_lib.baseboard_fab2(sch_1):page193_i46:iof11" )
			)
			( pin "J4B2.F12"
				( objectStatus "@baseboard_fab2_lib.baseboard_fab2(sch_1):page193_i46:iof12" )
			)
			( pin "J4B2.F13"
				( objectStatus "@baseboard_fab2_lib.baseboard_fab2(sch_1):page193_i46:iof13" )
			)
			( pin "J4B2.F14"
				( objectStatus "@baseboard_fab2_lib.baseboard_fab2(sch_1):page193_i46:iof14" )
			)
			( pin "J4B2.F15"
				( objectStatus "@baseboard_fab2_lib.baseboard_fab2(sch_1):page193_i46:iof15" )
			)
			( pin "J4B2.F16"
				( objectStatus "@baseboard_fab2_lib.baseboard_fab2(sch_1):page193_i46:iof16" )
			)
			( pin "J4B2.F17"
				( objectStatus "@baseboard_fab2_lib.baseboard_fab2(sch_1):page193_i46:iof17" )
			)
			( pin "J4B2.F18"
				( objectStatus "@baseboard_fab2_lib.baseboard_fab2(sch_1):page193_i46:iof18" )
			)
			( pin "J4B2.F19"
				( objectStatus "@baseboard_fab2_lib.baseboard_fab2(sch_1):page193_i46:iof19" )
			)
			( pin "J4B2.F20"
				( objectStatus "@baseboard_fab2_lib.baseboard_fab2(sch_1):page193_i46:iof20" )
			)
			( pin "C4E24.1"
				( objectStatus "@baseboard_fab2_lib.baseboard_fab2(sch_1):page193_i61:a" )
			)
			( pin "C4E24.2"
				( objectStatus "@baseboard_fab2_lib.baseboard_fab2(sch_1):page193_i61:b" )
			)
			( pin "C6R16.1"
				( objectStatus "@baseboard_fab2_lib.baseboard_fab2(sch_1):page193_i62:a" )
			)
			( pin "C6R16.2"
				( objectStatus "@baseboard_fab2_lib.baseboard_fab2(sch_1):page193_i62:b" )
			)
			( pin "C4F1.1"
				( objectStatus "@baseboard_fab2_lib.baseboard_fab2(sch_1):page193_i68:a" )
			)
			( pin "C4F1.2"
				( objectStatus "@baseboard_fab2_lib.baseboard_fab2(sch_1):page193_i68:b" )
			)
			( pin "C4F3.1"
				( objectStatus "@baseboard_fab2_lib.baseboard_fab2(sch_1):page193_i70:a" )
			)
			( pin "C4F3.2"
				( objectStatus "@baseboard_fab2_lib.baseboard_fab2(sch_1):page193_i70:b" )
			)
			( pin "C3F1.1"
				( objectStatus "@baseboard_fab2_lib.baseboard_fab2(sch_1):page193_i140:a" )
			)
			( pin "C3F1.2"
				( objectStatus "@baseboard_fab2_lib.baseboard_fab2(sch_1):page193_i140:b" )
			)
			( pin "C4F2.1"
				( objectStatus "@baseboard_fab2_lib.baseboard_fab2(sch_1):page193_i141:a" )
			)
			( pin "C4F2.2"
				( objectStatus "@baseboard_fab2_lib.baseboard_fab2(sch_1):page193_i141:b" )
			)
			( pin "R4C12.1"
				( objectStatus "@baseboard_fab2_lib.baseboard_fab2(sch_1):page193_i169:a" )
			)
			( pin "R4C12.2"
				( objectStatus "@baseboard_fab2_lib.baseboard_fab2(sch_1):page193_i169:b" )
			)
			( pin "R4C11.1"
				( objectStatus "@baseboard_fab2_lib.baseboard_fab2(sch_1):page193_i170:a" )
			)
			( pin "R4C11.2"
				( objectStatus "@baseboard_fab2_lib.baseboard_fab2(sch_1):page193_i170:b" )
			)
			( pin "C4T2.1"
				( objectStatus "@baseboard_fab2_lib.baseboard_fab2(sch_1):page194_i9:a" )
			)
			( pin "C4T2.2"
				( objectStatus "@baseboard_fab2_lib.baseboard_fab2(sch_1):page194_i9:b" )
			)
			( pin "C4T1.1"
				( objectStatus "@baseboard_fab2_lib.baseboard_fab2(sch_1):page194_i16:a" )
			)
			( pin "C4T1.2"
				( objectStatus "@baseboard_fab2_lib.baseboard_fab2(sch_1):page194_i16:b" )
			)
			( pin "C4R1.1"
				( objectStatus "@baseboard_fab2_lib.baseboard_fab2(sch_1):page194_i29:a" )
			)
			( pin "C4R1.2"
				( objectStatus "@baseboard_fab2_lib.baseboard_fab2(sch_1):page194_i29:b" )
			)
			( pin "C3R4.1"
				( objectStatus "@baseboard_fab2_lib.baseboard_fab2(sch_1):page194_i31:a" )
			)
			( pin "C3R4.2"
				( objectStatus "@baseboard_fab2_lib.baseboard_fab2(sch_1):page194_i31:b" )
			)
			( pin "J6E1.A1"
				( objectStatus "@baseboard_fab2_lib.baseboard_fab2(sch_1):page194_i55:ioa1" )
			)
			( pin "J6E1.A2"
				( objectStatus "@baseboard_fab2_lib.baseboard_fab2(sch_1):page194_i55:ioa2" )
			)
			( pin "J6E1.A3"
				( objectStatus "@baseboard_fab2_lib.baseboard_fab2(sch_1):page194_i55:ioa3" )
			)
			( pin "J6E1.A4"
				( objectStatus "@baseboard_fab2_lib.baseboard_fab2(sch_1):page194_i55:ioa4" )
			)
			( pin "J6E1.A5"
				( objectStatus "@baseboard_fab2_lib.baseboard_fab2(sch_1):page194_i55:ioa5" )
			)
			( pin "J6E1.A6"
				( objectStatus "@baseboard_fab2_lib.baseboard_fab2(sch_1):page194_i55:ioa6" )
			)
			( pin "J6E1.A7"
				( objectStatus "@baseboard_fab2_lib.baseboard_fab2(sch_1):page194_i55:ioa7" )
			)
			( pin "J6E1.A8"
				( objectStatus "@baseboard_fab2_lib.baseboard_fab2(sch_1):page194_i55:ioa8" )
			)
			( pin "J6E1.A9"
				( objectStatus "@baseboard_fab2_lib.baseboard_fab2(sch_1):page194_i55:ioa9" )
			)
			( pin "J6E1.A10"
				( objectStatus "@baseboard_fab2_lib.baseboard_fab2(sch_1):page194_i55:ioa10" )
			)
			( pin "J6E1.A11"
				( objectStatus "@baseboard_fab2_lib.baseboard_fab2(sch_1):page194_i55:ioa11" )
			)
			( pin "J6E1.A12"
				( objectStatus "@baseboard_fab2_lib.baseboard_fab2(sch_1):page194_i55:ioa12" )
			)
			( pin "J6E1.A13"
				( objectStatus "@baseboard_fab2_lib.baseboard_fab2(sch_1):page194_i55:ioa13" )
			)
			( pin "J6E1.A14"
				( objectStatus "@baseboard_fab2_lib.baseboard_fab2(sch_1):page194_i55:ioa14" )
			)
			( pin "J6E1.A15"
				( objectStatus "@baseboard_fab2_lib.baseboard_fab2(sch_1):page194_i55:ioa15" )
			)
			( pin "J6E1.A16"
				( objectStatus "@baseboard_fab2_lib.baseboard_fab2(sch_1):page194_i55:ioa16" )
			)
			( pin "J6E1.A17"
				( objectStatus "@baseboard_fab2_lib.baseboard_fab2(sch_1):page194_i55:ioa17" )
			)
			( pin "J6E1.A18"
				( objectStatus "@baseboard_fab2_lib.baseboard_fab2(sch_1):page194_i55:ioa18" )
			)
			( pin "J6E1.A19"
				( objectStatus "@baseboard_fab2_lib.baseboard_fab2(sch_1):page194_i55:ioa19" )
			)
			( pin "J6E1.A20"
				( objectStatus "@baseboard_fab2_lib.baseboard_fab2(sch_1):page194_i55:ioa20" )
			)
			( pin "J6E1.B1"
				( objectStatus "@baseboard_fab2_lib.baseboard_fab2(sch_1):page194_i55:iob1" )
			)
			( pin "J6E1.B2"
				( objectStatus "@baseboard_fab2_lib.baseboard_fab2(sch_1):page194_i55:iob2" )
			)
			( pin "J6E1.B3"
				( objectStatus "@baseboard_fab2_lib.baseboard_fab2(sch_1):page194_i55:iob3" )
			)
			( pin "J6E1.B4"
				( objectStatus "@baseboard_fab2_lib.baseboard_fab2(sch_1):page194_i55:iob4" )
			)
			( pin "J6E1.B5"
				( objectStatus "@baseboard_fab2_lib.baseboard_fab2(sch_1):page194_i55:iob5" )
			)
			( pin "J6E1.B6"
				( objectStatus "@baseboard_fab2_lib.baseboard_fab2(sch_1):page194_i55:iob6" )
			)
			( pin "J6E1.B7"
				( objectStatus "@baseboard_fab2_lib.baseboard_fab2(sch_1):page194_i55:iob7" )
			)
			( pin "J6E1.B8"
				( objectStatus "@baseboard_fab2_lib.baseboard_fab2(sch_1):page194_i55:iob8" )
			)
			( pin "J6E1.B9"
				( objectStatus "@baseboard_fab2_lib.baseboard_fab2(sch_1):page194_i55:iob9" )
			)
			( pin "J6E1.B10"
				( objectStatus "@baseboard_fab2_lib.baseboard_fab2(sch_1):page194_i55:iob10" )
			)
			( pin "J6E1.B11"
				( objectStatus "@baseboard_fab2_lib.baseboard_fab2(sch_1):page194_i55:iob11" )
			)
			( pin "J6E1.B12"
				( objectStatus "@baseboard_fab2_lib.baseboard_fab2(sch_1):page194_i55:iob12" )
			)
			( pin "J6E1.B13"
				( objectStatus "@baseboard_fab2_lib.baseboard_fab2(sch_1):page194_i55:iob13" )
			)
			( pin "J6E1.B14"
				( objectStatus "@baseboard_fab2_lib.baseboard_fab2(sch_1):page194_i55:iob14" )
			)
			( pin "J6E1.B15"
				( objectStatus "@baseboard_fab2_lib.baseboard_fab2(sch_1):page194_i55:iob15" )
			)
			( pin "J6E1.B16"
				( objectStatus "@baseboard_fab2_lib.baseboard_fab2(sch_1):page194_i55:iob16" )
			)
			( pin "J6E1.B17"
				( objectStatus "@baseboard_fab2_lib.baseboard_fab2(sch_1):page194_i55:iob17" )
			)
			( pin "J6E1.B18"
				( objectStatus "@baseboard_fab2_lib.baseboard_fab2(sch_1):page194_i55:iob18" )
			)
			( pin "J6E1.B19"
				( objectStatus "@baseboard_fab2_lib.baseboard_fab2(sch_1):page194_i55:iob19" )
			)
			( pin "J6E1.B20"
				( objectStatus "@baseboard_fab2_lib.baseboard_fab2(sch_1):page194_i55:iob20" )
			)
			( pin "J6E1.C1"
				( objectStatus "@baseboard_fab2_lib.baseboard_fab2(sch_1):page194_i55:ioc1" )
			)
			( pin "J6E1.C2"
				( objectStatus "@baseboard_fab2_lib.baseboard_fab2(sch_1):page194_i55:ioc2" )
			)
			( pin "J6E1.C3"
				( objectStatus "@baseboard_fab2_lib.baseboard_fab2(sch_1):page194_i55:ioc3" )
			)
			( pin "J6E1.C4"
				( objectStatus "@baseboard_fab2_lib.baseboard_fab2(sch_1):page194_i55:ioc4" )
			)
			( pin "J6E1.C5"
				( objectStatus "@baseboard_fab2_lib.baseboard_fab2(sch_1):page194_i55:ioc5" )
			)
			( pin "J6E1.C6"
				( objectStatus "@baseboard_fab2_lib.baseboard_fab2(sch_1):page194_i55:ioc6" )
			)
			( pin "J6E1.C7"
				( objectStatus "@baseboard_fab2_lib.baseboard_fab2(sch_1):page194_i55:ioc7" )
			)
			( pin "J6E1.C8"
				( objectStatus "@baseboard_fab2_lib.baseboard_fab2(sch_1):page194_i55:ioc8" )
			)
			( pin "J6E1.C9"
				( objectStatus "@baseboard_fab2_lib.baseboard_fab2(sch_1):page194_i55:ioc9" )
			)
			( pin "J6E1.C10"
				( objectStatus "@baseboard_fab2_lib.baseboard_fab2(sch_1):page194_i55:ioc10" )
			)
			( pin "J6E1.C11"
				( objectStatus "@baseboard_fab2_lib.baseboard_fab2(sch_1):page194_i55:ioc11" )
			)
			( pin "J6E1.C12"
				( objectStatus "@baseboard_fab2_lib.baseboard_fab2(sch_1):page194_i55:ioc12" )
			)
			( pin "J6E1.C13"
				( objectStatus "@baseboard_fab2_lib.baseboard_fab2(sch_1):page194_i55:ioc13" )
			)
			( pin "J6E1.C14"
				( objectStatus "@baseboard_fab2_lib.baseboard_fab2(sch_1):page194_i55:ioc14" )
			)
			( pin "J6E1.C15"
				( objectStatus "@baseboard_fab2_lib.baseboard_fab2(sch_1):page194_i55:ioc15" )
			)
			( pin "J6E1.C16"
				( objectStatus "@baseboard_fab2_lib.baseboard_fab2(sch_1):page194_i55:ioc16" )
			)
			( pin "J6E1.C17"
				( objectStatus "@baseboard_fab2_lib.baseboard_fab2(sch_1):page194_i55:ioc17" )
			)
			( pin "J6E1.C18"
				( objectStatus "@baseboard_fab2_lib.baseboard_fab2(sch_1):page194_i55:ioc18" )
			)
			( pin "J6E1.C19"
				( objectStatus "@baseboard_fab2_lib.baseboard_fab2(sch_1):page194_i55:ioc19" )
			)
			( pin "J6E1.C20"
				( objectStatus "@baseboard_fab2_lib.baseboard_fab2(sch_1):page194_i55:ioc20" )
			)
			( pin "J6E1.D1"
				( objectStatus "@baseboard_fab2_lib.baseboard_fab2(sch_1):page194_i55:iod1" )
			)
			( pin "J6E1.D2"
				( objectStatus "@baseboard_fab2_lib.baseboard_fab2(sch_1):page194_i55:iod2" )
			)
			( pin "J6E1.D3"
				( objectStatus "@baseboard_fab2_lib.baseboard_fab2(sch_1):page194_i55:iod3" )
			)
			( pin "J6E1.D4"
				( objectStatus "@baseboard_fab2_lib.baseboard_fab2(sch_1):page194_i55:iod4" )
			)
			( pin "J6E1.D5"
				( objectStatus "@baseboard_fab2_lib.baseboard_fab2(sch_1):page194_i55:iod5" )
			)
			( pin "J6E1.D6"
				( objectStatus "@baseboard_fab2_lib.baseboard_fab2(sch_1):page194_i55:iod6" )
			)
			( pin "J6E1.D7"
				( objectStatus "@baseboard_fab2_lib.baseboard_fab2(sch_1):page194_i55:iod7" )
			)
			( pin "J6E1.D8"
				( objectStatus "@baseboard_fab2_lib.baseboard_fab2(sch_1):page194_i55:iod8" )
			)
			( pin "J6E1.D9"
				( objectStatus "@baseboard_fab2_lib.baseboard_fab2(sch_1):page194_i55:iod9" )
			)
			( pin "J6E1.D10"
				( objectStatus "@baseboard_fab2_lib.baseboard_fab2(sch_1):page194_i55:iod10" )
			)
			( pin "J6E1.D11"
				( objectStatus "@baseboard_fab2_lib.baseboard_fab2(sch_1):page194_i55:iod11" )
			)
			( pin "J6E1.D12"
				( objectStatus "@baseboard_fab2_lib.baseboard_fab2(sch_1):page194_i55:iod12" )
			)
			( pin "J6E1.D13"
				( objectStatus "@baseboard_fab2_lib.baseboard_fab2(sch_1):page194_i55:iod13" )
			)
			( pin "J6E1.D14"
				( objectStatus "@baseboard_fab2_lib.baseboard_fab2(sch_1):page194_i55:iod14" )
			)
			( pin "J6E1.D15"
				( objectStatus "@baseboard_fab2_lib.baseboard_fab2(sch_1):page194_i55:iod15" )
			)
			( pin "J6E1.D16"
				( objectStatus "@baseboard_fab2_lib.baseboard_fab2(sch_1):page194_i55:iod16" )
			)
			( pin "J6E1.D17"
				( objectStatus "@baseboard_fab2_lib.baseboard_fab2(sch_1):page194_i55:iod17" )
			)
			( pin "J6E1.D18"
				( objectStatus "@baseboard_fab2_lib.baseboard_fab2(sch_1):page194_i55:iod18" )
			)
			( pin "J6E1.D19"
				( objectStatus "@baseboard_fab2_lib.baseboard_fab2(sch_1):page194_i55:iod19" )
			)
			( pin "J6E1.D20"
				( objectStatus "@baseboard_fab2_lib.baseboard_fab2(sch_1):page194_i55:iod20" )
			)
			( pin "J6E1.E1"
				( objectStatus "@baseboard_fab2_lib.baseboard_fab2(sch_1):page194_i55:ioe1" )
			)
			( pin "J6E1.E2"
				( objectStatus "@baseboard_fab2_lib.baseboard_fab2(sch_1):page194_i55:ioe2" )
			)
			( pin "J6E1.E3"
				( objectStatus "@baseboard_fab2_lib.baseboard_fab2(sch_1):page194_i55:ioe3" )
			)
			( pin "J6E1.E4"
				( objectStatus "@baseboard_fab2_lib.baseboard_fab2(sch_1):page194_i55:ioe4" )
			)
			( pin "J6E1.E5"
				( objectStatus "@baseboard_fab2_lib.baseboard_fab2(sch_1):page194_i55:ioe5" )
			)
			( pin "J6E1.E6"
				( objectStatus "@baseboard_fab2_lib.baseboard_fab2(sch_1):page194_i55:ioe6" )
			)
			( pin "J6E1.E7"
				( objectStatus "@baseboard_fab2_lib.baseboard_fab2(sch_1):page194_i55:ioe7" )
			)
			( pin "J6E1.E8"
				( objectStatus "@baseboard_fab2_lib.baseboard_fab2(sch_1):page194_i55:ioe8" )
			)
			( pin "J6E1.E9"
				( objectStatus "@baseboard_fab2_lib.baseboard_fab2(sch_1):page194_i55:ioe9" )
			)
			( pin "J6E1.E10"
				( objectStatus "@baseboard_fab2_lib.baseboard_fab2(sch_1):page194_i55:ioe10" )
			)
			( pin "J6E1.E11"
				( objectStatus "@baseboard_fab2_lib.baseboard_fab2(sch_1):page194_i55:ioe11" )
			)
			( pin "J6E1.E12"
				( objectStatus "@baseboard_fab2_lib.baseboard_fab2(sch_1):page194_i55:ioe12" )
			)
			( pin "J6E1.E13"
				( objectStatus "@baseboard_fab2_lib.baseboard_fab2(sch_1):page194_i55:ioe13" )
			)
			( pin "J6E1.E14"
				( objectStatus "@baseboard_fab2_lib.baseboard_fab2(sch_1):page194_i55:ioe14" )
			)
			( pin "J6E1.E15"
				( objectStatus "@baseboard_fab2_lib.baseboard_fab2(sch_1):page194_i55:ioe15" )
			)
			( pin "J6E1.E16"
				( objectStatus "@baseboard_fab2_lib.baseboard_fab2(sch_1):page194_i55:ioe16" )
			)
			( pin "J6E1.E17"
				( objectStatus "@baseboard_fab2_lib.baseboard_fab2(sch_1):page194_i55:ioe17" )
			)
			( pin "J6E1.E18"
				( objectStatus "@baseboard_fab2_lib.baseboard_fab2(sch_1):page194_i55:ioe18" )
			)
			( pin "J6E1.E19"
				( objectStatus "@baseboard_fab2_lib.baseboard_fab2(sch_1):page194_i55:ioe19" )
			)
			( pin "J6E1.E20"
				( objectStatus "@baseboard_fab2_lib.baseboard_fab2(sch_1):page194_i55:ioe20" )
			)
			( pin "J6E1.F1"
				( objectStatus "@baseboard_fab2_lib.baseboard_fab2(sch_1):page194_i55:iof1" )
			)
			( pin "J6E1.F2"
				( objectStatus "@baseboard_fab2_lib.baseboard_fab2(sch_1):page194_i55:iof2" )
			)
			( pin "J6E1.F3"
				( objectStatus "@baseboard_fab2_lib.baseboard_fab2(sch_1):page194_i55:iof3" )
			)
			( pin "J6E1.F4"
				( objectStatus "@baseboard_fab2_lib.baseboard_fab2(sch_1):page194_i55:iof4" )
			)
			( pin "J6E1.F5"
				( objectStatus "@baseboard_fab2_lib.baseboard_fab2(sch_1):page194_i55:iof5" )
			)
			( pin "J6E1.F6"
				( objectStatus "@baseboard_fab2_lib.baseboard_fab2(sch_1):page194_i55:iof6" )
			)
			( pin "J6E1.F7"
				( objectStatus "@baseboard_fab2_lib.baseboard_fab2(sch_1):page194_i55:iof7" )
			)
			( pin "J6E1.F8"
				( objectStatus "@baseboard_fab2_lib.baseboard_fab2(sch_1):page194_i55:iof8" )
			)
			( pin "J6E1.F9"
				( objectStatus "@baseboard_fab2_lib.baseboard_fab2(sch_1):page194_i55:iof9" )
			)
			( pin "J6E1.F10"
				( objectStatus "@baseboard_fab2_lib.baseboard_fab2(sch_1):page194_i55:iof10" )
			)
			( pin "J6E1.F11"
				( objectStatus "@baseboard_fab2_lib.baseboard_fab2(sch_1):page194_i55:iof11" )
			)
			( pin "J6E1.F12"
				( objectStatus "@baseboard_fab2_lib.baseboard_fab2(sch_1):page194_i55:iof12" )
			)
			( pin "J6E1.F13"
				( objectStatus "@baseboard_fab2_lib.baseboard_fab2(sch_1):page194_i55:iof13" )
			)
			( pin "J6E1.F14"
				( objectStatus "@baseboard_fab2_lib.baseboard_fab2(sch_1):page194_i55:iof14" )
			)
			( pin "J6E1.F15"
				( objectStatus "@baseboard_fab2_lib.baseboard_fab2(sch_1):page194_i55:iof15" )
			)
			( pin "J6E1.F16"
				( objectStatus "@baseboard_fab2_lib.baseboard_fab2(sch_1):page194_i55:iof16" )
			)
			( pin "J6E1.F17"
				( objectStatus "@baseboard_fab2_lib.baseboard_fab2(sch_1):page194_i55:iof17" )
			)
			( pin "J6E1.F18"
				( objectStatus "@baseboard_fab2_lib.baseboard_fab2(sch_1):page194_i55:iof18" )
			)
			( pin "J6E1.F19"
				( objectStatus "@baseboard_fab2_lib.baseboard_fab2(sch_1):page194_i55:iof19" )
			)
			( pin "J6E1.F20"
				( objectStatus "@baseboard_fab2_lib.baseboard_fab2(sch_1):page194_i55:iof20" )
			)
			( pin "J6B1.A1"
				( objectStatus "@baseboard_fab2_lib.baseboard_fab2(sch_1):page194_i56:ioa1" )
			)
			( pin "J6B1.A2"
				( objectStatus "@baseboard_fab2_lib.baseboard_fab2(sch_1):page194_i56:ioa2" )
			)
			( pin "J6B1.A3"
				( objectStatus "@baseboard_fab2_lib.baseboard_fab2(sch_1):page194_i56:ioa3" )
			)
			( pin "J6B1.A4"
				( objectStatus "@baseboard_fab2_lib.baseboard_fab2(sch_1):page194_i56:ioa4" )
			)
			( pin "J6B1.A5"
				( objectStatus "@baseboard_fab2_lib.baseboard_fab2(sch_1):page194_i56:ioa5" )
			)
			( pin "J6B1.A6"
				( objectStatus "@baseboard_fab2_lib.baseboard_fab2(sch_1):page194_i56:ioa6" )
			)
			( pin "J6B1.A7"
				( objectStatus "@baseboard_fab2_lib.baseboard_fab2(sch_1):page194_i56:ioa7" )
			)
			( pin "J6B1.A8"
				( objectStatus "@baseboard_fab2_lib.baseboard_fab2(sch_1):page194_i56:ioa8" )
			)
			( pin "J6B1.A9"
				( objectStatus "@baseboard_fab2_lib.baseboard_fab2(sch_1):page194_i56:ioa9" )
			)
			( pin "J6B1.A10"
				( objectStatus "@baseboard_fab2_lib.baseboard_fab2(sch_1):page194_i56:ioa10" )
			)
			( pin "J6B1.A11"
				( objectStatus "@baseboard_fab2_lib.baseboard_fab2(sch_1):page194_i56:ioa11" )
			)
			( pin "J6B1.A12"
				( objectStatus "@baseboard_fab2_lib.baseboard_fab2(sch_1):page194_i56:ioa12" )
			)
			( pin "J6B1.A13"
				( objectStatus "@baseboard_fab2_lib.baseboard_fab2(sch_1):page194_i56:ioa13" )
			)
			( pin "J6B1.A14"
				( objectStatus "@baseboard_fab2_lib.baseboard_fab2(sch_1):page194_i56:ioa14" )
			)
			( pin "J6B1.A15"
				( objectStatus "@baseboard_fab2_lib.baseboard_fab2(sch_1):page194_i56:ioa15" )
			)
			( pin "J6B1.A16"
				( objectStatus "@baseboard_fab2_lib.baseboard_fab2(sch_1):page194_i56:ioa16" )
			)
			( pin "J6B1.A17"
				( objectStatus "@baseboard_fab2_lib.baseboard_fab2(sch_1):page194_i56:ioa17" )
			)
			( pin "J6B1.A18"
				( objectStatus "@baseboard_fab2_lib.baseboard_fab2(sch_1):page194_i56:ioa18" )
			)
			( pin "J6B1.A19"
				( objectStatus "@baseboard_fab2_lib.baseboard_fab2(sch_1):page194_i56:ioa19" )
			)
			( pin "J6B1.A20"
				( objectStatus "@baseboard_fab2_lib.baseboard_fab2(sch_1):page194_i56:ioa20" )
			)
			( pin "J6B1.B1"
				( objectStatus "@baseboard_fab2_lib.baseboard_fab2(sch_1):page194_i56:iob1" )
			)
			( pin "J6B1.B2"
				( objectStatus "@baseboard_fab2_lib.baseboard_fab2(sch_1):page194_i56:iob2" )
			)
			( pin "J6B1.B3"
				( objectStatus "@baseboard_fab2_lib.baseboard_fab2(sch_1):page194_i56:iob3" )
			)
			( pin "J6B1.B4"
				( objectStatus "@baseboard_fab2_lib.baseboard_fab2(sch_1):page194_i56:iob4" )
			)
			( pin "J6B1.B5"
				( objectStatus "@baseboard_fab2_lib.baseboard_fab2(sch_1):page194_i56:iob5" )
			)
			( pin "J6B1.B6"
				( objectStatus "@baseboard_fab2_lib.baseboard_fab2(sch_1):page194_i56:iob6" )
			)
			( pin "J6B1.B7"
				( objectStatus "@baseboard_fab2_lib.baseboard_fab2(sch_1):page194_i56:iob7" )
			)
			( pin "J6B1.B8"
				( objectStatus "@baseboard_fab2_lib.baseboard_fab2(sch_1):page194_i56:iob8" )
			)
			( pin "J6B1.B9"
				( objectStatus "@baseboard_fab2_lib.baseboard_fab2(sch_1):page194_i56:iob9" )
			)
			( pin "J6B1.B10"
				( objectStatus "@baseboard_fab2_lib.baseboard_fab2(sch_1):page194_i56:iob10" )
			)
			( pin "J6B1.B11"
				( objectStatus "@baseboard_fab2_lib.baseboard_fab2(sch_1):page194_i56:iob11" )
			)
			( pin "J6B1.B12"
				( objectStatus "@baseboard_fab2_lib.baseboard_fab2(sch_1):page194_i56:iob12" )
			)
			( pin "J6B1.B13"
				( objectStatus "@baseboard_fab2_lib.baseboard_fab2(sch_1):page194_i56:iob13" )
			)
			( pin "J6B1.B14"
				( objectStatus "@baseboard_fab2_lib.baseboard_fab2(sch_1):page194_i56:iob14" )
			)
			( pin "J6B1.B15"
				( objectStatus "@baseboard_fab2_lib.baseboard_fab2(sch_1):page194_i56:iob15" )
			)
			( pin "J6B1.B16"
				( objectStatus "@baseboard_fab2_lib.baseboard_fab2(sch_1):page194_i56:iob16" )
			)
			( pin "J6B1.B17"
				( objectStatus "@baseboard_fab2_lib.baseboard_fab2(sch_1):page194_i56:iob17" )
			)
			( pin "J6B1.B18"
				( objectStatus "@baseboard_fab2_lib.baseboard_fab2(sch_1):page194_i56:iob18" )
			)
			( pin "J6B1.B19"
				( objectStatus "@baseboard_fab2_lib.baseboard_fab2(sch_1):page194_i56:iob19" )
			)
			( pin "J6B1.B20"
				( objectStatus "@baseboard_fab2_lib.baseboard_fab2(sch_1):page194_i56:iob20" )
			)
			( pin "J6B1.C1"
				( objectStatus "@baseboard_fab2_lib.baseboard_fab2(sch_1):page194_i56:ioc1" )
			)
			( pin "J6B1.C2"
				( objectStatus "@baseboard_fab2_lib.baseboard_fab2(sch_1):page194_i56:ioc2" )
			)
			( pin "J6B1.C3"
				( objectStatus "@baseboard_fab2_lib.baseboard_fab2(sch_1):page194_i56:ioc3" )
			)
			( pin "J6B1.C4"
				( objectStatus "@baseboard_fab2_lib.baseboard_fab2(sch_1):page194_i56:ioc4" )
			)
			( pin "J6B1.C5"
				( objectStatus "@baseboard_fab2_lib.baseboard_fab2(sch_1):page194_i56:ioc5" )
			)
			( pin "J6B1.C6"
				( objectStatus "@baseboard_fab2_lib.baseboard_fab2(sch_1):page194_i56:ioc6" )
			)
			( pin "J6B1.C7"
				( objectStatus "@baseboard_fab2_lib.baseboard_fab2(sch_1):page194_i56:ioc7" )
			)
			( pin "J6B1.C8"
				( objectStatus "@baseboard_fab2_lib.baseboard_fab2(sch_1):page194_i56:ioc8" )
			)
			( pin "J6B1.C9"
				( objectStatus "@baseboard_fab2_lib.baseboard_fab2(sch_1):page194_i56:ioc9" )
			)
			( pin "J6B1.C10"
				( objectStatus "@baseboard_fab2_lib.baseboard_fab2(sch_1):page194_i56:ioc10" )
			)
			( pin "J6B1.C11"
				( objectStatus "@baseboard_fab2_lib.baseboard_fab2(sch_1):page194_i56:ioc11" )
			)
			( pin "J6B1.C12"
				( objectStatus "@baseboard_fab2_lib.baseboard_fab2(sch_1):page194_i56:ioc12" )
			)
			( pin "J6B1.C13"
				( objectStatus "@baseboard_fab2_lib.baseboard_fab2(sch_1):page194_i56:ioc13" )
			)
			( pin "J6B1.C14"
				( objectStatus "@baseboard_fab2_lib.baseboard_fab2(sch_1):page194_i56:ioc14" )
			)
			( pin "J6B1.C15"
				( objectStatus "@baseboard_fab2_lib.baseboard_fab2(sch_1):page194_i56:ioc15" )
			)
			( pin "J6B1.C16"
				( objectStatus "@baseboard_fab2_lib.baseboard_fab2(sch_1):page194_i56:ioc16" )
			)
			( pin "J6B1.C17"
				( objectStatus "@baseboard_fab2_lib.baseboard_fab2(sch_1):page194_i56:ioc17" )
			)
			( pin "J6B1.C18"
				( objectStatus "@baseboard_fab2_lib.baseboard_fab2(sch_1):page194_i56:ioc18" )
			)
			( pin "J6B1.C19"
				( objectStatus "@baseboard_fab2_lib.baseboard_fab2(sch_1):page194_i56:ioc19" )
			)
			( pin "J6B1.C20"
				( objectStatus "@baseboard_fab2_lib.baseboard_fab2(sch_1):page194_i56:ioc20" )
			)
			( pin "J6B1.D1"
				( objectStatus "@baseboard_fab2_lib.baseboard_fab2(sch_1):page194_i56:iod1" )
			)
			( pin "J6B1.D2"
				( objectStatus "@baseboard_fab2_lib.baseboard_fab2(sch_1):page194_i56:iod2" )
			)
			( pin "J6B1.D3"
				( objectStatus "@baseboard_fab2_lib.baseboard_fab2(sch_1):page194_i56:iod3" )
			)
			( pin "J6B1.D4"
				( objectStatus "@baseboard_fab2_lib.baseboard_fab2(sch_1):page194_i56:iod4" )
			)
			( pin "J6B1.D5"
				( objectStatus "@baseboard_fab2_lib.baseboard_fab2(sch_1):page194_i56:iod5" )
			)
			( pin "J6B1.D6"
				( objectStatus "@baseboard_fab2_lib.baseboard_fab2(sch_1):page194_i56:iod6" )
			)
			( pin "J6B1.D7"
				( objectStatus "@baseboard_fab2_lib.baseboard_fab2(sch_1):page194_i56:iod7" )
			)
			( pin "J6B1.D8"
				( objectStatus "@baseboard_fab2_lib.baseboard_fab2(sch_1):page194_i56:iod8" )
			)
			( pin "J6B1.D9"
				( objectStatus "@baseboard_fab2_lib.baseboard_fab2(sch_1):page194_i56:iod9" )
			)
			( pin "J6B1.D10"
				( objectStatus "@baseboard_fab2_lib.baseboard_fab2(sch_1):page194_i56:iod10" )
			)
			( pin "J6B1.D11"
				( objectStatus "@baseboard_fab2_lib.baseboard_fab2(sch_1):page194_i56:iod11" )
			)
			( pin "J6B1.D12"
				( objectStatus "@baseboard_fab2_lib.baseboard_fab2(sch_1):page194_i56:iod12" )
			)
			( pin "J6B1.D13"
				( objectStatus "@baseboard_fab2_lib.baseboard_fab2(sch_1):page194_i56:iod13" )
			)
			( pin "J6B1.D14"
				( objectStatus "@baseboard_fab2_lib.baseboard_fab2(sch_1):page194_i56:iod14" )
			)
			( pin "J6B1.D15"
				( objectStatus "@baseboard_fab2_lib.baseboard_fab2(sch_1):page194_i56:iod15" )
			)
			( pin "J6B1.D16"
				( objectStatus "@baseboard_fab2_lib.baseboard_fab2(sch_1):page194_i56:iod16" )
			)
			( pin "J6B1.D17"
				( objectStatus "@baseboard_fab2_lib.baseboard_fab2(sch_1):page194_i56:iod17" )
			)
			( pin "J6B1.D18"
				( objectStatus "@baseboard_fab2_lib.baseboard_fab2(sch_1):page194_i56:iod18" )
			)
			( pin "J6B1.D19"
				( objectStatus "@baseboard_fab2_lib.baseboard_fab2(sch_1):page194_i56:iod19" )
			)
			( pin "J6B1.D20"
				( objectStatus "@baseboard_fab2_lib.baseboard_fab2(sch_1):page194_i56:iod20" )
			)
			( pin "J6B1.E1"
				( objectStatus "@baseboard_fab2_lib.baseboard_fab2(sch_1):page194_i56:ioe1" )
			)
			( pin "J6B1.E2"
				( objectStatus "@baseboard_fab2_lib.baseboard_fab2(sch_1):page194_i56:ioe2" )
			)
			( pin "J6B1.E3"
				( objectStatus "@baseboard_fab2_lib.baseboard_fab2(sch_1):page194_i56:ioe3" )
			)
			( pin "J6B1.E4"
				( objectStatus "@baseboard_fab2_lib.baseboard_fab2(sch_1):page194_i56:ioe4" )
			)
			( pin "J6B1.E5"
				( objectStatus "@baseboard_fab2_lib.baseboard_fab2(sch_1):page194_i56:ioe5" )
			)
			( pin "J6B1.E6"
				( objectStatus "@baseboard_fab2_lib.baseboard_fab2(sch_1):page194_i56:ioe6" )
			)
			( pin "J6B1.E7"
				( objectStatus "@baseboard_fab2_lib.baseboard_fab2(sch_1):page194_i56:ioe7" )
			)
			( pin "J6B1.E8"
				( objectStatus "@baseboard_fab2_lib.baseboard_fab2(sch_1):page194_i56:ioe8" )
			)
			( pin "J6B1.E9"
				( objectStatus "@baseboard_fab2_lib.baseboard_fab2(sch_1):page194_i56:ioe9" )
			)
			( pin "J6B1.E10"
				( objectStatus "@baseboard_fab2_lib.baseboard_fab2(sch_1):page194_i56:ioe10" )
			)
			( pin "J6B1.E11"
				( objectStatus "@baseboard_fab2_lib.baseboard_fab2(sch_1):page194_i56:ioe11" )
			)
			( pin "J6B1.E12"
				( objectStatus "@baseboard_fab2_lib.baseboard_fab2(sch_1):page194_i56:ioe12" )
			)
			( pin "J6B1.E13"
				( objectStatus "@baseboard_fab2_lib.baseboard_fab2(sch_1):page194_i56:ioe13" )
			)
			( pin "J6B1.E14"
				( objectStatus "@baseboard_fab2_lib.baseboard_fab2(sch_1):page194_i56:ioe14" )
			)
			( pin "J6B1.E15"
				( objectStatus "@baseboard_fab2_lib.baseboard_fab2(sch_1):page194_i56:ioe15" )
			)
			( pin "J6B1.E16"
				( objectStatus "@baseboard_fab2_lib.baseboard_fab2(sch_1):page194_i56:ioe16" )
			)
			( pin "J6B1.E17"
				( objectStatus "@baseboard_fab2_lib.baseboard_fab2(sch_1):page194_i56:ioe17" )
			)
			( pin "J6B1.E18"
				( objectStatus "@baseboard_fab2_lib.baseboard_fab2(sch_1):page194_i56:ioe18" )
			)
			( pin "J6B1.E19"
				( objectStatus "@baseboard_fab2_lib.baseboard_fab2(sch_1):page194_i56:ioe19" )
			)
			( pin "J6B1.E20"
				( objectStatus "@baseboard_fab2_lib.baseboard_fab2(sch_1):page194_i56:ioe20" )
			)
			( pin "J6B1.F1"
				( objectStatus "@baseboard_fab2_lib.baseboard_fab2(sch_1):page194_i56:iof1" )
			)
			( pin "J6B1.F2"
				( objectStatus "@baseboard_fab2_lib.baseboard_fab2(sch_1):page194_i56:iof2" )
			)
			( pin "J6B1.F3"
				( objectStatus "@baseboard_fab2_lib.baseboard_fab2(sch_1):page194_i56:iof3" )
			)
			( pin "J6B1.F4"
				( objectStatus "@baseboard_fab2_lib.baseboard_fab2(sch_1):page194_i56:iof4" )
			)
			( pin "J6B1.F5"
				( objectStatus "@baseboard_fab2_lib.baseboard_fab2(sch_1):page194_i56:iof5" )
			)
			( pin "J6B1.F6"
				( objectStatus "@baseboard_fab2_lib.baseboard_fab2(sch_1):page194_i56:iof6" )
			)
			( pin "J6B1.F7"
				( objectStatus "@baseboard_fab2_lib.baseboard_fab2(sch_1):page194_i56:iof7" )
			)
			( pin "J6B1.F8"
				( objectStatus "@baseboard_fab2_lib.baseboard_fab2(sch_1):page194_i56:iof8" )
			)
			( pin "J6B1.F9"
				( objectStatus "@baseboard_fab2_lib.baseboard_fab2(sch_1):page194_i56:iof9" )
			)
			( pin "J6B1.F10"
				( objectStatus "@baseboard_fab2_lib.baseboard_fab2(sch_1):page194_i56:iof10" )
			)
			( pin "J6B1.F11"
				( objectStatus "@baseboard_fab2_lib.baseboard_fab2(sch_1):page194_i56:iof11" )
			)
			( pin "J6B1.F12"
				( objectStatus "@baseboard_fab2_lib.baseboard_fab2(sch_1):page194_i56:iof12" )
			)
			( pin "J6B1.F13"
				( objectStatus "@baseboard_fab2_lib.baseboard_fab2(sch_1):page194_i56:iof13" )
			)
			( pin "J6B1.F14"
				( objectStatus "@baseboard_fab2_lib.baseboard_fab2(sch_1):page194_i56:iof14" )
			)
			( pin "J6B1.F15"
				( objectStatus "@baseboard_fab2_lib.baseboard_fab2(sch_1):page194_i56:iof15" )
			)
			( pin "J6B1.F16"
				( objectStatus "@baseboard_fab2_lib.baseboard_fab2(sch_1):page194_i56:iof16" )
			)
			( pin "J6B1.F17"
				( objectStatus "@baseboard_fab2_lib.baseboard_fab2(sch_1):page194_i56:iof17" )
			)
			( pin "J6B1.F18"
				( objectStatus "@baseboard_fab2_lib.baseboard_fab2(sch_1):page194_i56:iof18" )
			)
			( pin "J6B1.F19"
				( objectStatus "@baseboard_fab2_lib.baseboard_fab2(sch_1):page194_i56:iof19" )
			)
			( pin "J6B1.F20"
				( objectStatus "@baseboard_fab2_lib.baseboard_fab2(sch_1):page194_i56:iof20" )
			)
			( pin "C3N40.1"
				( objectStatus "@baseboard_fab2_lib.baseboard_fab2(sch_1):page194_i86:a" )
			)
			( pin "C3N40.2"
				( objectStatus "@baseboard_fab2_lib.baseboard_fab2(sch_1):page194_i86:b" )
			)
			( pin "C3M46.1"
				( objectStatus "@baseboard_fab2_lib.baseboard_fab2(sch_1):page194_i99:a" )
			)
			( pin "C3M46.2"
				( objectStatus "@baseboard_fab2_lib.baseboard_fab2(sch_1):page194_i99:b" )
			)
			( pin "C3N14.1"
				( objectStatus "@baseboard_fab2_lib.baseboard_fab2(sch_1):page194_i101:a" )
			)
			( pin "C3N14.2"
				( objectStatus "@baseboard_fab2_lib.baseboard_fab2(sch_1):page194_i101:b" )
			)
			( pin "C3T1.1"
				( objectStatus "@baseboard_fab2_lib.baseboard_fab2(sch_1):page194_i149:a" )
			)
			( pin "C3T1.2"
				( objectStatus "@baseboard_fab2_lib.baseboard_fab2(sch_1):page194_i149:b" )
			)
			( pin "C3T2.1"
				( objectStatus "@baseboard_fab2_lib.baseboard_fab2(sch_1):page194_i150:a" )
			)
			( pin "C3T2.2"
				( objectStatus "@baseboard_fab2_lib.baseboard_fab2(sch_1):page194_i150:b" )
			)
			( pin "R7C24.1"
				( objectStatus "@baseboard_fab2_lib.baseboard_fab2(sch_1):page194_i155:a" )
			)
			( pin "R7C24.2"
				( objectStatus "@baseboard_fab2_lib.baseboard_fab2(sch_1):page194_i155:b" )
			)
			( pin "R3N29.1"
				( objectStatus "@baseboard_fab2_lib.baseboard_fab2(sch_1):page194_i156:a" )
			)
			( pin "R3N29.2"
				( objectStatus "@baseboard_fab2_lib.baseboard_fab2(sch_1):page194_i156:b" )
			)
			( pin "RM1E1.1"
				( objectStatus "@baseboard_fab2_lib.baseboard_fab2(sch_1):page195_i26:io1" )
			)
			( pin "RM1E1.2"
				( objectStatus "@baseboard_fab2_lib.baseboard_fab2(sch_1):page195_i26:io2" )
			)
			( pin "RM1E1.3"
				( objectStatus "@baseboard_fab2_lib.baseboard_fab2(sch_1):page195_i26:io3" )
			)
			( pin "J1E1.A1"
				( objectStatus "@baseboard_fab2_lib.baseboard_fab2(sch_1):page195_i29:a1" )
			)
			( pin "J1E1.A2"
				( objectStatus "@baseboard_fab2_lib.baseboard_fab2(sch_1):page195_i29:a2" )
			)
			( pin "J1E1.A3"
				( objectStatus "@baseboard_fab2_lib.baseboard_fab2(sch_1):page195_i29:a3" )
			)
			( pin "J1E1.B1"
				( objectStatus "@baseboard_fab2_lib.baseboard_fab2(sch_1):page195_i29:b1" )
			)
			( pin "J1E1.B2"
				( objectStatus "@baseboard_fab2_lib.baseboard_fab2(sch_1):page195_i29:b2" )
			)
			( pin "J1E1.B3"
				( objectStatus "@baseboard_fab2_lib.baseboard_fab2(sch_1):page195_i29:b3" )
			)
			( pin "J1E1.C1"
				( objectStatus "@baseboard_fab2_lib.baseboard_fab2(sch_1):page195_i29:c1" )
			)
			( pin "J1E1.C2"
				( objectStatus "@baseboard_fab2_lib.baseboard_fab2(sch_1):page195_i29:c2" )
			)
			( pin "J1E1.C3"
				( objectStatus "@baseboard_fab2_lib.baseboard_fab2(sch_1):page195_i29:c3" )
			)
			( pin "J1E1.D1"
				( objectStatus "@baseboard_fab2_lib.baseboard_fab2(sch_1):page195_i29:d1" )
			)
			( pin "J1E1.D2"
				( objectStatus "@baseboard_fab2_lib.baseboard_fab2(sch_1):page195_i29:d2" )
			)
			( pin "J1E1.D3"
				( objectStatus "@baseboard_fab2_lib.baseboard_fab2(sch_1):page195_i29:d3" )
			)
			( pin "C9R5.1"
				( objectStatus "@baseboard_fab2_lib.baseboard_fab2(sch_1):page195_i31:a" )
			)
			( pin "C9R5.2"
				( objectStatus "@baseboard_fab2_lib.baseboard_fab2(sch_1):page195_i31:b" )
			)
			( pin "C1E12.1"
				( objectStatus "@baseboard_fab2_lib.baseboard_fab2(sch_1):page195_i32:a" )
			)
			( pin "C1E12.2"
				( objectStatus "@baseboard_fab2_lib.baseboard_fab2(sch_1):page195_i32:b" )
			)
			( pin "C1E15.1"
				( objectStatus "@baseboard_fab2_lib.baseboard_fab2(sch_1):page195_i35:a" )
			)
			( pin "C1E15.2"
				( objectStatus "@baseboard_fab2_lib.baseboard_fab2(sch_1):page195_i35:b" )
			)
			( pin "C9R12.1"
				( objectStatus "@baseboard_fab2_lib.baseboard_fab2(sch_1):page195_i36:a" )
			)
			( pin "C9R12.2"
				( objectStatus "@baseboard_fab2_lib.baseboard_fab2(sch_1):page195_i36:b" )
			)
			( pin "C9R6.1"
				( objectStatus "@baseboard_fab2_lib.baseboard_fab2(sch_1):page195_i37:a" )
			)
			( pin "C9R6.2"
				( objectStatus "@baseboard_fab2_lib.baseboard_fab2(sch_1):page195_i37:b" )
			)
			( pin "C1E17.1"
				( objectStatus "@baseboard_fab2_lib.baseboard_fab2(sch_1):page195_i38:a" )
			)
			( pin "C1E17.2"
				( objectStatus "@baseboard_fab2_lib.baseboard_fab2(sch_1):page195_i38:b" )
			)
			( pin "C1E16.1"
				( objectStatus "@baseboard_fab2_lib.baseboard_fab2(sch_1):page195_i39:a" )
			)
			( pin "C1E16.2"
				( objectStatus "@baseboard_fab2_lib.baseboard_fab2(sch_1):page195_i39:b" )
			)
			( pin "TH4G1.1"
				( objectStatus "@baseboard_fab2_lib.baseboard_fab2(sch_1):page195_i49:\1\" )
			)
			( pin "TH9G1.1"
				( objectStatus "@baseboard_fab2_lib.baseboard_fab2(sch_1):page195_i52:\1\" )
			)
			( pin "TH9A1.1"
				( objectStatus "@baseboard_fab2_lib.baseboard_fab2(sch_1):page195_i54:\1\" )
			)
			( pin "TH1A1.1"
				( objectStatus "@baseboard_fab2_lib.baseboard_fab2(sch_1):page195_i56:\1\" )
			)
			( pin "TH4A1.1"
				( objectStatus "@baseboard_fab2_lib.baseboard_fab2(sch_1):page195_i62:\1\" )
			)
			( pin "TH7A1.1"
				( objectStatus "@baseboard_fab2_lib.baseboard_fab2(sch_1):page195_i65:\1\" )
			)
			( pin "TH7G1.1"
				( objectStatus "@baseboard_fab2_lib.baseboard_fab2(sch_1):page195_i67:\1\" )
			)
			( pin "J1D1.A1"
				( objectStatus "@baseboard_fab2_lib.baseboard_fab2(sch_1):page195_i78:a1" )
			)
			( pin "J1D1.A2"
				( objectStatus "@baseboard_fab2_lib.baseboard_fab2(sch_1):page195_i78:a2" )
			)
			( pin "J1D1.A3"
				( objectStatus "@baseboard_fab2_lib.baseboard_fab2(sch_1):page195_i78:a3" )
			)
			( pin "J1D1.B1"
				( objectStatus "@baseboard_fab2_lib.baseboard_fab2(sch_1):page195_i78:b1" )
			)
			( pin "J1D1.B2"
				( objectStatus "@baseboard_fab2_lib.baseboard_fab2(sch_1):page195_i78:b2" )
			)
			( pin "J1D1.B3"
				( objectStatus "@baseboard_fab2_lib.baseboard_fab2(sch_1):page195_i78:b3" )
			)
			( pin "J1D1.C1"
				( objectStatus "@baseboard_fab2_lib.baseboard_fab2(sch_1):page195_i78:c1" )
			)
			( pin "J1D1.C2"
				( objectStatus "@baseboard_fab2_lib.baseboard_fab2(sch_1):page195_i78:c2" )
			)
			( pin "J1D1.C3"
				( objectStatus "@baseboard_fab2_lib.baseboard_fab2(sch_1):page195_i78:c3" )
			)
			( pin "J1D1.D1"
				( objectStatus "@baseboard_fab2_lib.baseboard_fab2(sch_1):page195_i78:d1" )
			)
			( pin "J1D1.D2"
				( objectStatus "@baseboard_fab2_lib.baseboard_fab2(sch_1):page195_i78:d2" )
			)
			( pin "J1D1.D3"
				( objectStatus "@baseboard_fab2_lib.baseboard_fab2(sch_1):page195_i78:d3" )
			)
			( pin "C4F6.1"
				( objectStatus "@baseboard_fab2_lib.baseboard_fab2(sch_1):page195_i82:a" )
			)
			( pin "C4F6.2"
				( objectStatus "@baseboard_fab2_lib.baseboard_fab2(sch_1):page195_i82:b" )
			)
			( pin "C4B13.1"
				( objectStatus "@baseboard_fab2_lib.baseboard_fab2(sch_1):page195_i83:a" )
			)
			( pin "C4B13.2"
				( objectStatus "@baseboard_fab2_lib.baseboard_fab2(sch_1):page195_i83:b" )
			)
			( pin "C1B14.1"
				( objectStatus "@baseboard_fab2_lib.baseboard_fab2(sch_1):page195_i84:a" )
			)
			( pin "C1B14.2"
				( objectStatus "@baseboard_fab2_lib.baseboard_fab2(sch_1):page195_i84:b" )
			)
			( pin "C1F7.1"
				( objectStatus "@baseboard_fab2_lib.baseboard_fab2(sch_1):page195_i85:a" )
			)
			( pin "C1F7.2"
				( objectStatus "@baseboard_fab2_lib.baseboard_fab2(sch_1):page195_i85:b" )
			)
			( pin "C4F5.1"
				( objectStatus "@baseboard_fab2_lib.baseboard_fab2(sch_1):page195_i96:a" )
			)
			( pin "C4F5.2"
				( objectStatus "@baseboard_fab2_lib.baseboard_fab2(sch_1):page195_i96:b" )
			)
			( pin "C4B14.1"
				( objectStatus "@baseboard_fab2_lib.baseboard_fab2(sch_1):page195_i97:a" )
			)
			( pin "C4B14.2"
				( objectStatus "@baseboard_fab2_lib.baseboard_fab2(sch_1):page195_i97:b" )
			)
			( pin "C3T6.1"
				( objectStatus "@baseboard_fab2_lib.baseboard_fab2(sch_1):page195_i98:a" )
			)
			( pin "C3T6.2"
				( objectStatus "@baseboard_fab2_lib.baseboard_fab2(sch_1):page195_i98:b" )
			)
			( pin "C9M3.1"
				( objectStatus "@baseboard_fab2_lib.baseboard_fab2(sch_1):page195_i99:a" )
			)
			( pin "C9M3.2"
				( objectStatus "@baseboard_fab2_lib.baseboard_fab2(sch_1):page195_i99:b" )
			)
			( pin "C3B6.1"
				( objectStatus "@baseboard_fab2_lib.baseboard_fab2(sch_1):page195_i100:a" )
			)
			( pin "C3B6.2"
				( objectStatus "@baseboard_fab2_lib.baseboard_fab2(sch_1):page195_i100:b" )
			)
			( pin "C1R23.1"
				( objectStatus "@baseboard_fab2_lib.baseboard_fab2(sch_1):page195_i101:a" )
			)
			( pin "C1R23.2"
				( objectStatus "@baseboard_fab2_lib.baseboard_fab2(sch_1):page195_i101:b" )
			)
			( pin "C4M6.1"
				( objectStatus "@baseboard_fab2_lib.baseboard_fab2(sch_1):page195_i102:a" )
			)
			( pin "C4M6.2"
				( objectStatus "@baseboard_fab2_lib.baseboard_fab2(sch_1):page195_i102:b" )
			)
			( pin "C1M5.1"
				( objectStatus "@baseboard_fab2_lib.baseboard_fab2(sch_1):page195_i103:a" )
			)
			( pin "C1M5.2"
				( objectStatus "@baseboard_fab2_lib.baseboard_fab2(sch_1):page195_i103:b" )
			)
			( pin "C3T13.1"
				( objectStatus "@baseboard_fab2_lib.baseboard_fab2(sch_1):page195_i104:a" )
			)
			( pin "C3T13.2"
				( objectStatus "@baseboard_fab2_lib.baseboard_fab2(sch_1):page195_i104:b" )
			)
			( pin "C4M7.1"
				( objectStatus "@baseboard_fab2_lib.baseboard_fab2(sch_1):page195_i105:a" )
			)
			( pin "C4M7.2"
				( objectStatus "@baseboard_fab2_lib.baseboard_fab2(sch_1):page195_i105:b" )
			)
			( pin "C3T15.1"
				( objectStatus "@baseboard_fab2_lib.baseboard_fab2(sch_1):page195_i106:a" )
			)
			( pin "C3T15.2"
				( objectStatus "@baseboard_fab2_lib.baseboard_fab2(sch_1):page195_i106:b" )
			)
			( pin "C7M6.1"
				( objectStatus "@baseboard_fab2_lib.baseboard_fab2(sch_1):page195_i108:a" )
			)
			( pin "C7M6.2"
				( objectStatus "@baseboard_fab2_lib.baseboard_fab2(sch_1):page195_i108:b" )
			)
			( pin "C6N5.1"
				( objectStatus "@baseboard_fab2_lib.baseboard_fab2(sch_1):page195_i109:a" )
			)
			( pin "C6N5.2"
				( objectStatus "@baseboard_fab2_lib.baseboard_fab2(sch_1):page195_i109:b" )
			)
			( pin "C9T3.1"
				( objectStatus "@baseboard_fab2_lib.baseboard_fab2(sch_1):page195_i111:a" )
			)
			( pin "C9T3.2"
				( objectStatus "@baseboard_fab2_lib.baseboard_fab2(sch_1):page195_i111:b" )
			)
			( pin "C4F4.1"
				( objectStatus "@baseboard_fab2_lib.baseboard_fab2(sch_1):page195_i112:a" )
			)
			( pin "C4F4.2"
				( objectStatus "@baseboard_fab2_lib.baseboard_fab2(sch_1):page195_i112:b" )
			)
			( pin "C3T3.1"
				( objectStatus "@baseboard_fab2_lib.baseboard_fab2(sch_1):page195_i113:a" )
			)
			( pin "C3T3.2"
				( objectStatus "@baseboard_fab2_lib.baseboard_fab2(sch_1):page195_i113:b" )
			)
			( pin "R2U43.1"
				( objectStatus "@baseboard_fab2_lib.baseboard_fab2(sch_1):page196_i46:a" )
			)
			( pin "R2U43.2"
				( objectStatus "@baseboard_fab2_lib.baseboard_fab2(sch_1):page196_i46:b" )
			)
			( pin "XBT8G1.3"
				( objectStatus "@baseboard_fab2_lib.baseboard_fab2(sch_1):page196_i51:n" )
			)
			( pin "XBT8G1.1"
				( objectStatus "@baseboard_fab2_lib.baseboard_fab2(sch_1):page196_i51:p1" )
			)
			( pin "XBT8G1.2"
				( objectStatus "@baseboard_fab2_lib.baseboard_fab2(sch_1):page196_i51:p2" )
			)
			( pin "CR2U1.1"
				( objectStatus "@baseboard_fab2_lib.baseboard_fab2(sch_1):page196_i53:a1" )
			)
			( pin "CR2U1.2"
				( objectStatus "@baseboard_fab2_lib.baseboard_fab2(sch_1):page196_i53:a2" )
			)
			( pin "CR2U1.3"
				( objectStatus "@baseboard_fab2_lib.baseboard_fab2(sch_1):page196_i53:c" )
			)
			( pin "R3P44.1"
				( objectStatus "@baseboard_fab2_lib.baseboard_fab2(sch_1):page196_i59:a" )
			)
			( pin "R3P44.2"
				( objectStatus "@baseboard_fab2_lib.baseboard_fab2(sch_1):page196_i59:b" )
			)
			( pin "C3P45.1"
				( objectStatus "@baseboard_fab2_lib.baseboard_fab2(sch_1):page196_i60:a" )
			)
			( pin "C3P45.2"
				( objectStatus "@baseboard_fab2_lib.baseboard_fab2(sch_1):page196_i60:b" )
			)
			( pin "R2P20.1"
				( objectStatus "@baseboard_fab2_lib.baseboard_fab2(sch_1):page196_i65:a" )
			)
			( pin "R2P20.2"
				( objectStatus "@baseboard_fab2_lib.baseboard_fab2(sch_1):page196_i65:b" )
			)
			( pin "R1L16.1"
				( objectStatus "@baseboard_fab2_lib.baseboard_fab2(sch_1):page196_i68:a" )
			)
			( pin "R1L16.2"
				( objectStatus "@baseboard_fab2_lib.baseboard_fab2(sch_1):page196_i68:b" )
			)
			( pin "U7D3.5"
				( objectStatus "@baseboard_fab2_lib.baseboard_fab2(sch_1):page196_i70:cext" )
			)
			( pin "U7D3.1"
				( objectStatus "@baseboard_fab2_lib.baseboard_fab2(sch_1):page196_i70:enin" )
			)
			( pin "U7D3.4"
				( objectStatus "@baseboard_fab2_lib.baseboard_fab2(sch_1):page196_i70:enout" )
			)
			( pin "U7D3.2"
				( objectStatus "@baseboard_fab2_lib.baseboard_fab2(sch_1):page196_i70:gnd" )
			)
			( pin "U7D3.6"
				( objectStatus "@baseboard_fab2_lib.baseboard_fab2(sch_1):page196_i70:vcc" )
			)
			( pin "U7D3.3"
				( objectStatus "@baseboard_fab2_lib.baseboard_fab2(sch_1):page196_i70:vin" )
			)
			( pin "R3P50.1"
				( objectStatus "@baseboard_fab2_lib.baseboard_fab2(sch_1):page196_i71:a" )
			)
			( pin "R3P50.2"
				( objectStatus "@baseboard_fab2_lib.baseboard_fab2(sch_1):page196_i71:b" )
			)
			( pin "C3P46.1"
				( objectStatus "@baseboard_fab2_lib.baseboard_fab2(sch_1):page196_i72:a" )
			)
			( pin "C3P46.2"
				( objectStatus "@baseboard_fab2_lib.baseboard_fab2(sch_1):page196_i72:b" )
			)
			( pin "R3P48.1"
				( objectStatus "@baseboard_fab2_lib.baseboard_fab2(sch_1):page196_i74:a" )
			)
			( pin "R3P48.2"
				( objectStatus "@baseboard_fab2_lib.baseboard_fab2(sch_1):page196_i74:b" )
			)
			( pin "R3P51.1"
				( objectStatus "@baseboard_fab2_lib.baseboard_fab2(sch_1):page196_i75:a" )
			)
			( pin "R3P51.2"
				( objectStatus "@baseboard_fab2_lib.baseboard_fab2(sch_1):page196_i75:b" )
			)
			( pin "U1L3.2"
				( objectStatus "@baseboard_fab2_lib.baseboard_fab2(sch_1):page196_i80:reset_n" )
			)
			( pin "U1L3.3"
				( objectStatus "@baseboard_fab2_lib.baseboard_fab2(sch_1):page196_i80:vcc" )
			)
			( pin "C1L16.1"
				( objectStatus "@baseboard_fab2_lib.baseboard_fab2(sch_1):page196_i81:a" )
			)
			( pin "C1L16.2"
				( objectStatus "@baseboard_fab2_lib.baseboard_fab2(sch_1):page196_i81:b" )
			)
			( pin "U8E2.2"
				( objectStatus "@baseboard_fab2_lib.baseboard_fab2(sch_1):page196_i89:reset_n" )
			)
			( pin "U8E2.3"
				( objectStatus "@baseboard_fab2_lib.baseboard_fab2(sch_1):page196_i89:vcc" )
			)
			( pin "R8E7.1"
				( objectStatus "@baseboard_fab2_lib.baseboard_fab2(sch_1):page196_i90:a" )
			)
			( pin "R8E7.2"
				( objectStatus "@baseboard_fab2_lib.baseboard_fab2(sch_1):page196_i90:b" )
			)
			( pin "C8E3.1"
				( objectStatus "@baseboard_fab2_lib.baseboard_fab2(sch_1):page196_i94:a" )
			)
			( pin "C8E3.2"
				( objectStatus "@baseboard_fab2_lib.baseboard_fab2(sch_1):page196_i94:b" )
			)
			( pin "C2U26.1"
				( objectStatus "@baseboard_fab2_lib.baseboard_fab2(sch_1):page196_i102:a" )
			)
			( pin "C2U26.2"
				( objectStatus "@baseboard_fab2_lib.baseboard_fab2(sch_1):page196_i102:b" )
			)
			( pin "CR7E1.2"
				( objectStatus "@baseboard_fab2_lib.baseboard_fab2(sch_1):page196_i103:a" )
			)
			( pin "CR7E1.1"
				( objectStatus "@baseboard_fab2_lib.baseboard_fab2(sch_1):page196_i103:c" )
			)
			( pin "U8D8.5"
				( objectStatus "@baseboard_fab2_lib.baseboard_fab2(sch_1):page196_i104:gnd" )
			)
			( pin "U8D8.4"
				( objectStatus "@baseboard_fab2_lib.baseboard_fab2(sch_1):page196_i104:inap" )
			)
			( pin "U8D8.3"
				( objectStatus "@baseboard_fab2_lib.baseboard_fab2(sch_1):page196_i104:inbn" )
			)
			( pin "U8D8.6"
				( objectStatus "@baseboard_fab2_lib.baseboard_fab2(sch_1):page196_i104:outa" )
			)
			( pin "U8D8.1"
				( objectStatus "@baseboard_fab2_lib.baseboard_fab2(sch_1):page196_i104:outb" )
			)
			( pin "U8D8.2"
				( objectStatus "@baseboard_fab2_lib.baseboard_fab2(sch_1):page196_i104:vdd" )
			)
			( pin "C8D4.1"
				( objectStatus "@baseboard_fab2_lib.baseboard_fab2(sch_1):page196_i105:a" )
			)
			( pin "C8D4.2"
				( objectStatus "@baseboard_fab2_lib.baseboard_fab2(sch_1):page196_i105:b" )
			)
			( pin "R8D42.1"
				( objectStatus "@baseboard_fab2_lib.baseboard_fab2(sch_1):page196_i106:a" )
			)
			( pin "R8D42.2"
				( objectStatus "@baseboard_fab2_lib.baseboard_fab2(sch_1):page196_i106:b" )
			)
			( pin "R8D38.1"
				( objectStatus "@baseboard_fab2_lib.baseboard_fab2(sch_1):page196_i112:a" )
			)
			( pin "R8D38.2"
				( objectStatus "@baseboard_fab2_lib.baseboard_fab2(sch_1):page196_i112:b" )
			)
			( pin "R8D40.1"
				( objectStatus "@baseboard_fab2_lib.baseboard_fab2(sch_1):page196_i113:a" )
			)
			( pin "R8D40.2"
				( objectStatus "@baseboard_fab2_lib.baseboard_fab2(sch_1):page196_i113:b" )
			)
			( pin "R8D39.1"
				( objectStatus "@baseboard_fab2_lib.baseboard_fab2(sch_1):page196_i114:a" )
			)
			( pin "R8D39.2"
				( objectStatus "@baseboard_fab2_lib.baseboard_fab2(sch_1):page196_i114:b" )
			)
			( pin "R8D37.1"
				( objectStatus "@baseboard_fab2_lib.baseboard_fab2(sch_1):page196_i115:a" )
			)
			( pin "R8D37.2"
				( objectStatus "@baseboard_fab2_lib.baseboard_fab2(sch_1):page196_i115:b" )
			)
			( pin "R8D41.1"
				( objectStatus "@baseboard_fab2_lib.baseboard_fab2(sch_1):page196_i120:a" )
			)
			( pin "R8D41.2"
				( objectStatus "@baseboard_fab2_lib.baseboard_fab2(sch_1):page196_i120:b" )
			)
			( pin "R2P18.1"
				( objectStatus "@baseboard_fab2_lib.baseboard_fab2(sch_1):page196_i121:a" )
			)
			( pin "R2P18.2"
				( objectStatus "@baseboard_fab2_lib.baseboard_fab2(sch_1):page196_i121:b" )
			)
			( pin "R2P21.1"
				( objectStatus "@baseboard_fab2_lib.baseboard_fab2(sch_1):page196_i122:a" )
			)
			( pin "R2P21.2"
				( objectStatus "@baseboard_fab2_lib.baseboard_fab2(sch_1):page196_i122:b" )
			)
			( pin "Q2P2.3"
				( objectStatus "@baseboard_fab2_lib.baseboard_fab2(sch_1):page196_i124:drn" )
			)
			( pin "Q2P2.1"
				( objectStatus "@baseboard_fab2_lib.baseboard_fab2(sch_1):page196_i124:gate" )
			)
			( pin "Q2P2.2"
				( objectStatus "@baseboard_fab2_lib.baseboard_fab2(sch_1):page196_i124:src" )
			)
			( pin "CR8E1.2"
				( objectStatus "@baseboard_fab2_lib.baseboard_fab2(sch_1):page196_i128:a" )
			)
			( pin "CR8E1.1"
				( objectStatus "@baseboard_fab2_lib.baseboard_fab2(sch_1):page196_i128:c" )
			)
			( pin "C6U18.1"
				( objectStatus "@baseboard_fab2_lib.baseboard_fab2(sch_1):page197_i52:a" )
			)
			( pin "C6U18.2"
				( objectStatus "@baseboard_fab2_lib.baseboard_fab2(sch_1):page197_i52:b" )
			)
			( pin "C6T2.1"
				( objectStatus "@baseboard_fab2_lib.baseboard_fab2(sch_1):page197_i54:a" )
			)
			( pin "C6T2.2"
				( objectStatus "@baseboard_fab2_lib.baseboard_fab2(sch_1):page197_i54:b" )
			)
			( pin "C4B11.1"
				( objectStatus "@baseboard_fab2_lib.baseboard_fab2(sch_1):page197_i59:a" )
			)
			( pin "C4B11.2"
				( objectStatus "@baseboard_fab2_lib.baseboard_fab2(sch_1):page197_i59:b" )
			)
			( pin "C4A4.1"
				( objectStatus "@baseboard_fab2_lib.baseboard_fab2(sch_1):page197_i62:a" )
			)
			( pin "C4A4.2"
				( objectStatus "@baseboard_fab2_lib.baseboard_fab2(sch_1):page197_i62:b" )
			)
			( pin "C6U10.1"
				( objectStatus "@baseboard_fab2_lib.baseboard_fab2(sch_1):page197_i65:a" )
			)
			( pin "C6U10.2"
				( objectStatus "@baseboard_fab2_lib.baseboard_fab2(sch_1):page197_i65:b" )
			)
			( pin "C4A17.1"
				( objectStatus "@baseboard_fab2_lib.baseboard_fab2(sch_1):page197_i67:a" )
			)
			( pin "C4A17.2"
				( objectStatus "@baseboard_fab2_lib.baseboard_fab2(sch_1):page197_i67:b" )
			)
			( pin "C9T8.1"
				( objectStatus "@baseboard_fab2_lib.baseboard_fab2(sch_1):page197_i70:a" )
			)
			( pin "C9T8.2"
				( objectStatus "@baseboard_fab2_lib.baseboard_fab2(sch_1):page197_i70:b" )
			)
			( pin "C9U11.1"
				( objectStatus "@baseboard_fab2_lib.baseboard_fab2(sch_1):page197_i73:a" )
			)
			( pin "C9U11.2"
				( objectStatus "@baseboard_fab2_lib.baseboard_fab2(sch_1):page197_i73:b" )
			)
			( pin "C9U8.1"
				( objectStatus "@baseboard_fab2_lib.baseboard_fab2(sch_1):page197_i76:a" )
			)
			( pin "C9U8.2"
				( objectStatus "@baseboard_fab2_lib.baseboard_fab2(sch_1):page197_i76:b" )
			)
			( pin "C1A4.1"
				( objectStatus "@baseboard_fab2_lib.baseboard_fab2(sch_1):page197_i79:a" )
			)
			( pin "C1A4.2"
				( objectStatus "@baseboard_fab2_lib.baseboard_fab2(sch_1):page197_i79:b" )
			)
			( pin "C1B7.1"
				( objectStatus "@baseboard_fab2_lib.baseboard_fab2(sch_1):page197_i82:a" )
			)
			( pin "C1B7.2"
				( objectStatus "@baseboard_fab2_lib.baseboard_fab2(sch_1):page197_i82:b" )
			)
			( pin "C1A16.1"
				( objectStatus "@baseboard_fab2_lib.baseboard_fab2(sch_1):page197_i85:a" )
			)
			( pin "C1A16.2"
				( objectStatus "@baseboard_fab2_lib.baseboard_fab2(sch_1):page197_i85:b" )
			)
			( pin "U4F1.2"
				( objectStatus "@baseboard_fab2_lib.baseboard_fab2(sch_1):page197_i97:gnd(0)" )
			)
			( pin "U4F1.1"
				( objectStatus "@baseboard_fab2_lib.baseboard_fab2(sch_1):page197_i97:gnd(1)" )
			)
			( pin "U4F1.3"
				( objectStatus "@baseboard_fab2_lib.baseboard_fab2(sch_1):page197_i97:\out\" )
			)
			( pin "U4F1.4"
				( objectStatus "@baseboard_fab2_lib.baseboard_fab2(sch_1):page197_i97:rsn" )
			)
			( pin "U4F1.5"
				( objectStatus "@baseboard_fab2_lib.baseboard_fab2(sch_1):page197_i97:rsp" )
			)
			( pin "R4F2.1"
				( objectStatus "@baseboard_fab2_lib.baseboard_fab2(sch_1):page197_i99:a" )
			)
			( pin "R4F2.2"
				( objectStatus "@baseboard_fab2_lib.baseboard_fab2(sch_1):page197_i99:b" )
			)
			( pin "R4F1.1"
				( objectStatus "@baseboard_fab2_lib.baseboard_fab2(sch_1):page197_i110:a" )
			)
			( pin "R4F1.2"
				( objectStatus "@baseboard_fab2_lib.baseboard_fab2(sch_1):page197_i110:b" )
			)
			( pin "R4B11.1"
				( objectStatus "@baseboard_fab2_lib.baseboard_fab2(sch_1):page197_i113:a" )
			)
			( pin "R4B11.2"
				( objectStatus "@baseboard_fab2_lib.baseboard_fab2(sch_1):page197_i113:b" )
			)
			( pin "U4B1.2"
				( objectStatus "@baseboard_fab2_lib.baseboard_fab2(sch_1):page197_i120:gnd(0)" )
			)
			( pin "U4B1.1"
				( objectStatus "@baseboard_fab2_lib.baseboard_fab2(sch_1):page197_i120:gnd(1)" )
			)
			( pin "U4B1.3"
				( objectStatus "@baseboard_fab2_lib.baseboard_fab2(sch_1):page197_i120:\out\" )
			)
			( pin "U4B1.4"
				( objectStatus "@baseboard_fab2_lib.baseboard_fab2(sch_1):page197_i120:rsn" )
			)
			( pin "U4B1.5"
				( objectStatus "@baseboard_fab2_lib.baseboard_fab2(sch_1):page197_i120:rsp" )
			)
			( pin "R4B12.1"
				( objectStatus "@baseboard_fab2_lib.baseboard_fab2(sch_1):page197_i121:a" )
			)
			( pin "R4B12.2"
				( objectStatus "@baseboard_fab2_lib.baseboard_fab2(sch_1):page197_i121:b" )
			)
			( pin "R9T4.1"
				( objectStatus "@baseboard_fab2_lib.baseboard_fab2(sch_1):page197_i126:a" )
			)
			( pin "R9T4.2"
				( objectStatus "@baseboard_fab2_lib.baseboard_fab2(sch_1):page197_i126:b" )
			)
			( pin "R1F3.1"
				( objectStatus "@baseboard_fab2_lib.baseboard_fab2(sch_1):page197_i131:a" )
			)
			( pin "R1F3.2"
				( objectStatus "@baseboard_fab2_lib.baseboard_fab2(sch_1):page197_i131:b" )
			)
			( pin "U1F1.2"
				( objectStatus "@baseboard_fab2_lib.baseboard_fab2(sch_1):page197_i133:gnd(0)" )
			)
			( pin "U1F1.1"
				( objectStatus "@baseboard_fab2_lib.baseboard_fab2(sch_1):page197_i133:gnd(1)" )
			)
			( pin "U1F1.3"
				( objectStatus "@baseboard_fab2_lib.baseboard_fab2(sch_1):page197_i133:\out\" )
			)
			( pin "U1F1.4"
				( objectStatus "@baseboard_fab2_lib.baseboard_fab2(sch_1):page197_i133:rsn" )
			)
			( pin "U1F1.5"
				( objectStatus "@baseboard_fab2_lib.baseboard_fab2(sch_1):page197_i133:rsp" )
			)
			( pin "R1B14.1"
				( objectStatus "@baseboard_fab2_lib.baseboard_fab2(sch_1):page197_i137:a" )
			)
			( pin "R1B14.2"
				( objectStatus "@baseboard_fab2_lib.baseboard_fab2(sch_1):page197_i137:b" )
			)
			( pin "R9M4.1"
				( objectStatus "@baseboard_fab2_lib.baseboard_fab2(sch_1):page197_i142:a" )
			)
			( pin "R9M4.2"
				( objectStatus "@baseboard_fab2_lib.baseboard_fab2(sch_1):page197_i142:b" )
			)
			( pin "U1B1.2"
				( objectStatus "@baseboard_fab2_lib.baseboard_fab2(sch_1):page197_i144:gnd(0)" )
			)
			( pin "U1B1.1"
				( objectStatus "@baseboard_fab2_lib.baseboard_fab2(sch_1):page197_i144:gnd(1)" )
			)
			( pin "U1B1.3"
				( objectStatus "@baseboard_fab2_lib.baseboard_fab2(sch_1):page197_i144:\out\" )
			)
			( pin "U1B1.4"
				( objectStatus "@baseboard_fab2_lib.baseboard_fab2(sch_1):page197_i144:rsn" )
			)
			( pin "U1B1.5"
				( objectStatus "@baseboard_fab2_lib.baseboard_fab2(sch_1):page197_i144:rsp" )
			)
			( pin "EU2T1.5"
				( objectStatus "@baseboard_fab2_lib.baseboard_fab2(sch_1):page198_i1:d" )
			)
			( pin "EU2T1.7"
				( objectStatus "@baseboard_fab2_lib.baseboard_fab2(sch_1):page198_i1:g" )
			)
			( pin "EU2T1.4"
				( objectStatus "@baseboard_fab2_lib.baseboard_fab2(sch_1):page198_i1:gnd" )
			)
			( pin "EU2T1.2"
				( objectStatus "@baseboard_fab2_lib.baseboard_fab2(sch_1):page198_i1:\on\" )
			)
			( pin "EU2T1.8"
				( objectStatus "@baseboard_fab2_lib.baseboard_fab2(sch_1):page198_i1:pg" )
			)
			( pin "EU2T1.6"
				( objectStatus "@baseboard_fab2_lib.baseboard_fab2(sch_1):page198_i1:s" )
			)
			( pin "EU2T1.3"
				( objectStatus "@baseboard_fab2_lib.baseboard_fab2(sch_1):page198_i1:shdn_n" )
			)
			( pin "EU2T1.9"
				( objectStatus "@baseboard_fab2_lib.baseboard_fab2(sch_1):page198_i1:thpad" )
			)
			( pin "EU2T1.1"
				( objectStatus "@baseboard_fab2_lib.baseboard_fab2(sch_1):page198_i1:vcc" )
			)
			( pin "EU8B1.5"
				( objectStatus "@baseboard_fab2_lib.baseboard_fab2(sch_1):page198_i13:d" )
			)
			( pin "EU8B1.7"
				( objectStatus "@baseboard_fab2_lib.baseboard_fab2(sch_1):page198_i13:g" )
			)
			( pin "EU8B1.4"
				( objectStatus "@baseboard_fab2_lib.baseboard_fab2(sch_1):page198_i13:gnd" )
			)
			( pin "EU8B1.2"
				( objectStatus "@baseboard_fab2_lib.baseboard_fab2(sch_1):page198_i13:\on\" )
			)
			( pin "EU8B1.8"
				( objectStatus "@baseboard_fab2_lib.baseboard_fab2(sch_1):page198_i13:pg" )
			)
			( pin "EU8B1.6"
				( objectStatus "@baseboard_fab2_lib.baseboard_fab2(sch_1):page198_i13:s" )
			)
			( pin "EU8B1.3"
				( objectStatus "@baseboard_fab2_lib.baseboard_fab2(sch_1):page198_i13:shdn_n" )
			)
			( pin "EU8B1.9"
				( objectStatus "@baseboard_fab2_lib.baseboard_fab2(sch_1):page198_i13:thpad" )
			)
			( pin "EU8B1.1"
				( objectStatus "@baseboard_fab2_lib.baseboard_fab2(sch_1):page198_i13:vcc" )
			)
			( pin "EU7E1.5"
				( objectStatus "@baseboard_fab2_lib.baseboard_fab2(sch_1):page198_i19:d" )
			)
			( pin "EU7E1.7"
				( objectStatus "@baseboard_fab2_lib.baseboard_fab2(sch_1):page198_i19:g" )
			)
			( pin "EU7E1.4"
				( objectStatus "@baseboard_fab2_lib.baseboard_fab2(sch_1):page198_i19:gnd" )
			)
			( pin "EU7E1.2"
				( objectStatus "@baseboard_fab2_lib.baseboard_fab2(sch_1):page198_i19:\on\" )
			)
			( pin "EU7E1.8"
				( objectStatus "@baseboard_fab2_lib.baseboard_fab2(sch_1):page198_i19:pg" )
			)
			( pin "EU7E1.6"
				( objectStatus "@baseboard_fab2_lib.baseboard_fab2(sch_1):page198_i19:s" )
			)
			( pin "EU7E1.3"
				( objectStatus "@baseboard_fab2_lib.baseboard_fab2(sch_1):page198_i19:shdn_n" )
			)
			( pin "EU7E1.9"
				( objectStatus "@baseboard_fab2_lib.baseboard_fab2(sch_1):page198_i19:thpad" )
			)
			( pin "EU7E1.1"
				( objectStatus "@baseboard_fab2_lib.baseboard_fab2(sch_1):page198_i19:vcc" )
			)
			( pin "C8F17.1"
				( objectStatus "@baseboard_fab2_lib.baseboard_fab2(sch_1):page198_i24:a" )
			)
			( pin "C8F17.2"
				( objectStatus "@baseboard_fab2_lib.baseboard_fab2(sch_1):page198_i24:b" )
			)
			( pin "C8B8.1"
				( objectStatus "@baseboard_fab2_lib.baseboard_fab2(sch_1):page198_i26:a" )
			)
			( pin "C8B8.2"
				( objectStatus "@baseboard_fab2_lib.baseboard_fab2(sch_1):page198_i26:b" )
			)
			( pin "C8E19.1"
				( objectStatus "@baseboard_fab2_lib.baseboard_fab2(sch_1):page198_i28:a" )
			)
			( pin "C8E19.2"
				( objectStatus "@baseboard_fab2_lib.baseboard_fab2(sch_1):page198_i28:b" )
			)
			( pin "C8B5.1"
				( objectStatus "@baseboard_fab2_lib.baseboard_fab2(sch_1):page198_i37:a" )
			)
			( pin "C8B5.2"
				( objectStatus "@baseboard_fab2_lib.baseboard_fab2(sch_1):page198_i37:b" )
			)
			( pin "C8B12.1"
				( objectStatus "@baseboard_fab2_lib.baseboard_fab2(sch_1):page198_i38:a" )
			)
			( pin "C8B12.2"
				( objectStatus "@baseboard_fab2_lib.baseboard_fab2(sch_1):page198_i38:b" )
			)
			( pin "C8B6.1"
				( objectStatus "@baseboard_fab2_lib.baseboard_fab2(sch_1):page198_i40:a" )
			)
			( pin "C8B6.2"
				( objectStatus "@baseboard_fab2_lib.baseboard_fab2(sch_1):page198_i40:b" )
			)
			( pin "C8B7.1"
				( objectStatus "@baseboard_fab2_lib.baseboard_fab2(sch_1):page198_i41:a" )
			)
			( pin "C8B7.2"
				( objectStatus "@baseboard_fab2_lib.baseboard_fab2(sch_1):page198_i41:b" )
			)
			( pin "C2T36.1"
				( objectStatus "@baseboard_fab2_lib.baseboard_fab2(sch_1):page198_i43:a" )
			)
			( pin "C2T36.2"
				( objectStatus "@baseboard_fab2_lib.baseboard_fab2(sch_1):page198_i43:b" )
			)
			( pin "C2U1.1"
				( objectStatus "@baseboard_fab2_lib.baseboard_fab2(sch_1):page198_i44:a" )
			)
			( pin "C2U1.2"
				( objectStatus "@baseboard_fab2_lib.baseboard_fab2(sch_1):page198_i44:b" )
			)
			( pin "C2U19.1"
				( objectStatus "@baseboard_fab2_lib.baseboard_fab2(sch_1):page198_i46:a" )
			)
			( pin "C2U19.2"
				( objectStatus "@baseboard_fab2_lib.baseboard_fab2(sch_1):page198_i46:b" )
			)
			( pin "C2U2.1"
				( objectStatus "@baseboard_fab2_lib.baseboard_fab2(sch_1):page198_i47:a" )
			)
			( pin "C2U2.2"
				( objectStatus "@baseboard_fab2_lib.baseboard_fab2(sch_1):page198_i47:b" )
			)
			( pin "C7E9.1"
				( objectStatus "@baseboard_fab2_lib.baseboard_fab2(sch_1):page198_i49:a" )
			)
			( pin "C7E9.2"
				( objectStatus "@baseboard_fab2_lib.baseboard_fab2(sch_1):page198_i49:b" )
			)
			( pin "C7E8.1"
				( objectStatus "@baseboard_fab2_lib.baseboard_fab2(sch_1):page198_i50:a" )
			)
			( pin "C7E8.2"
				( objectStatus "@baseboard_fab2_lib.baseboard_fab2(sch_1):page198_i50:b" )
			)
			( pin "C7E5.1"
				( objectStatus "@baseboard_fab2_lib.baseboard_fab2(sch_1):page198_i52:a" )
			)
			( pin "C7E5.2"
				( objectStatus "@baseboard_fab2_lib.baseboard_fab2(sch_1):page198_i52:b" )
			)
			( pin "C7E6.1"
				( objectStatus "@baseboard_fab2_lib.baseboard_fab2(sch_1):page198_i53:a" )
			)
			( pin "C7E6.2"
				( objectStatus "@baseboard_fab2_lib.baseboard_fab2(sch_1):page198_i53:b" )
			)
			( pin "C1B18.1"
				( objectStatus "@baseboard_fab2_lib.baseboard_fab2(sch_1):page198_i61:a" )
			)
			( pin "C1B18.2"
				( objectStatus "@baseboard_fab2_lib.baseboard_fab2(sch_1):page198_i61:b" )
			)
			( pin "C1B19.1"
				( objectStatus "@baseboard_fab2_lib.baseboard_fab2(sch_1):page198_i64:a" )
			)
			( pin "C1B19.2"
				( objectStatus "@baseboard_fab2_lib.baseboard_fab2(sch_1):page198_i64:b" )
			)
			( pin "C9M6.1"
				( objectStatus "@baseboard_fab2_lib.baseboard_fab2(sch_1):page198_i67:a" )
			)
			( pin "C9M6.2"
				( objectStatus "@baseboard_fab2_lib.baseboard_fab2(sch_1):page198_i67:b" )
			)
			( pin "EU9M1.5"
				( objectStatus "@baseboard_fab2_lib.baseboard_fab2(sch_1):page198_i69:d" )
			)
			( pin "EU9M1.7"
				( objectStatus "@baseboard_fab2_lib.baseboard_fab2(sch_1):page198_i69:g" )
			)
			( pin "EU9M1.4"
				( objectStatus "@baseboard_fab2_lib.baseboard_fab2(sch_1):page198_i69:gnd" )
			)
			( pin "EU9M1.2"
				( objectStatus "@baseboard_fab2_lib.baseboard_fab2(sch_1):page198_i69:\on\" )
			)
			( pin "EU9M1.8"
				( objectStatus "@baseboard_fab2_lib.baseboard_fab2(sch_1):page198_i69:pg" )
			)
			( pin "EU9M1.6"
				( objectStatus "@baseboard_fab2_lib.baseboard_fab2(sch_1):page198_i69:s" )
			)
			( pin "EU9M1.3"
				( objectStatus "@baseboard_fab2_lib.baseboard_fab2(sch_1):page198_i69:shdn_n" )
			)
			( pin "EU9M1.9"
				( objectStatus "@baseboard_fab2_lib.baseboard_fab2(sch_1):page198_i69:thpad" )
			)
			( pin "EU9M1.1"
				( objectStatus "@baseboard_fab2_lib.baseboard_fab2(sch_1):page198_i69:vcc" )
			)
			( pin "C9M10.1"
				( objectStatus "@baseboard_fab2_lib.baseboard_fab2(sch_1):page198_i74:a" )
			)
			( pin "C9M10.2"
				( objectStatus "@baseboard_fab2_lib.baseboard_fab2(sch_1):page198_i74:b" )
			)
			( pin "C9M9.1"
				( objectStatus "@baseboard_fab2_lib.baseboard_fab2(sch_1):page198_i76:a" )
			)
			( pin "C9M9.2"
				( objectStatus "@baseboard_fab2_lib.baseboard_fab2(sch_1):page198_i76:b" )
			)
			( pin "R8E12.1"
				( objectStatus "@baseboard_fab2_lib.baseboard_fab2(sch_1):page198_i78:a" )
			)
			( pin "R8E12.2"
				( objectStatus "@baseboard_fab2_lib.baseboard_fab2(sch_1):page198_i78:b" )
			)
			( pin "R8B4.1"
				( objectStatus "@baseboard_fab2_lib.baseboard_fab2(sch_1):page198_i83:a" )
			)
			( pin "R8B4.2"
				( objectStatus "@baseboard_fab2_lib.baseboard_fab2(sch_1):page198_i83:b" )
			)
			( pin "Q8G1.5"
				( objectStatus "@baseboard_fab2_lib.baseboard_fab2(sch_1):page198_i85:drn" )
			)
			( pin "Q8G1.4"
				( objectStatus "@baseboard_fab2_lib.baseboard_fab2(sch_1):page198_i85:gate" )
			)
			( pin "Q8G1.1"
				( objectStatus "@baseboard_fab2_lib.baseboard_fab2(sch_1):page198_i85:src" )
			)
			( pin "Q1B1.5"
				( objectStatus "@baseboard_fab2_lib.baseboard_fab2(sch_1):page198_i86:drn" )
			)
			( pin "Q1B1.4"
				( objectStatus "@baseboard_fab2_lib.baseboard_fab2(sch_1):page198_i86:gate" )
			)
			( pin "Q1B1.1"
				( objectStatus "@baseboard_fab2_lib.baseboard_fab2(sch_1):page198_i86:src" )
			)
			( pin "Q8B1.5"
				( objectStatus "@baseboard_fab2_lib.baseboard_fab2(sch_1):page198_i87:drn" )
			)
			( pin "Q8B1.4"
				( objectStatus "@baseboard_fab2_lib.baseboard_fab2(sch_1):page198_i87:gate" )
			)
			( pin "Q8B1.1"
				( objectStatus "@baseboard_fab2_lib.baseboard_fab2(sch_1):page198_i87:src" )
			)
			( pin "Q7E7.5"
				( objectStatus "@baseboard_fab2_lib.baseboard_fab2(sch_1):page198_i88:drn" )
			)
			( pin "Q7E7.4"
				( objectStatus "@baseboard_fab2_lib.baseboard_fab2(sch_1):page198_i88:gate" )
			)
			( pin "Q7E7.1"
				( objectStatus "@baseboard_fab2_lib.baseboard_fab2(sch_1):page198_i88:src" )
			)
			( pin "R9P30.1"
				( objectStatus "@baseboard_fab2_lib.baseboard_fab2(sch_1):page199_i2:a" )
			)
			( pin "R9P30.2"
				( objectStatus "@baseboard_fab2_lib.baseboard_fab2(sch_1):page199_i2:b" )
			)
			( pin "C1D25.1"
				( objectStatus "@baseboard_fab2_lib.baseboard_fab2(sch_1):page199_i3:a" )
			)
			( pin "C1D25.2"
				( objectStatus "@baseboard_fab2_lib.baseboard_fab2(sch_1):page199_i3:b" )
			)
			( pin "R9P28.1"
				( objectStatus "@baseboard_fab2_lib.baseboard_fab2(sch_1):page199_i6:a" )
			)
			( pin "R9P28.2"
				( objectStatus "@baseboard_fab2_lib.baseboard_fab2(sch_1):page199_i6:b" )
			)
			( pin "C1D27.1"
				( objectStatus "@baseboard_fab2_lib.baseboard_fab2(sch_1):page199_i7:a" )
			)
			( pin "C1D27.2"
				( objectStatus "@baseboard_fab2_lib.baseboard_fab2(sch_1):page199_i7:b" )
			)
			( pin "R1D43.1"
				( objectStatus "@baseboard_fab2_lib.baseboard_fab2(sch_1):page199_i9:a" )
			)
			( pin "R1D43.2"
				( objectStatus "@baseboard_fab2_lib.baseboard_fab2(sch_1):page199_i9:b" )
			)
			( pin "EU1D2.7"
				( objectStatus "@baseboard_fab2_lib.baseboard_fab2(sch_1):page199_i10:adr1" )
			)
			( pin "EU1D2.8"
				( objectStatus "@baseboard_fab2_lib.baseboard_fab2(sch_1):page199_i10:adr2" )
			)
			( pin "EU1D2.19"
				( objectStatus "@baseboard_fab2_lib.baseboard_fab2(sch_1):page199_i10:csout" )
			)
			( pin "EU1D2.12"
				( objectStatus "@baseboard_fab2_lib.baseboard_fab2(sch_1):page199_i10:enable" )
			)
			( pin "EU1D2.33"
				( objectStatus "@baseboard_fab2_lib.baseboard_fab2(sch_1):page199_i10:ep" )
			)
			( pin "EU1D2.6"
				( objectStatus "@baseboard_fab2_lib.baseboard_fab2(sch_1):page199_i10:fault_n" )
			)
			( pin "EU1D2.24"
				( objectStatus "@baseboard_fab2_lib.baseboard_fab2(sch_1):page199_i10:gate" )
			)
			( pin "EU1D2.22"
				( objectStatus "@baseboard_fab2_lib.baseboard_fab2(sch_1):page199_i10:gnd" )
			)
			( pin "EU1D2.13"
				( objectStatus "@baseboard_fab2_lib.baseboard_fab2(sch_1):page199_i10:gpo1_alert1_n_conv" )
			)
			( pin "EU1D2.14"
				( objectStatus "@baseboard_fab2_lib.baseboard_fab2(sch_1):page199_i10:gpo2_alert2_n" )
			)
			( pin "EU1D2.27"
				( objectStatus "@baseboard_fab2_lib.baseboard_fab2(sch_1):page199_i10:hsn" )
			)
			( pin "EU1D2.28"
				( objectStatus "@baseboard_fab2_lib.baseboard_fab2(sch_1):page199_i10:hsp" )
			)
			( pin "EU1D2.3"
				( objectStatus "@baseboard_fab2_lib.baseboard_fab2(sch_1):page199_i10:iset" )
			)
			( pin "EU1D2.4"
				( objectStatus "@baseboard_fab2_lib.baseboard_fab2(sch_1):page199_i10:istart" )
			)
			( pin "EU1D2.10"
				( objectStatus "@baseboard_fab2_lib.baseboard_fab2(sch_1):page199_i10:mclk" )
			)
			( pin "EU1D2.11"
				( objectStatus "@baseboard_fab2_lib.baseboard_fab2(sch_1):page199_i10:mdat" )
			)
			( pin "EU1D2.26"
				( objectStatus "@baseboard_fab2_lib.baseboard_fab2(sch_1):page199_i10:mon" )
			)
			( pin "EU1D2.29"
				( objectStatus "@baseboard_fab2_lib.baseboard_fab2(sch_1):page199_i10:mop" )
			)
			( pin "EU1D2.32"
				( objectStatus "@baseboard_fab2_lib.baseboard_fab2(sch_1):page199_i10:ov" )
			)
			( pin "EU1D2.23"
				( objectStatus "@baseboard_fab2_lib.baseboard_fab2(sch_1):page199_i10:pgnd" )
			)
			( pin "EU1D2.1"
				( objectStatus "@baseboard_fab2_lib.baseboard_fab2(sch_1):page199_i10:pset" )
			)
			( pin "EU1D2.21"
				( objectStatus "@baseboard_fab2_lib.baseboard_fab2(sch_1):page199_i10:pwgin" )
			)
			( pin "EU1D2.18"
				( objectStatus "@baseboard_fab2_lib.baseboard_fab2(sch_1):page199_i10:pwrgd" )
			)
			( pin "EU1D2.17"
				( objectStatus "@baseboard_fab2_lib.baseboard_fab2(sch_1):page199_i10:retry_n" )
			)
			( pin "EU1D2.16"
				( objectStatus "@baseboard_fab2_lib.baseboard_fab2(sch_1):page199_i10:scl" )
			)
			( pin "EU1D2.15"
				( objectStatus "@baseboard_fab2_lib.baseboard_fab2(sch_1):page199_i10:sda" )
			)
			( pin "EU1D2.9"
				( objectStatus "@baseboard_fab2_lib.baseboard_fab2(sch_1):page199_i10:spiss_n" )
			)
			( pin "EU1D2.25"
				( objectStatus "@baseboard_fab2_lib.baseboard_fab2(sch_1):page199_i10:temp" )
			)
			( pin "EU1D2.5"
				( objectStatus "@baseboard_fab2_lib.baseboard_fab2(sch_1):page199_i10:timer" )
			)
			( pin "EU1D2.31"
				( objectStatus "@baseboard_fab2_lib.baseboard_fab2(sch_1):page199_i10:uv" )
			)
			( pin "EU1D2.2"
				( objectStatus "@baseboard_fab2_lib.baseboard_fab2(sch_1):page199_i10:vcap" )
			)
			( pin "EU1D2.30"
				( objectStatus "@baseboard_fab2_lib.baseboard_fab2(sch_1):page199_i10:vcc" )
			)
			( pin "EU1D2.20"
				( objectStatus "@baseboard_fab2_lib.baseboard_fab2(sch_1):page199_i10:vout" )
			)
			( pin "R9P29.1"
				( objectStatus "@baseboard_fab2_lib.baseboard_fab2(sch_1):page199_i12:a" )
			)
			( pin "R9P29.2"
				( objectStatus "@baseboard_fab2_lib.baseboard_fab2(sch_1):page199_i12:b" )
			)
			( pin "R1D42.1"
				( objectStatus "@baseboard_fab2_lib.baseboard_fab2(sch_1):page199_i13:a" )
			)
			( pin "R1D42.2"
				( objectStatus "@baseboard_fab2_lib.baseboard_fab2(sch_1):page199_i13:b" )
			)
			( pin "R1D37.1"
				( objectStatus "@baseboard_fab2_lib.baseboard_fab2(sch_1):page199_i15:a" )
			)
			( pin "R1D37.2"
				( objectStatus "@baseboard_fab2_lib.baseboard_fab2(sch_1):page199_i15:b" )
			)
			( pin "R1D39.1"
				( objectStatus "@baseboard_fab2_lib.baseboard_fab2(sch_1):page199_i16:a" )
			)
			( pin "R1D39.2"
				( objectStatus "@baseboard_fab2_lib.baseboard_fab2(sch_1):page199_i16:b" )
			)
			( pin "R1D32.1"
				( objectStatus "@baseboard_fab2_lib.baseboard_fab2(sch_1):page199_i17:a" )
			)
			( pin "R1D32.2"
				( objectStatus "@baseboard_fab2_lib.baseboard_fab2(sch_1):page199_i17:b" )
			)
			( pin "R1D41.1"
				( objectStatus "@baseboard_fab2_lib.baseboard_fab2(sch_1):page199_i19:a" )
			)
			( pin "R1D41.2"
				( objectStatus "@baseboard_fab2_lib.baseboard_fab2(sch_1):page199_i19:b" )
			)
			( pin "C9P14.1"
				( objectStatus "@baseboard_fab2_lib.baseboard_fab2(sch_1):page199_i24:a" )
			)
			( pin "C9P14.2"
				( objectStatus "@baseboard_fab2_lib.baseboard_fab2(sch_1):page199_i24:b" )
			)
			( pin "R1D28.1"
				( objectStatus "@baseboard_fab2_lib.baseboard_fab2(sch_1):page199_i26:a" )
			)
			( pin "R1D28.2"
				( objectStatus "@baseboard_fab2_lib.baseboard_fab2(sch_1):page199_i26:b" )
			)
			( pin "R1D24.1"
				( objectStatus "@baseboard_fab2_lib.baseboard_fab2(sch_1):page199_i27:a" )
			)
			( pin "R1D24.2"
				( objectStatus "@baseboard_fab2_lib.baseboard_fab2(sch_1):page199_i27:b" )
			)
			( pin "R1D25.1"
				( objectStatus "@baseboard_fab2_lib.baseboard_fab2(sch_1):page199_i28:a" )
			)
			( pin "R1D25.2"
				( objectStatus "@baseboard_fab2_lib.baseboard_fab2(sch_1):page199_i28:b" )
			)
			( pin "R9P17.1"
				( objectStatus "@baseboard_fab2_lib.baseboard_fab2(sch_1):page199_i33:a" )
			)
			( pin "R9P17.2"
				( objectStatus "@baseboard_fab2_lib.baseboard_fab2(sch_1):page199_i33:b" )
			)
			( pin "R9P16.1"
				( objectStatus "@baseboard_fab2_lib.baseboard_fab2(sch_1):page199_i36:a" )
			)
			( pin "R9P16.2"
				( objectStatus "@baseboard_fab2_lib.baseboard_fab2(sch_1):page199_i36:b" )
			)
			( pin "R1D29.1"
				( objectStatus "@baseboard_fab2_lib.baseboard_fab2(sch_1):page199_i37:a" )
			)
			( pin "R1D29.2"
				( objectStatus "@baseboard_fab2_lib.baseboard_fab2(sch_1):page199_i37:b" )
			)
			( pin "R1D27.1"
				( objectStatus "@baseboard_fab2_lib.baseboard_fab2(sch_1):page199_i38:a" )
			)
			( pin "R1D27.2"
				( objectStatus "@baseboard_fab2_lib.baseboard_fab2(sch_1):page199_i38:b" )
			)
			( pin "R9P18.1"
				( objectStatus "@baseboard_fab2_lib.baseboard_fab2(sch_1):page199_i41:a" )
			)
			( pin "R9P18.2"
				( objectStatus "@baseboard_fab2_lib.baseboard_fab2(sch_1):page199_i41:b" )
			)
			( pin "R1D31.1"
				( objectStatus "@baseboard_fab2_lib.baseboard_fab2(sch_1):page199_i43:a" )
			)
			( pin "R1D31.2"
				( objectStatus "@baseboard_fab2_lib.baseboard_fab2(sch_1):page199_i43:b" )
			)
			( pin "C1D11.1"
				( objectStatus "@baseboard_fab2_lib.baseboard_fab2(sch_1):page199_i53:a" )
			)
			( pin "C1D11.2"
				( objectStatus "@baseboard_fab2_lib.baseboard_fab2(sch_1):page199_i53:b" )
			)
			( pin "R9P23.1"
				( objectStatus "@baseboard_fab2_lib.baseboard_fab2(sch_1):page199_i54:a" )
			)
			( pin "R9P23.2"
				( objectStatus "@baseboard_fab2_lib.baseboard_fab2(sch_1):page199_i54:b" )
			)
			( pin "R9P24.1"
				( objectStatus "@baseboard_fab2_lib.baseboard_fab2(sch_1):page199_i55:a" )
			)
			( pin "R9P24.2"
				( objectStatus "@baseboard_fab2_lib.baseboard_fab2(sch_1):page199_i55:b" )
			)
			( pin "Q1D3.1"
				( objectStatus "@baseboard_fab2_lib.baseboard_fab2(sch_1):page199_i58:b" )
			)
			( pin "Q1D3.3"
				( objectStatus "@baseboard_fab2_lib.baseboard_fab2(sch_1):page199_i58:c" )
			)
			( pin "Q1D3.2"
				( objectStatus "@baseboard_fab2_lib.baseboard_fab2(sch_1):page199_i58:e" )
			)
			( pin "R1D36.1"
				( objectStatus "@baseboard_fab2_lib.baseboard_fab2(sch_1):page199_i65:a" )
			)
			( pin "R1D36.2"
				( objectStatus "@baseboard_fab2_lib.baseboard_fab2(sch_1):page199_i65:b" )
			)
			( pin "C9P12.1"
				( objectStatus "@baseboard_fab2_lib.baseboard_fab2(sch_1):page199_i67:a" )
			)
			( pin "C9P12.2"
				( objectStatus "@baseboard_fab2_lib.baseboard_fab2(sch_1):page199_i67:b" )
			)
			( pin "Q1D1.3"
				( objectStatus "@baseboard_fab2_lib.baseboard_fab2(sch_1):page199_i82:drain(0)" )
			)
			( pin "Q1D1.5"
				( objectStatus "@baseboard_fab2_lib.baseboard_fab2(sch_1):page199_i82:gate(0)" )
			)
			( pin "Q1D1.4"
				( objectStatus "@baseboard_fab2_lib.baseboard_fab2(sch_1):page199_i82:source(0)" )
			)
			( pin "R1D13.1"
				( objectStatus "@baseboard_fab2_lib.baseboard_fab2(sch_1):page199_i84:a" )
			)
			( pin "R1D13.2"
				( objectStatus "@baseboard_fab2_lib.baseboard_fab2(sch_1):page199_i84:b" )
			)
			( pin "R1D16.1"
				( objectStatus "@baseboard_fab2_lib.baseboard_fab2(sch_1):page199_i85:a" )
			)
			( pin "R1D16.2"
				( objectStatus "@baseboard_fab2_lib.baseboard_fab2(sch_1):page199_i85:b" )
			)
			( pin "Q1D1.6"
				( objectStatus "@baseboard_fab2_lib.baseboard_fab2(sch_1):page199_i86:drain(0)" )
			)
			( pin "Q1D1.2"
				( objectStatus "@baseboard_fab2_lib.baseboard_fab2(sch_1):page199_i86:gate(0)" )
			)
			( pin "Q1D1.1"
				( objectStatus "@baseboard_fab2_lib.baseboard_fab2(sch_1):page199_i86:source(0)" )
			)
			( pin "R1D18.1"
				( objectStatus "@baseboard_fab2_lib.baseboard_fab2(sch_1):page199_i87:a" )
			)
			( pin "R1D18.2"
				( objectStatus "@baseboard_fab2_lib.baseboard_fab2(sch_1):page199_i87:b" )
			)
			( pin "R1D11.1"
				( objectStatus "@baseboard_fab2_lib.baseboard_fab2(sch_1):page199_i88:a" )
			)
			( pin "R1D11.2"
				( objectStatus "@baseboard_fab2_lib.baseboard_fab2(sch_1):page199_i88:b" )
			)
			( pin "R1D15.1"
				( objectStatus "@baseboard_fab2_lib.baseboard_fab2(sch_1):page199_i92:a" )
			)
			( pin "R1D15.2"
				( objectStatus "@baseboard_fab2_lib.baseboard_fab2(sch_1):page199_i92:b" )
			)
			( pin "VR1D1.2"
				( objectStatus "@baseboard_fab2_lib.baseboard_fab2(sch_1):page199_i99:a" )
			)
			( pin "VR1D1.1"
				( objectStatus "@baseboard_fab2_lib.baseboard_fab2(sch_1):page199_i99:c" )
			)
			( pin "R1D40.1"
				( objectStatus "@baseboard_fab2_lib.baseboard_fab2(sch_1):page199_i100:a" )
			)
			( pin "R1D40.2"
				( objectStatus "@baseboard_fab2_lib.baseboard_fab2(sch_1):page199_i100:b" )
			)
			( pin "R1D34.1"
				( objectStatus "@baseboard_fab2_lib.baseboard_fab2(sch_1):page199_i102:a" )
			)
			( pin "R1D34.2"
				( objectStatus "@baseboard_fab2_lib.baseboard_fab2(sch_1):page199_i102:b" )
			)
			( pin "C9P15.1"
				( objectStatus "@baseboard_fab2_lib.baseboard_fab2(sch_1):page199_i105:a" )
			)
			( pin "C9P15.2"
				( objectStatus "@baseboard_fab2_lib.baseboard_fab2(sch_1):page199_i105:b" )
			)
			( pin "C1D26.1"
				( objectStatus "@baseboard_fab2_lib.baseboard_fab2(sch_1):page199_i107:a" )
			)
			( pin "C1D26.2"
				( objectStatus "@baseboard_fab2_lib.baseboard_fab2(sch_1):page199_i107:b" )
			)
			( pin "R1D33.1"
				( objectStatus "@baseboard_fab2_lib.baseboard_fab2(sch_1):page199_i108:a" )
			)
			( pin "R1D33.2"
				( objectStatus "@baseboard_fab2_lib.baseboard_fab2(sch_1):page199_i108:b" )
			)
			( pin "R1D26.1"
				( objectStatus "@baseboard_fab2_lib.baseboard_fab2(sch_1):page199_i109:a" )
			)
			( pin "R1D26.2"
				( objectStatus "@baseboard_fab2_lib.baseboard_fab2(sch_1):page199_i109:b" )
			)
			( pin "R1D30.1"
				( objectStatus "@baseboard_fab2_lib.baseboard_fab2(sch_1):page199_i110:a" )
			)
			( pin "R1D30.2"
				( objectStatus "@baseboard_fab2_lib.baseboard_fab2(sch_1):page199_i110:b" )
			)
			( pin "C1D19.1"
				( objectStatus "@baseboard_fab2_lib.baseboard_fab2(sch_1):page199_i119:a" )
			)
			( pin "C1D19.2"
				( objectStatus "@baseboard_fab2_lib.baseboard_fab2(sch_1):page199_i119:b" )
			)
			( pin "C1D21.1"
				( objectStatus "@baseboard_fab2_lib.baseboard_fab2(sch_1):page199_i121:a" )
			)
			( pin "C1D21.2"
				( objectStatus "@baseboard_fab2_lib.baseboard_fab2(sch_1):page199_i121:b" )
			)
			( pin "J1B3.1"
				( objectStatus "@baseboard_fab2_lib.baseboard_fab2(sch_1):page199_i123:io1" )
			)
			( pin "J1B3.2"
				( objectStatus "@baseboard_fab2_lib.baseboard_fab2(sch_1):page199_i123:io2" )
			)
			( pin "J1B3.3"
				( objectStatus "@baseboard_fab2_lib.baseboard_fab2(sch_1):page199_i123:io3" )
			)
			( pin "J1B4.1"
				( objectStatus "@baseboard_fab2_lib.baseboard_fab2(sch_1):page199_i124:io1" )
			)
			( pin "J1B4.2"
				( objectStatus "@baseboard_fab2_lib.baseboard_fab2(sch_1):page199_i124:io2" )
			)
			( pin "J1B4.3"
				( objectStatus "@baseboard_fab2_lib.baseboard_fab2(sch_1):page199_i124:io3" )
			)
			( pin "C9P17.1"
				( objectStatus "@baseboard_fab2_lib.baseboard_fab2(sch_1):page200_i36:a" )
			)
			( pin "C9P17.2"
				( objectStatus "@baseboard_fab2_lib.baseboard_fab2(sch_1):page200_i36:b" )
			)
			( pin "C9P16.1"
				( objectStatus "@baseboard_fab2_lib.baseboard_fab2(sch_1):page200_i40:a" )
			)
			( pin "C9P16.2"
				( objectStatus "@baseboard_fab2_lib.baseboard_fab2(sch_1):page200_i40:b" )
			)
			( pin "C1D22.1"
				( objectStatus "@baseboard_fab2_lib.baseboard_fab2(sch_1):page200_i42:a" )
			)
			( pin "C1D22.2"
				( objectStatus "@baseboard_fab2_lib.baseboard_fab2(sch_1):page200_i42:b" )
			)
			( pin "R1D45.1"
				( objectStatus "@baseboard_fab2_lib.baseboard_fab2(sch_1):page200_i43:a" )
			)
			( pin "R1D45.2"
				( objectStatus "@baseboard_fab2_lib.baseboard_fab2(sch_1):page200_i43:b" )
			)
			( pin "R1D44.1"
				( objectStatus "@baseboard_fab2_lib.baseboard_fab2(sch_1):page200_i44:a" )
			)
			( pin "R1D44.2"
				( objectStatus "@baseboard_fab2_lib.baseboard_fab2(sch_1):page200_i44:b" )
			)
			( pin "R9P27.1"
				( objectStatus "@baseboard_fab2_lib.baseboard_fab2(sch_1):page200_i47:a" )
			)
			( pin "R9P27.2"
				( objectStatus "@baseboard_fab2_lib.baseboard_fab2(sch_1):page200_i47:b" )
			)
			( pin "R1D46.1"
				( objectStatus "@baseboard_fab2_lib.baseboard_fab2(sch_1):page200_i48:a" )
			)
			( pin "R1D46.2"
				( objectStatus "@baseboard_fab2_lib.baseboard_fab2(sch_1):page200_i48:b" )
			)
			( pin "R9R1.1"
				( objectStatus "@baseboard_fab2_lib.baseboard_fab2(sch_1):page200_i49:\1\" )
			)
			( pin "R9R1.2"
				( objectStatus "@baseboard_fab2_lib.baseboard_fab2(sch_1):page200_i49:\2\" )
			)
			( pin "R9R1.3"
				( objectStatus "@baseboard_fab2_lib.baseboard_fab2(sch_1):page200_i49:\3\" )
			)
			( pin "R9R1.4"
				( objectStatus "@baseboard_fab2_lib.baseboard_fab2(sch_1):page200_i49:\4\" )
			)
			( pin "R9R1.5"
				( objectStatus "@baseboard_fab2_lib.baseboard_fab2(sch_1):page200_i49:\5\" )
			)
			( pin "R9R1.6"
				( objectStatus "@baseboard_fab2_lib.baseboard_fab2(sch_1):page200_i49:\6\" )
			)
			( pin "R1D49.1"
				( objectStatus "@baseboard_fab2_lib.baseboard_fab2(sch_1):page200_i50:\1\" )
			)
			( pin "R1D49.2"
				( objectStatus "@baseboard_fab2_lib.baseboard_fab2(sch_1):page200_i50:\2\" )
			)
			( pin "R1D49.3"
				( objectStatus "@baseboard_fab2_lib.baseboard_fab2(sch_1):page200_i50:\3\" )
			)
			( pin "R1D49.4"
				( objectStatus "@baseboard_fab2_lib.baseboard_fab2(sch_1):page200_i50:\4\" )
			)
			( pin "R1D49.5"
				( objectStatus "@baseboard_fab2_lib.baseboard_fab2(sch_1):page200_i50:\5\" )
			)
			( pin "R1D49.6"
				( objectStatus "@baseboard_fab2_lib.baseboard_fab2(sch_1):page200_i50:\6\" )
			)
			( pin "R9P26.1"
				( objectStatus "@baseboard_fab2_lib.baseboard_fab2(sch_1):page200_i51:a" )
			)
			( pin "R9P26.2"
				( objectStatus "@baseboard_fab2_lib.baseboard_fab2(sch_1):page200_i51:b" )
			)
			( pin "R1D47.1"
				( objectStatus "@baseboard_fab2_lib.baseboard_fab2(sch_1):page200_i52:a" )
			)
			( pin "R1D47.2"
				( objectStatus "@baseboard_fab2_lib.baseboard_fab2(sch_1):page200_i52:b" )
			)
			( pin "EU1E3.5"
				( objectStatus "@baseboard_fab2_lib.baseboard_fab2(sch_1):page200_i54:d" )
			)
			( pin "EU1E3.4"
				( objectStatus "@baseboard_fab2_lib.baseboard_fab2(sch_1):page200_i54:g" )
			)
			( pin "EU1E3.1"
				( objectStatus "@baseboard_fab2_lib.baseboard_fab2(sch_1):page200_i54:s1" )
			)
			( pin "EU1E3.2"
				( objectStatus "@baseboard_fab2_lib.baseboard_fab2(sch_1):page200_i54:s2" )
			)
			( pin "EU1E3.3"
				( objectStatus "@baseboard_fab2_lib.baseboard_fab2(sch_1):page200_i54:s3" )
			)
			( pin "R1E1.1"
				( objectStatus "@baseboard_fab2_lib.baseboard_fab2(sch_1):page200_i56:a" )
			)
			( pin "R1E1.2"
				( objectStatus "@baseboard_fab2_lib.baseboard_fab2(sch_1):page200_i56:b" )
			)
			( pin "EU9R1.5"
				( objectStatus "@baseboard_fab2_lib.baseboard_fab2(sch_1):page200_i57:d" )
			)
			( pin "EU9R1.4"
				( objectStatus "@baseboard_fab2_lib.baseboard_fab2(sch_1):page200_i57:g" )
			)
			( pin "EU9R1.1"
				( objectStatus "@baseboard_fab2_lib.baseboard_fab2(sch_1):page200_i57:s1" )
			)
			( pin "EU9R1.2"
				( objectStatus "@baseboard_fab2_lib.baseboard_fab2(sch_1):page200_i57:s2" )
			)
			( pin "EU9R1.3"
				( objectStatus "@baseboard_fab2_lib.baseboard_fab2(sch_1):page200_i57:s3" )
			)
			( pin "R9R4.1"
				( objectStatus "@baseboard_fab2_lib.baseboard_fab2(sch_1):page200_i58:a" )
			)
			( pin "R9R4.2"
				( objectStatus "@baseboard_fab2_lib.baseboard_fab2(sch_1):page200_i58:b" )
			)
			( pin "EU1E1.5"
				( objectStatus "@baseboard_fab2_lib.baseboard_fab2(sch_1):page200_i59:d" )
			)
			( pin "EU1E1.4"
				( objectStatus "@baseboard_fab2_lib.baseboard_fab2(sch_1):page200_i59:g" )
			)
			( pin "EU1E1.1"
				( objectStatus "@baseboard_fab2_lib.baseboard_fab2(sch_1):page200_i59:s1" )
			)
			( pin "EU1E1.2"
				( objectStatus "@baseboard_fab2_lib.baseboard_fab2(sch_1):page200_i59:s2" )
			)
			( pin "EU1E1.3"
				( objectStatus "@baseboard_fab2_lib.baseboard_fab2(sch_1):page200_i59:s3" )
			)
			( pin "R1D48.1"
				( objectStatus "@baseboard_fab2_lib.baseboard_fab2(sch_1):page200_i60:a" )
			)
			( pin "R1D48.2"
				( objectStatus "@baseboard_fab2_lib.baseboard_fab2(sch_1):page200_i60:b" )
			)
			( pin "R9P19.1"
				( objectStatus "@baseboard_fab2_lib.baseboard_fab2(sch_1):page200_i70:a" )
			)
			( pin "R9P19.2"
				( objectStatus "@baseboard_fab2_lib.baseboard_fab2(sch_1):page200_i70:b" )
			)
			( pin "R9P21.1"
				( objectStatus "@baseboard_fab2_lib.baseboard_fab2(sch_1):page200_i71:a" )
			)
			( pin "R9P21.2"
				( objectStatus "@baseboard_fab2_lib.baseboard_fab2(sch_1):page200_i71:b" )
			)
			( pin "R9P20.1"
				( objectStatus "@baseboard_fab2_lib.baseboard_fab2(sch_1):page200_i86:a" )
			)
			( pin "R9P20.2"
				( objectStatus "@baseboard_fab2_lib.baseboard_fab2(sch_1):page200_i86:b" )
			)
			( pin "U1D1.2"
				( objectStatus "@baseboard_fab2_lib.baseboard_fab2(sch_1):page200_i103:a" )
			)
			( pin "U1D1.1"
				( objectStatus "@baseboard_fab2_lib.baseboard_fab2(sch_1):page200_i103:oe" )
			)
			( pin "U1D1.4"
				( objectStatus "@baseboard_fab2_lib.baseboard_fab2(sch_1):page200_i103:y" )
			)
			( pin "R9P13.1"
				( objectStatus "@baseboard_fab2_lib.baseboard_fab2(sch_1):page200_i107:a" )
			)
			( pin "R9P13.2"
				( objectStatus "@baseboard_fab2_lib.baseboard_fab2(sch_1):page200_i107:b" )
			)
			( pin "R9P11.1"
				( objectStatus "@baseboard_fab2_lib.baseboard_fab2(sch_1):page200_i108:a" )
			)
			( pin "R9P11.2"
				( objectStatus "@baseboard_fab2_lib.baseboard_fab2(sch_1):page200_i108:b" )
			)
			( pin "R9P7.1"
				( objectStatus "@baseboard_fab2_lib.baseboard_fab2(sch_1):page200_i145:a" )
			)
			( pin "R9P7.2"
				( objectStatus "@baseboard_fab2_lib.baseboard_fab2(sch_1):page200_i145:b" )
			)
			( pin "R9P9.1"
				( objectStatus "@baseboard_fab2_lib.baseboard_fab2(sch_1):page200_i146:a" )
			)
			( pin "R9P9.2"
				( objectStatus "@baseboard_fab2_lib.baseboard_fab2(sch_1):page200_i146:b" )
			)
			( pin "R9P6.1"
				( objectStatus "@baseboard_fab2_lib.baseboard_fab2(sch_1):page200_i149:a" )
			)
			( pin "R9P6.2"
				( objectStatus "@baseboard_fab2_lib.baseboard_fab2(sch_1):page200_i149:b" )
			)
			( pin "R1D51.1"
				( objectStatus "@baseboard_fab2_lib.baseboard_fab2(sch_1):page200_i154:a" )
			)
			( pin "R1D51.2"
				( objectStatus "@baseboard_fab2_lib.baseboard_fab2(sch_1):page200_i154:b" )
			)
			( pin "C1E2.1"
				( objectStatus "@baseboard_fab2_lib.baseboard_fab2(sch_1):page200_i155:a" )
			)
			( pin "C1E2.2"
				( objectStatus "@baseboard_fab2_lib.baseboard_fab2(sch_1):page200_i155:b" )
			)
			( pin "R1D22.1"
				( objectStatus "@baseboard_fab2_lib.baseboard_fab2(sch_1):page200_i158:a" )
			)
			( pin "R1D22.2"
				( objectStatus "@baseboard_fab2_lib.baseboard_fab2(sch_1):page200_i158:b" )
			)
			( pin "U9P1.5"
				( objectStatus "@baseboard_fab2_lib.baseboard_fab2(sch_1):page200_i163:gnd" )
			)
			( pin "U9P1.4"
				( objectStatus "@baseboard_fab2_lib.baseboard_fab2(sch_1):page200_i163:inap" )
			)
			( pin "U9P1.3"
				( objectStatus "@baseboard_fab2_lib.baseboard_fab2(sch_1):page200_i163:inbn" )
			)
			( pin "U9P1.6"
				( objectStatus "@baseboard_fab2_lib.baseboard_fab2(sch_1):page200_i163:outa" )
			)
			( pin "U9P1.1"
				( objectStatus "@baseboard_fab2_lib.baseboard_fab2(sch_1):page200_i163:outb" )
			)
			( pin "U9P1.2"
				( objectStatus "@baseboard_fab2_lib.baseboard_fab2(sch_1):page200_i163:vdd" )
			)
			( pin "U1D2.5"
				( objectStatus "@baseboard_fab2_lib.baseboard_fab2(sch_1):page200_i170:gnd" )
			)
			( pin "U1D2.4"
				( objectStatus "@baseboard_fab2_lib.baseboard_fab2(sch_1):page200_i170:inap" )
			)
			( pin "U1D2.3"
				( objectStatus "@baseboard_fab2_lib.baseboard_fab2(sch_1):page200_i170:inbn" )
			)
			( pin "U1D2.6"
				( objectStatus "@baseboard_fab2_lib.baseboard_fab2(sch_1):page200_i170:outa" )
			)
			( pin "U1D2.1"
				( objectStatus "@baseboard_fab2_lib.baseboard_fab2(sch_1):page200_i170:outb" )
			)
			( pin "U1D2.2"
				( objectStatus "@baseboard_fab2_lib.baseboard_fab2(sch_1):page200_i170:vdd" )
			)
			( pin "R1D20.1"
				( objectStatus "@baseboard_fab2_lib.baseboard_fab2(sch_1):page200_i172:a" )
			)
			( pin "R1D20.2"
				( objectStatus "@baseboard_fab2_lib.baseboard_fab2(sch_1):page200_i172:b" )
			)
			( pin "R1D14.1"
				( objectStatus "@baseboard_fab2_lib.baseboard_fab2(sch_1):page200_i173:a" )
			)
			( pin "R1D14.2"
				( objectStatus "@baseboard_fab2_lib.baseboard_fab2(sch_1):page200_i173:b" )
			)
			( pin "R1D12.1"
				( objectStatus "@baseboard_fab2_lib.baseboard_fab2(sch_1):page200_i174:a" )
			)
			( pin "R1D12.2"
				( objectStatus "@baseboard_fab2_lib.baseboard_fab2(sch_1):page200_i174:b" )
			)
			( pin "R1D19.1"
				( objectStatus "@baseboard_fab2_lib.baseboard_fab2(sch_1):page200_i175:a" )
			)
			( pin "R1D19.2"
				( objectStatus "@baseboard_fab2_lib.baseboard_fab2(sch_1):page200_i175:b" )
			)
			( pin "C9P6.1"
				( objectStatus "@baseboard_fab2_lib.baseboard_fab2(sch_1):page200_i185:a" )
			)
			( pin "C9P6.2"
				( objectStatus "@baseboard_fab2_lib.baseboard_fab2(sch_1):page200_i185:b" )
			)
			( pin "C1D9.1"
				( objectStatus "@baseboard_fab2_lib.baseboard_fab2(sch_1):page200_i187:a" )
			)
			( pin "C1D9.2"
				( objectStatus "@baseboard_fab2_lib.baseboard_fab2(sch_1):page200_i187:b" )
			)
			( pin "R1D10.1"
				( objectStatus "@baseboard_fab2_lib.baseboard_fab2(sch_1):page200_i189:a" )
			)
			( pin "R1D10.2"
				( objectStatus "@baseboard_fab2_lib.baseboard_fab2(sch_1):page200_i189:b" )
			)
			( pin "R1D23.1"
				( objectStatus "@baseboard_fab2_lib.baseboard_fab2(sch_1):page200_i191:a" )
			)
			( pin "R1D23.2"
				( objectStatus "@baseboard_fab2_lib.baseboard_fab2(sch_1):page200_i191:b" )
			)
			( pin "R9P10.1"
				( objectStatus "@baseboard_fab2_lib.baseboard_fab2(sch_1):page200_i192:a" )
			)
			( pin "R9P10.2"
				( objectStatus "@baseboard_fab2_lib.baseboard_fab2(sch_1):page200_i192:b" )
			)
			( pin "Q9P1.6"
				( objectStatus "@baseboard_fab2_lib.baseboard_fab2(sch_1):page200_i196:drain(0)" )
			)
			( pin "Q9P1.2"
				( objectStatus "@baseboard_fab2_lib.baseboard_fab2(sch_1):page200_i196:gate(0)" )
			)
			( pin "Q9P1.1"
				( objectStatus "@baseboard_fab2_lib.baseboard_fab2(sch_1):page200_i196:source(0)" )
			)
			( pin "R9P15.1"
				( objectStatus "@baseboard_fab2_lib.baseboard_fab2(sch_1):page200_i198:a" )
			)
			( pin "R9P15.2"
				( objectStatus "@baseboard_fab2_lib.baseboard_fab2(sch_1):page200_i198:b" )
			)
			( pin "Q9P1.3"
				( objectStatus "@baseboard_fab2_lib.baseboard_fab2(sch_1):page200_i199:drain(0)" )
			)
			( pin "Q9P1.5"
				( objectStatus "@baseboard_fab2_lib.baseboard_fab2(sch_1):page200_i199:gate(0)" )
			)
			( pin "Q9P1.4"
				( objectStatus "@baseboard_fab2_lib.baseboard_fab2(sch_1):page200_i199:source(0)" )
			)
			( pin "U9P2.5"
				( objectStatus "@baseboard_fab2_lib.baseboard_fab2(sch_1):page200_i200:gnd" )
			)
			( pin "U9P2.4"
				( objectStatus "@baseboard_fab2_lib.baseboard_fab2(sch_1):page200_i200:inap" )
			)
			( pin "U9P2.3"
				( objectStatus "@baseboard_fab2_lib.baseboard_fab2(sch_1):page200_i200:inbn" )
			)
			( pin "U9P2.6"
				( objectStatus "@baseboard_fab2_lib.baseboard_fab2(sch_1):page200_i200:outa" )
			)
			( pin "U9P2.1"
				( objectStatus "@baseboard_fab2_lib.baseboard_fab2(sch_1):page200_i200:outb" )
			)
			( pin "U9P2.2"
				( objectStatus "@baseboard_fab2_lib.baseboard_fab2(sch_1):page200_i200:vdd" )
			)
			( pin "C9P11.1"
				( objectStatus "@baseboard_fab2_lib.baseboard_fab2(sch_1):page200_i201:a" )
			)
			( pin "C9P11.2"
				( objectStatus "@baseboard_fab2_lib.baseboard_fab2(sch_1):page200_i201:b" )
			)
			( pin "Q1D2.3"
				( objectStatus "@baseboard_fab2_lib.baseboard_fab2(sch_1):page200_i203:drn" )
			)
			( pin "Q1D2.1"
				( objectStatus "@baseboard_fab2_lib.baseboard_fab2(sch_1):page200_i203:gate" )
			)
			( pin "Q1D2.2"
				( objectStatus "@baseboard_fab2_lib.baseboard_fab2(sch_1):page200_i203:src" )
			)
			( pin "R1D21.1"
				( objectStatus "@baseboard_fab2_lib.baseboard_fab2(sch_1):page200_i204:a" )
			)
			( pin "R1D21.2"
				( objectStatus "@baseboard_fab2_lib.baseboard_fab2(sch_1):page200_i204:b" )
			)
			( pin "R9P4.1"
				( objectStatus "@baseboard_fab2_lib.baseboard_fab2(sch_1):page200_i210:a" )
			)
			( pin "R9P4.2"
				( objectStatus "@baseboard_fab2_lib.baseboard_fab2(sch_1):page200_i210:b" )
			)
			( pin "CR9P2.2"
				( objectStatus "@baseboard_fab2_lib.baseboard_fab2(sch_1):page200_i213:a" )
			)
			( pin "CR9P2.1"
				( objectStatus "@baseboard_fab2_lib.baseboard_fab2(sch_1):page200_i213:c" )
			)
			( pin "CR9P1.2"
				( objectStatus "@baseboard_fab2_lib.baseboard_fab2(sch_1):page200_i214:a" )
			)
			( pin "CR9P1.1"
				( objectStatus "@baseboard_fab2_lib.baseboard_fab2(sch_1):page200_i214:c" )
			)
			( pin "R9P5.1"
				( objectStatus "@baseboard_fab2_lib.baseboard_fab2(sch_1):page200_i215:a" )
			)
			( pin "R9P5.2"
				( objectStatus "@baseboard_fab2_lib.baseboard_fab2(sch_1):page200_i215:b" )
			)
			( pin "R9P12.1"
				( objectStatus "@baseboard_fab2_lib.baseboard_fab2(sch_1):page200_i218:a" )
			)
			( pin "R9P12.2"
				( objectStatus "@baseboard_fab2_lib.baseboard_fab2(sch_1):page200_i218:b" )
			)
			( pin "CR1F5.2"
				( objectStatus "@baseboard_fab2_lib.baseboard_fab2(sch_1):page200_i220:a" )
			)
			( pin "CR1F5.1"
				( objectStatus "@baseboard_fab2_lib.baseboard_fab2(sch_1):page200_i220:c" )
			)
			( pin "R9P33.1"
				( objectStatus "@baseboard_fab2_lib.baseboard_fab2(sch_1):page200_i222:a" )
			)
			( pin "R9P33.2"
				( objectStatus "@baseboard_fab2_lib.baseboard_fab2(sch_1):page200_i222:b" )
			)
			( pin "R4E4.1"
				( objectStatus "@baseboard_fab2_lib.baseboard_fab2(sch_1):page201_i19:a" )
			)
			( pin "R4E4.2"
				( objectStatus "@baseboard_fab2_lib.baseboard_fab2(sch_1):page201_i19:b" )
			)
			( pin "R4E10.1"
				( objectStatus "@baseboard_fab2_lib.baseboard_fab2(sch_1):page201_i20:a" )
			)
			( pin "R4E10.2"
				( objectStatus "@baseboard_fab2_lib.baseboard_fab2(sch_1):page201_i20:b" )
			)
			( pin "R4D31.1"
				( objectStatus "@baseboard_fab2_lib.baseboard_fab2(sch_1):page201_i22:a" )
			)
			( pin "R4D31.2"
				( objectStatus "@baseboard_fab2_lib.baseboard_fab2(sch_1):page201_i22:b" )
			)
			( pin "R4D58.1"
				( objectStatus "@baseboard_fab2_lib.baseboard_fab2(sch_1):page201_i25:a" )
			)
			( pin "R4D58.2"
				( objectStatus "@baseboard_fab2_lib.baseboard_fab2(sch_1):page201_i25:b" )
			)
			( pin "R4D67.1"
				( objectStatus "@baseboard_fab2_lib.baseboard_fab2(sch_1):page201_i26:a" )
			)
			( pin "R4D67.2"
				( objectStatus "@baseboard_fab2_lib.baseboard_fab2(sch_1):page201_i26:b" )
			)
			( pin "R4E5.1"
				( objectStatus "@baseboard_fab2_lib.baseboard_fab2(sch_1):page201_i27:a" )
			)
			( pin "R4E5.2"
				( objectStatus "@baseboard_fab2_lib.baseboard_fab2(sch_1):page201_i27:b" )
			)
			( pin "R4D50.1"
				( objectStatus "@baseboard_fab2_lib.baseboard_fab2(sch_1):page201_i28:a" )
			)
			( pin "R4D50.2"
				( objectStatus "@baseboard_fab2_lib.baseboard_fab2(sch_1):page201_i28:b" )
			)
			( pin "C4D25.1"
				( objectStatus "@baseboard_fab2_lib.baseboard_fab2(sch_1):page201_i30:a" )
			)
			( pin "C4D25.2"
				( objectStatus "@baseboard_fab2_lib.baseboard_fab2(sch_1):page201_i30:b" )
			)
			( pin "R4D53.1"
				( objectStatus "@baseboard_fab2_lib.baseboard_fab2(sch_1):page201_i31:a" )
			)
			( pin "R4D53.2"
				( objectStatus "@baseboard_fab2_lib.baseboard_fab2(sch_1):page201_i31:b" )
			)
			( pin "C4D26.1"
				( objectStatus "@baseboard_fab2_lib.baseboard_fab2(sch_1):page201_i32:a" )
			)
			( pin "C4D26.2"
				( objectStatus "@baseboard_fab2_lib.baseboard_fab2(sch_1):page201_i32:b" )
			)
			( pin "C4D15.1"
				( objectStatus "@baseboard_fab2_lib.baseboard_fab2(sch_1):page201_i37:a" )
			)
			( pin "C4D15.2"
				( objectStatus "@baseboard_fab2_lib.baseboard_fab2(sch_1):page201_i37:b" )
			)
			( pin "C4D19.1"
				( objectStatus "@baseboard_fab2_lib.baseboard_fab2(sch_1):page201_i39:a" )
			)
			( pin "C4D19.2"
				( objectStatus "@baseboard_fab2_lib.baseboard_fab2(sch_1):page201_i39:b" )
			)
			( pin "R4D26.1"
				( objectStatus "@baseboard_fab2_lib.baseboard_fab2(sch_1):page201_i40:a" )
			)
			( pin "R4D26.2"
				( objectStatus "@baseboard_fab2_lib.baseboard_fab2(sch_1):page201_i40:b" )
			)
			( pin "R4E9.1"
				( objectStatus "@baseboard_fab2_lib.baseboard_fab2(sch_1):page201_i52:a" )
			)
			( pin "R4E9.2"
				( objectStatus "@baseboard_fab2_lib.baseboard_fab2(sch_1):page201_i52:b" )
			)
			( pin "R4D27.1"
				( objectStatus "@baseboard_fab2_lib.baseboard_fab2(sch_1):page201_i54:a" )
			)
			( pin "R4D27.2"
				( objectStatus "@baseboard_fab2_lib.baseboard_fab2(sch_1):page201_i54:b" )
			)
			( pin "R4D32.1"
				( objectStatus "@baseboard_fab2_lib.baseboard_fab2(sch_1):page201_i55:a" )
			)
			( pin "R4D32.2"
				( objectStatus "@baseboard_fab2_lib.baseboard_fab2(sch_1):page201_i55:b" )
			)
			( pin "R4E6.1"
				( objectStatus "@baseboard_fab2_lib.baseboard_fab2(sch_1):page201_i56:a" )
			)
			( pin "R4E6.2"
				( objectStatus "@baseboard_fab2_lib.baseboard_fab2(sch_1):page201_i56:b" )
			)
			( pin "C4D20.1"
				( objectStatus "@baseboard_fab2_lib.baseboard_fab2(sch_1):page201_i60:a" )
			)
			( pin "C4D20.2"
				( objectStatus "@baseboard_fab2_lib.baseboard_fab2(sch_1):page201_i60:b" )
			)
			( pin "C4D29.1"
				( objectStatus "@baseboard_fab2_lib.baseboard_fab2(sch_1):page201_i64:a" )
			)
			( pin "C4D29.2"
				( objectStatus "@baseboard_fab2_lib.baseboard_fab2(sch_1):page201_i64:b" )
			)
			( pin "C4D17.1"
				( objectStatus "@baseboard_fab2_lib.baseboard_fab2(sch_1):page201_i66:a" )
			)
			( pin "C4D17.2"
				( objectStatus "@baseboard_fab2_lib.baseboard_fab2(sch_1):page201_i66:b" )
			)
			( pin "C4D18.1"
				( objectStatus "@baseboard_fab2_lib.baseboard_fab2(sch_1):page201_i68:a" )
			)
			( pin "C4D18.2"
				( objectStatus "@baseboard_fab2_lib.baseboard_fab2(sch_1):page201_i68:b" )
			)
			( pin "C4D45.1"
				( objectStatus "@baseboard_fab2_lib.baseboard_fab2(sch_1):page201_i70:a" )
			)
			( pin "C4D45.2"
				( objectStatus "@baseboard_fab2_lib.baseboard_fab2(sch_1):page201_i70:b" )
			)
			( pin "R4D66.1"
				( objectStatus "@baseboard_fab2_lib.baseboard_fab2(sch_1):page201_i98:a" )
			)
			( pin "R4D66.2"
				( objectStatus "@baseboard_fab2_lib.baseboard_fab2(sch_1):page201_i98:b" )
			)
			( pin "R6P32.1"
				( objectStatus "@baseboard_fab2_lib.baseboard_fab2(sch_1):page201_i102:a" )
			)
			( pin "R6P32.2"
				( objectStatus "@baseboard_fab2_lib.baseboard_fab2(sch_1):page201_i102:b" )
			)
			( pin "R6P37.1"
				( objectStatus "@baseboard_fab2_lib.baseboard_fab2(sch_1):page201_i103:a" )
			)
			( pin "R6P37.2"
				( objectStatus "@baseboard_fab2_lib.baseboard_fab2(sch_1):page201_i103:b" )
			)
			( pin "R4E8.1"
				( objectStatus "@baseboard_fab2_lib.baseboard_fab2(sch_1):page201_i109:a" )
			)
			( pin "R4E8.2"
				( objectStatus "@baseboard_fab2_lib.baseboard_fab2(sch_1):page201_i109:b" )
			)
			( pin "R4D39.1"
				( objectStatus "@baseboard_fab2_lib.baseboard_fab2(sch_1):page201_i110:a" )
			)
			( pin "R4D39.2"
				( objectStatus "@baseboard_fab2_lib.baseboard_fab2(sch_1):page201_i110:b" )
			)
			( pin "R4E3.1"
				( objectStatus "@baseboard_fab2_lib.baseboard_fab2(sch_1):page201_i111:a" )
			)
			( pin "R4E3.2"
				( objectStatus "@baseboard_fab2_lib.baseboard_fab2(sch_1):page201_i111:b" )
			)
			( pin "R4E20.1"
				( objectStatus "@baseboard_fab2_lib.baseboard_fab2(sch_1):page201_i116:a" )
			)
			( pin "R4E20.2"
				( objectStatus "@baseboard_fab2_lib.baseboard_fab2(sch_1):page201_i116:b" )
			)
			( pin "R6P27.1"
				( objectStatus "@baseboard_fab2_lib.baseboard_fab2(sch_1):page201_i120:a" )
			)
			( pin "R6P27.2"
				( objectStatus "@baseboard_fab2_lib.baseboard_fab2(sch_1):page201_i120:b" )
			)
			( pin "R6P28.1"
				( objectStatus "@baseboard_fab2_lib.baseboard_fab2(sch_1):page201_i121:a" )
			)
			( pin "R6P28.2"
				( objectStatus "@baseboard_fab2_lib.baseboard_fab2(sch_1):page201_i121:b" )
			)
			( pin "J8D4.1"
				( objectStatus "@baseboard_fab2_lib.baseboard_fab2(sch_1):page201_i122:io1" )
			)
			( pin "J8D4.2"
				( objectStatus "@baseboard_fab2_lib.baseboard_fab2(sch_1):page201_i122:io2" )
			)
			( pin "J8D4.3"
				( objectStatus "@baseboard_fab2_lib.baseboard_fab2(sch_1):page201_i122:io3" )
			)
			( pin "R4D63.1"
				( objectStatus "@baseboard_fab2_lib.baseboard_fab2(sch_1):page201_i124:a" )
			)
			( pin "R4D63.2"
				( objectStatus "@baseboard_fab2_lib.baseboard_fab2(sch_1):page201_i124:b" )
			)
			( pin "C4D42.1"
				( objectStatus "@baseboard_fab2_lib.baseboard_fab2(sch_1):page201_i125:a" )
			)
			( pin "C4D42.2"
				( objectStatus "@baseboard_fab2_lib.baseboard_fab2(sch_1):page201_i125:b" )
			)
			( pin "R4D65.1"
				( objectStatus "@baseboard_fab2_lib.baseboard_fab2(sch_1):page201_i127:a" )
			)
			( pin "R4D65.2"
				( objectStatus "@baseboard_fab2_lib.baseboard_fab2(sch_1):page201_i127:b" )
			)
			( pin "R6P45.1"
				( objectStatus "@baseboard_fab2_lib.baseboard_fab2(sch_1):page201_i128:a" )
			)
			( pin "R6P45.2"
				( objectStatus "@baseboard_fab2_lib.baseboard_fab2(sch_1):page201_i128:b" )
			)
			( pin "R6P18.1"
				( objectStatus "@baseboard_fab2_lib.baseboard_fab2(sch_1):page201_i131:a" )
			)
			( pin "R6P18.2"
				( objectStatus "@baseboard_fab2_lib.baseboard_fab2(sch_1):page201_i131:b" )
			)
			( pin "R6P16.1"
				( objectStatus "@baseboard_fab2_lib.baseboard_fab2(sch_1):page201_i132:a" )
			)
			( pin "R6P16.2"
				( objectStatus "@baseboard_fab2_lib.baseboard_fab2(sch_1):page201_i132:b" )
			)
			( pin "R6P42.1"
				( objectStatus "@baseboard_fab2_lib.baseboard_fab2(sch_1):page201_i139:a" )
			)
			( pin "R6P42.2"
				( objectStatus "@baseboard_fab2_lib.baseboard_fab2(sch_1):page201_i139:b" )
			)
			( pin "R6P38.1"
				( objectStatus "@baseboard_fab2_lib.baseboard_fab2(sch_1):page201_i147:a" )
			)
			( pin "R6P38.2"
				( objectStatus "@baseboard_fab2_lib.baseboard_fab2(sch_1):page201_i147:b" )
			)
			( pin "R6P34.1"
				( objectStatus "@baseboard_fab2_lib.baseboard_fab2(sch_1):page201_i148:a" )
			)
			( pin "R6P34.2"
				( objectStatus "@baseboard_fab2_lib.baseboard_fab2(sch_1):page201_i148:b" )
			)
			( pin "R6P30.1"
				( objectStatus "@baseboard_fab2_lib.baseboard_fab2(sch_1):page201_i149:a" )
			)
			( pin "R6P30.2"
				( objectStatus "@baseboard_fab2_lib.baseboard_fab2(sch_1):page201_i149:b" )
			)
			( pin "R6P43.1"
				( objectStatus "@baseboard_fab2_lib.baseboard_fab2(sch_1):page201_i150:a" )
			)
			( pin "R6P43.2"
				( objectStatus "@baseboard_fab2_lib.baseboard_fab2(sch_1):page201_i150:b" )
			)
			( pin "R6P29.1"
				( objectStatus "@baseboard_fab2_lib.baseboard_fab2(sch_1):page201_i154:a" )
			)
			( pin "R6P29.2"
				( objectStatus "@baseboard_fab2_lib.baseboard_fab2(sch_1):page201_i154:b" )
			)
			( pin "EU4D4.23"
				( objectStatus "@baseboard_fab2_lib.baseboard_fab2(sch_1):page201_i155:airef1" )
			)
			( pin "EU4D4.25"
				( objectStatus "@baseboard_fab2_lib.baseboard_fab2(sch_1):page201_i155:airef2" )
			)
			( pin "EU4D4.27"
				( objectStatus "@baseboard_fab2_lib.baseboard_fab2(sch_1):page201_i155:airef3" )
			)
			( pin "EU4D4.29"
				( objectStatus "@baseboard_fab2_lib.baseboard_fab2(sch_1):page201_i155:airef4" )
			)
			( pin "EU4D4.31"
				( objectStatus "@baseboard_fab2_lib.baseboard_fab2(sch_1):page201_i155:airef5" )
			)
			( pin "EU4D4.33"
				( objectStatus "@baseboard_fab2_lib.baseboard_fab2(sch_1):page201_i155:airef6" )
			)
			( pin "EU4D4.24"
				( objectStatus "@baseboard_fab2_lib.baseboard_fab2(sch_1):page201_i155:aisen1" )
			)
			( pin "EU4D4.26"
				( objectStatus "@baseboard_fab2_lib.baseboard_fab2(sch_1):page201_i155:aisen2" )
			)
			( pin "EU4D4.28"
				( objectStatus "@baseboard_fab2_lib.baseboard_fab2(sch_1):page201_i155:aisen3" )
			)
			( pin "EU4D4.30"
				( objectStatus "@baseboard_fab2_lib.baseboard_fab2(sch_1):page201_i155:aisen4" )
			)
			( pin "EU4D4.32"
				( objectStatus "@baseboard_fab2_lib.baseboard_fab2(sch_1):page201_i155:aisen5" )
			)
			( pin "EU4D4.34"
				( objectStatus "@baseboard_fab2_lib.baseboard_fab2(sch_1):page201_i155:aisen6" )
			)
			( pin "EU4D4.7"
				( objectStatus "@baseboard_fab2_lib.baseboard_fab2(sch_1):page201_i155:apwm1" )
			)
			( pin "EU4D4.6"
				( objectStatus "@baseboard_fab2_lib.baseboard_fab2(sch_1):page201_i155:apwm2" )
			)
			( pin "EU4D4.5"
				( objectStatus "@baseboard_fab2_lib.baseboard_fab2(sch_1):page201_i155:apwm3" )
			)
			( pin "EU4D4.4"
				( objectStatus "@baseboard_fab2_lib.baseboard_fab2(sch_1):page201_i155:apwm4" )
			)
			( pin "EU4D4.3"
				( objectStatus "@baseboard_fab2_lib.baseboard_fab2(sch_1):page201_i155:apwm5" )
			)
			( pin "EU4D4.2"
				( objectStatus "@baseboard_fab2_lib.baseboard_fab2(sch_1):page201_i155:apwm6" )
			)
			( pin "EU4D4.43"
				( objectStatus "@baseboard_fab2_lib.baseboard_fab2(sch_1):page201_i155:atsen" )
			)
			( pin "EU4D4.22"
				( objectStatus "@baseboard_fab2_lib.baseboard_fab2(sch_1):page201_i155:avref" )
			)
			( pin "EU4D4.12"
				( objectStatus "@baseboard_fab2_lib.baseboard_fab2(sch_1):page201_i155:avren" )
			)
			( pin "EU4D4.11"
				( objectStatus "@baseboard_fab2_lib.baseboard_fab2(sch_1):page201_i155:avrrdy" )
			)
			( pin "EU4D4.21"
				( objectStatus "@baseboard_fab2_lib.baseboard_fab2(sch_1):page201_i155:avsen" )
			)
			( pin "EU4D4.37"
				( objectStatus "@baseboard_fab2_lib.baseboard_fab2(sch_1):page201_i155:biref1" )
			)
			( pin "EU4D4.38"
				( objectStatus "@baseboard_fab2_lib.baseboard_fab2(sch_1):page201_i155:bisen1" )
			)
			( pin "EU4D4.1"
				( objectStatus "@baseboard_fab2_lib.baseboard_fab2(sch_1):page201_i155:bpwm1" )
			)
			( pin "EU4D4.42"
				( objectStatus "@baseboard_fab2_lib.baseboard_fab2(sch_1):page201_i155:btsen" )
			)
			( pin "EU4D4.36"
				( objectStatus "@baseboard_fab2_lib.baseboard_fab2(sch_1):page201_i155:bvref" )
			)
			( pin "EU4D4.35"
				( objectStatus "@baseboard_fab2_lib.baseboard_fab2(sch_1):page201_i155:bvsen" )
			)
			( pin "EU4D4.46"
				( objectStatus "@baseboard_fab2_lib.baseboard_fab2(sch_1):page201_i155:iinsen" )
			)
			( pin "EU4D4.15"
				( objectStatus "@baseboard_fab2_lib.baseboard_fab2(sch_1):page201_i155:mp0" )
			)
			( pin "EU4D4.16"
				( objectStatus "@baseboard_fab2_lib.baseboard_fab2(sch_1):page201_i155:mp1" )
			)
			( pin "EU4D4.20"
				( objectStatus "@baseboard_fab2_lib.baseboard_fab2(sch_1):page201_i155:mp2" )
			)
			( pin "EU4D4.39"
				( objectStatus "@baseboard_fab2_lib.baseboard_fab2(sch_1):page201_i155:mp3" )
			)
			( pin "EU4D4.40"
				( objectStatus "@baseboard_fab2_lib.baseboard_fab2(sch_1):page201_i155:mp4" )
			)
			( pin "EU4D4.14"
				( objectStatus "@baseboard_fab2_lib.baseboard_fab2(sch_1):page201_i155:pinalrt_n" )
			)
			( pin "EU4D4.10"
				( objectStatus "@baseboard_fab2_lib.baseboard_fab2(sch_1):page201_i155:reset_n" )
			)
			( pin "EU4D4.9"
				( objectStatus "@baseboard_fab2_lib.baseboard_fab2(sch_1):page201_i155:scl" )
			)
			( pin "EU4D4.8"
				( objectStatus "@baseboard_fab2_lib.baseboard_fab2(sch_1):page201_i155:sda" )
			)
			( pin "EU4D4.49"
				( objectStatus "@baseboard_fab2_lib.baseboard_fab2(sch_1):page201_i155:thpad" )
			)
			( pin "EU4D4.19"
				( objectStatus "@baseboard_fab2_lib.baseboard_fab2(sch_1):page201_i155:valrt_n" )
			)
			( pin "EU4D4.17"
				( objectStatus "@baseboard_fab2_lib.baseboard_fab2(sch_1):page201_i155:vclk" )
			)
			( pin "EU4D4.48"
				( objectStatus "@baseboard_fab2_lib.baseboard_fab2(sch_1):page201_i155:vd12" )
			)
			( pin "EU4D4.47"
				( objectStatus "@baseboard_fab2_lib.baseboard_fab2(sch_1):page201_i155:vdd" )
			)
			( pin "EU4D4.18"
				( objectStatus "@baseboard_fab2_lib.baseboard_fab2(sch_1):page201_i155:vdio" )
			)
			( pin "EU4D4.45"
				( objectStatus "@baseboard_fab2_lib.baseboard_fab2(sch_1):page201_i155:vinsen" )
			)
			( pin "EU4D4.13"
				( objectStatus "@baseboard_fab2_lib.baseboard_fab2(sch_1):page201_i155:vrhot_n" )
			)
			( pin "EU4D4.44"
				( objectStatus "@baseboard_fab2_lib.baseboard_fab2(sch_1):page201_i155:xaddr1" )
			)
			( pin "EU4D4.41"
				( objectStatus "@baseboard_fab2_lib.baseboard_fab2(sch_1):page201_i155:xaddr2" )
			)
			( pin "L4E1.1"
				( objectStatus "@baseboard_fab2_lib.baseboard_fab2(sch_1):page202_i5:ina" )
			)
			( pin "L4E1.2"
				( objectStatus "@baseboard_fab2_lib.baseboard_fab2(sch_1):page202_i5:inb" )
			)
			( pin "C6R7.1"
				( objectStatus "@baseboard_fab2_lib.baseboard_fab2(sch_1):page202_i9:a" )
			)
			( pin "C6R7.2"
				( objectStatus "@baseboard_fab2_lib.baseboard_fab2(sch_1):page202_i9:b" )
			)
			( pin "C4E5.1"
				( objectStatus "@baseboard_fab2_lib.baseboard_fab2(sch_1):page202_i18:a" )
			)
			( pin "C4E5.2"
				( objectStatus "@baseboard_fab2_lib.baseboard_fab2(sch_1):page202_i18:b" )
			)
			( pin "C4E6.1"
				( objectStatus "@baseboard_fab2_lib.baseboard_fab2(sch_1):page202_i19:a" )
			)
			( pin "C4E6.2"
				( objectStatus "@baseboard_fab2_lib.baseboard_fab2(sch_1):page202_i19:b" )
			)
			( pin "C4E17.1"
				( objectStatus "@baseboard_fab2_lib.baseboard_fab2(sch_1):page202_i22:a" )
			)
			( pin "C4E17.2"
				( objectStatus "@baseboard_fab2_lib.baseboard_fab2(sch_1):page202_i22:b" )
			)
			( pin "C4E27.1"
				( objectStatus "@baseboard_fab2_lib.baseboard_fab2(sch_1):page202_i24:a" )
			)
			( pin "C4E27.2"
				( objectStatus "@baseboard_fab2_lib.baseboard_fab2(sch_1):page202_i24:b" )
			)
			( pin "C4E25.1"
				( objectStatus "@baseboard_fab2_lib.baseboard_fab2(sch_1):page202_i25:a" )
			)
			( pin "C4E25.2"
				( objectStatus "@baseboard_fab2_lib.baseboard_fab2(sch_1):page202_i25:b" )
			)
			( pin "C4E11.1"
				( objectStatus "@baseboard_fab2_lib.baseboard_fab2(sch_1):page202_i27:a" )
			)
			( pin "C4E11.2"
				( objectStatus "@baseboard_fab2_lib.baseboard_fab2(sch_1):page202_i27:b" )
			)
			( pin "L4D3.1"
				( objectStatus "@baseboard_fab2_lib.baseboard_fab2(sch_1):page202_i29:ina" )
			)
			( pin "L4D3.2"
				( objectStatus "@baseboard_fab2_lib.baseboard_fab2(sch_1):page202_i29:inb" )
			)
			( pin "C4D50.1"
				( objectStatus "@baseboard_fab2_lib.baseboard_fab2(sch_1):page202_i32:a" )
			)
			( pin "C4D50.2"
				( objectStatus "@baseboard_fab2_lib.baseboard_fab2(sch_1):page202_i32:b" )
			)
			( pin "R6R2.1"
				( objectStatus "@baseboard_fab2_lib.baseboard_fab2(sch_1):page202_i33:a" )
			)
			( pin "R6R2.2"
				( objectStatus "@baseboard_fab2_lib.baseboard_fab2(sch_1):page202_i33:b" )
			)
			( pin "C4E10.1"
				( objectStatus "@baseboard_fab2_lib.baseboard_fab2(sch_1):page202_i34:a" )
			)
			( pin "C4E10.2"
				( objectStatus "@baseboard_fab2_lib.baseboard_fab2(sch_1):page202_i34:b" )
			)
			( pin "C4E20.1"
				( objectStatus "@baseboard_fab2_lib.baseboard_fab2(sch_1):page202_i35:a" )
			)
			( pin "C4E20.2"
				( objectStatus "@baseboard_fab2_lib.baseboard_fab2(sch_1):page202_i35:b" )
			)
			( pin "C4E19.1"
				( objectStatus "@baseboard_fab2_lib.baseboard_fab2(sch_1):page202_i36:a" )
			)
			( pin "C4E19.2"
				( objectStatus "@baseboard_fab2_lib.baseboard_fab2(sch_1):page202_i36:b" )
			)
			( pin "C6R11.1"
				( objectStatus "@baseboard_fab2_lib.baseboard_fab2(sch_1):page202_i37:a" )
			)
			( pin "C6R11.2"
				( objectStatus "@baseboard_fab2_lib.baseboard_fab2(sch_1):page202_i37:b" )
			)
			( pin "C6P13.1"
				( objectStatus "@baseboard_fab2_lib.baseboard_fab2(sch_1):page202_i38:a" )
			)
			( pin "C6P13.2"
				( objectStatus "@baseboard_fab2_lib.baseboard_fab2(sch_1):page202_i38:b" )
			)
			( pin "R6R6.1"
				( objectStatus "@baseboard_fab2_lib.baseboard_fab2(sch_1):page202_i39:a" )
			)
			( pin "R6R6.2"
				( objectStatus "@baseboard_fab2_lib.baseboard_fab2(sch_1):page202_i39:b" )
			)
			( pin "C6R13.1"
				( objectStatus "@baseboard_fab2_lib.baseboard_fab2(sch_1):page202_i42:a" )
			)
			( pin "C6R13.2"
				( objectStatus "@baseboard_fab2_lib.baseboard_fab2(sch_1):page202_i42:b" )
			)
			( pin "C4E26.1"
				( objectStatus "@baseboard_fab2_lib.baseboard_fab2(sch_1):page202_i45:a" )
			)
			( pin "C4E26.2"
				( objectStatus "@baseboard_fab2_lib.baseboard_fab2(sch_1):page202_i45:b" )
			)
			( pin "C4D49.1"
				( objectStatus "@baseboard_fab2_lib.baseboard_fab2(sch_1):page202_i46:a" )
			)
			( pin "C4D49.2"
				( objectStatus "@baseboard_fab2_lib.baseboard_fab2(sch_1):page202_i46:b" )
			)
			( pin "C4D48.1"
				( objectStatus "@baseboard_fab2_lib.baseboard_fab2(sch_1):page202_i47:a" )
			)
			( pin "C4D48.2"
				( objectStatus "@baseboard_fab2_lib.baseboard_fab2(sch_1):page202_i47:b" )
			)
			( pin "C6R4.1"
				( objectStatus "@baseboard_fab2_lib.baseboard_fab2(sch_1):page202_i48:a" )
			)
			( pin "C6R4.2"
				( objectStatus "@baseboard_fab2_lib.baseboard_fab2(sch_1):page202_i48:b" )
			)
			( pin "C6P22.1"
				( objectStatus "@baseboard_fab2_lib.baseboard_fab2(sch_1):page202_i49:a" )
			)
			( pin "C6P22.2"
				( objectStatus "@baseboard_fab2_lib.baseboard_fab2(sch_1):page202_i49:b" )
			)
			( pin "C6N8.1"
				( objectStatus "@baseboard_fab2_lib.baseboard_fab2(sch_1):page202_i51:a" )
			)
			( pin "C6N8.2"
				( objectStatus "@baseboard_fab2_lib.baseboard_fab2(sch_1):page202_i51:b" )
			)
			( pin "C4E3.1"
				( objectStatus "@baseboard_fab2_lib.baseboard_fab2(sch_1):page202_i61:a" )
			)
			( pin "C4E3.2"
				( objectStatus "@baseboard_fab2_lib.baseboard_fab2(sch_1):page202_i61:b" )
			)
			( pin "C6P16.1"
				( objectStatus "@baseboard_fab2_lib.baseboard_fab2(sch_1):page202_i62:a" )
			)
			( pin "C6P16.2"
				( objectStatus "@baseboard_fab2_lib.baseboard_fab2(sch_1):page202_i62:b" )
			)
			( pin "EU4E1.33"
				( objectStatus "@baseboard_fab2_lib.baseboard_fab2(sch_1):page202_i63:boost" )
			)
			( pin "EU4E1.35"
				( objectStatus "@baseboard_fab2_lib.baseboard_fab2(sch_1):page202_i63:en" )
			)
			( pin "EU4E1.6"
				( objectStatus "@baseboard_fab2_lib.baseboard_fab2(sch_1):page202_i63:gl(0)" )
			)
			( pin "EU4E1.41"
				( objectStatus "@baseboard_fab2_lib.baseboard_fab2(sch_1):page202_i63:gl(1)" )
			)
			( pin "EU4E1.38"
				( objectStatus "@baseboard_fab2_lib.baseboard_fab2(sch_1):page202_i63:iout" )
			)
			( pin "EU4E1.2"
				( objectStatus "@baseboard_fab2_lib.baseboard_fab2(sch_1):page202_i63:lgnd" )
			)
			( pin "EU4E1.31"
				( objectStatus "@baseboard_fab2_lib.baseboard_fab2(sch_1):page202_i63:nc" )
			)
			( pin "EU4E1.37"
				( objectStatus "@baseboard_fab2_lib.baseboard_fab2(sch_1):page202_i63:ocset" )
			)
			( pin "EU4E1.5"
				( objectStatus "@baseboard_fab2_lib.baseboard_fab2(sch_1):page202_i63:pgnd(0)" )
			)
			( pin "EU4E1.7"
				( objectStatus "@baseboard_fab2_lib.baseboard_fab2(sch_1):page202_i63:pgnd(1)" )
			)
			( pin "EU4E1.40"
				( objectStatus "@baseboard_fab2_lib.baseboard_fab2(sch_1):page202_i63:pgnd(2)" )
			)
			( pin "EU4E1.32"
				( objectStatus "@baseboard_fab2_lib.baseboard_fab2(sch_1):page202_i63:phase" )
			)
			( pin "EU4E1.34"
				( objectStatus "@baseboard_fab2_lib.baseboard_fab2(sch_1):page202_i63:pwm" )
			)
			( pin "EU4E1.39"
				( objectStatus "@baseboard_fab2_lib.baseboard_fab2(sch_1):page202_i63:refin" )
			)
			( pin "EU4E1.10"
				( objectStatus "@baseboard_fab2_lib.baseboard_fab2(sch_1):page202_i63:sw" )
			)
			( pin "EU4E1.36"
				( objectStatus "@baseboard_fab2_lib.baseboard_fab2(sch_1):page202_i63:tout_flt" )
			)
			( pin "EU4E1.3"
				( objectStatus "@baseboard_fab2_lib.baseboard_fab2(sch_1):page202_i63:vcc" )
			)
			( pin "EU4E1.4"
				( objectStatus "@baseboard_fab2_lib.baseboard_fab2(sch_1):page202_i63:vdrv" )
			)
			( pin "EU4E1.25"
				( objectStatus "@baseboard_fab2_lib.baseboard_fab2(sch_1):page202_i63:vin(0)" )
			)
			( pin "EU4E1.30"
				( objectStatus "@baseboard_fab2_lib.baseboard_fab2(sch_1):page202_i63:vin(1)" )
			)
			( pin "EU4E1.1"
				( objectStatus "@baseboard_fab2_lib.baseboard_fab2(sch_1):page202_i63:vos" )
			)
			( pin "EU4D6.33"
				( objectStatus "@baseboard_fab2_lib.baseboard_fab2(sch_1):page202_i64:boost" )
			)
			( pin "EU4D6.35"
				( objectStatus "@baseboard_fab2_lib.baseboard_fab2(sch_1):page202_i64:en" )
			)
			( pin "EU4D6.6"
				( objectStatus "@baseboard_fab2_lib.baseboard_fab2(sch_1):page202_i64:gl(0)" )
			)
			( pin "EU4D6.41"
				( objectStatus "@baseboard_fab2_lib.baseboard_fab2(sch_1):page202_i64:gl(1)" )
			)
			( pin "EU4D6.38"
				( objectStatus "@baseboard_fab2_lib.baseboard_fab2(sch_1):page202_i64:iout" )
			)
			( pin "EU4D6.2"
				( objectStatus "@baseboard_fab2_lib.baseboard_fab2(sch_1):page202_i64:lgnd" )
			)
			( pin "EU4D6.31"
				( objectStatus "@baseboard_fab2_lib.baseboard_fab2(sch_1):page202_i64:nc" )
			)
			( pin "EU4D6.37"
				( objectStatus "@baseboard_fab2_lib.baseboard_fab2(sch_1):page202_i64:ocset" )
			)
			( pin "EU4D6.5"
				( objectStatus "@baseboard_fab2_lib.baseboard_fab2(sch_1):page202_i64:pgnd(0)" )
			)
			( pin "EU4D6.7"
				( objectStatus "@baseboard_fab2_lib.baseboard_fab2(sch_1):page202_i64:pgnd(1)" )
			)
			( pin "EU4D6.40"
				( objectStatus "@baseboard_fab2_lib.baseboard_fab2(sch_1):page202_i64:pgnd(2)" )
			)
			( pin "EU4D6.32"
				( objectStatus "@baseboard_fab2_lib.baseboard_fab2(sch_1):page202_i64:phase" )
			)
			( pin "EU4D6.34"
				( objectStatus "@baseboard_fab2_lib.baseboard_fab2(sch_1):page202_i64:pwm" )
			)
			( pin "EU4D6.39"
				( objectStatus "@baseboard_fab2_lib.baseboard_fab2(sch_1):page202_i64:refin" )
			)
			( pin "EU4D6.10"
				( objectStatus "@baseboard_fab2_lib.baseboard_fab2(sch_1):page202_i64:sw" )
			)
			( pin "EU4D6.36"
				( objectStatus "@baseboard_fab2_lib.baseboard_fab2(sch_1):page202_i64:tout_flt" )
			)
			( pin "EU4D6.3"
				( objectStatus "@baseboard_fab2_lib.baseboard_fab2(sch_1):page202_i64:vcc" )
			)
			( pin "EU4D6.4"
				( objectStatus "@baseboard_fab2_lib.baseboard_fab2(sch_1):page202_i64:vdrv" )
			)
			( pin "EU4D6.25"
				( objectStatus "@baseboard_fab2_lib.baseboard_fab2(sch_1):page202_i64:vin(0)" )
			)
			( pin "EU4D6.30"
				( objectStatus "@baseboard_fab2_lib.baseboard_fab2(sch_1):page202_i64:vin(1)" )
			)
			( pin "EU4D6.1"
				( objectStatus "@baseboard_fab2_lib.baseboard_fab2(sch_1):page202_i64:vos" )
			)
			( pin "R4E22.1"
				( objectStatus "@baseboard_fab2_lib.baseboard_fab2(sch_1):page202_i65:a" )
			)
			( pin "R4E22.2"
				( objectStatus "@baseboard_fab2_lib.baseboard_fab2(sch_1):page202_i65:b" )
			)
			( pin "R4E19.1"
				( objectStatus "@baseboard_fab2_lib.baseboard_fab2(sch_1):page202_i67:a" )
			)
			( pin "R4E19.2"
				( objectStatus "@baseboard_fab2_lib.baseboard_fab2(sch_1):page202_i67:b" )
			)
			( pin "C6P24.1"
				( objectStatus "@baseboard_fab2_lib.baseboard_fab2(sch_1):page203_i1:a" )
			)
			( pin "C6P24.2"
				( objectStatus "@baseboard_fab2_lib.baseboard_fab2(sch_1):page203_i1:b" )
			)
			( pin "C6R6.1"
				( objectStatus "@baseboard_fab2_lib.baseboard_fab2(sch_1):page203_i2:a" )
			)
			( pin "C6R6.2"
				( objectStatus "@baseboard_fab2_lib.baseboard_fab2(sch_1):page203_i2:b" )
			)
			( pin "C4D9.1"
				( objectStatus "@baseboard_fab2_lib.baseboard_fab2(sch_1):page203_i3:a" )
			)
			( pin "C4D9.2"
				( objectStatus "@baseboard_fab2_lib.baseboard_fab2(sch_1):page203_i3:b" )
			)
			( pin "L4D2.1"
				( objectStatus "@baseboard_fab2_lib.baseboard_fab2(sch_1):page203_i15:ina" )
			)
			( pin "L4D2.2"
				( objectStatus "@baseboard_fab2_lib.baseboard_fab2(sch_1):page203_i15:inb" )
			)
			( pin "C6R3.1"
				( objectStatus "@baseboard_fab2_lib.baseboard_fab2(sch_1):page203_i16:a" )
			)
			( pin "C6R3.2"
				( objectStatus "@baseboard_fab2_lib.baseboard_fab2(sch_1):page203_i16:b" )
			)
			( pin "C6R9.1"
				( objectStatus "@baseboard_fab2_lib.baseboard_fab2(sch_1):page203_i18:a" )
			)
			( pin "C6R9.2"
				( objectStatus "@baseboard_fab2_lib.baseboard_fab2(sch_1):page203_i18:b" )
			)
			( pin "L4D1.1"
				( objectStatus "@baseboard_fab2_lib.baseboard_fab2(sch_1):page203_i24:ina" )
			)
			( pin "L4D1.2"
				( objectStatus "@baseboard_fab2_lib.baseboard_fab2(sch_1):page203_i24:inb" )
			)
			( pin "C6P3.1"
				( objectStatus "@baseboard_fab2_lib.baseboard_fab2(sch_1):page203_i25:a" )
			)
			( pin "C6P3.2"
				( objectStatus "@baseboard_fab2_lib.baseboard_fab2(sch_1):page203_i25:b" )
			)
			( pin "C6P23.1"
				( objectStatus "@baseboard_fab2_lib.baseboard_fab2(sch_1):page203_i28:a" )
			)
			( pin "C6P23.2"
				( objectStatus "@baseboard_fab2_lib.baseboard_fab2(sch_1):page203_i28:b" )
			)
			( pin "C6P14.1"
				( objectStatus "@baseboard_fab2_lib.baseboard_fab2(sch_1):page203_i29:a" )
			)
			( pin "C6P14.2"
				( objectStatus "@baseboard_fab2_lib.baseboard_fab2(sch_1):page203_i29:b" )
			)
			( pin "C6P18.1"
				( objectStatus "@baseboard_fab2_lib.baseboard_fab2(sch_1):page203_i30:a" )
			)
			( pin "C6P18.2"
				( objectStatus "@baseboard_fab2_lib.baseboard_fab2(sch_1):page203_i30:b" )
			)
			( pin "C6P8.1"
				( objectStatus "@baseboard_fab2_lib.baseboard_fab2(sch_1):page203_i32:a" )
			)
			( pin "C6P8.2"
				( objectStatus "@baseboard_fab2_lib.baseboard_fab2(sch_1):page203_i32:b" )
			)
			( pin "C6N9.1"
				( objectStatus "@baseboard_fab2_lib.baseboard_fab2(sch_1):page203_i34:a" )
			)
			( pin "C6N9.2"
				( objectStatus "@baseboard_fab2_lib.baseboard_fab2(sch_1):page203_i34:b" )
			)
			( pin "R6P19.1"
				( objectStatus "@baseboard_fab2_lib.baseboard_fab2(sch_1):page203_i38:a" )
			)
			( pin "R6P19.2"
				( objectStatus "@baseboard_fab2_lib.baseboard_fab2(sch_1):page203_i38:b" )
			)
			( pin "C4D13.1"
				( objectStatus "@baseboard_fab2_lib.baseboard_fab2(sch_1):page203_i40:a" )
			)
			( pin "C4D13.2"
				( objectStatus "@baseboard_fab2_lib.baseboard_fab2(sch_1):page203_i40:b" )
			)
			( pin "C4D14.1"
				( objectStatus "@baseboard_fab2_lib.baseboard_fab2(sch_1):page203_i41:a" )
			)
			( pin "C4D14.2"
				( objectStatus "@baseboard_fab2_lib.baseboard_fab2(sch_1):page203_i41:b" )
			)
			( pin "C4D28.1"
				( objectStatus "@baseboard_fab2_lib.baseboard_fab2(sch_1):page203_i42:a" )
			)
			( pin "C4D28.2"
				( objectStatus "@baseboard_fab2_lib.baseboard_fab2(sch_1):page203_i42:b" )
			)
			( pin "C4D16.1"
				( objectStatus "@baseboard_fab2_lib.baseboard_fab2(sch_1):page203_i45:a" )
			)
			( pin "C4D16.2"
				( objectStatus "@baseboard_fab2_lib.baseboard_fab2(sch_1):page203_i45:b" )
			)
			( pin "C4D35.1"
				( objectStatus "@baseboard_fab2_lib.baseboard_fab2(sch_1):page203_i46:a" )
			)
			( pin "C4D35.2"
				( objectStatus "@baseboard_fab2_lib.baseboard_fab2(sch_1):page203_i46:b" )
			)
			( pin "C4D30.1"
				( objectStatus "@baseboard_fab2_lib.baseboard_fab2(sch_1):page203_i47:a" )
			)
			( pin "C4D30.2"
				( objectStatus "@baseboard_fab2_lib.baseboard_fab2(sch_1):page203_i47:b" )
			)
			( pin "C4D5.1"
				( objectStatus "@baseboard_fab2_lib.baseboard_fab2(sch_1):page203_i48:a" )
			)
			( pin "C4D5.2"
				( objectStatus "@baseboard_fab2_lib.baseboard_fab2(sch_1):page203_i48:b" )
			)
			( pin "C4D6.1"
				( objectStatus "@baseboard_fab2_lib.baseboard_fab2(sch_1):page203_i49:a" )
			)
			( pin "C4D6.2"
				( objectStatus "@baseboard_fab2_lib.baseboard_fab2(sch_1):page203_i49:b" )
			)
			( pin "R6P10.1"
				( objectStatus "@baseboard_fab2_lib.baseboard_fab2(sch_1):page203_i50:a" )
			)
			( pin "R6P10.2"
				( objectStatus "@baseboard_fab2_lib.baseboard_fab2(sch_1):page203_i50:b" )
			)
			( pin "C4D7.1"
				( objectStatus "@baseboard_fab2_lib.baseboard_fab2(sch_1):page203_i51:a" )
			)
			( pin "C4D7.2"
				( objectStatus "@baseboard_fab2_lib.baseboard_fab2(sch_1):page203_i51:b" )
			)
			( pin "C4D11.1"
				( objectStatus "@baseboard_fab2_lib.baseboard_fab2(sch_1):page203_i52:a" )
			)
			( pin "C4D11.2"
				( objectStatus "@baseboard_fab2_lib.baseboard_fab2(sch_1):page203_i52:b" )
			)
			( pin "C4D10.1"
				( objectStatus "@baseboard_fab2_lib.baseboard_fab2(sch_1):page203_i53:a" )
			)
			( pin "C4D10.2"
				( objectStatus "@baseboard_fab2_lib.baseboard_fab2(sch_1):page203_i53:b" )
			)
			( pin "C6P19.1"
				( objectStatus "@baseboard_fab2_lib.baseboard_fab2(sch_1):page203_i54:a" )
			)
			( pin "C6P19.2"
				( objectStatus "@baseboard_fab2_lib.baseboard_fab2(sch_1):page203_i54:b" )
			)
			( pin "C6P20.1"
				( objectStatus "@baseboard_fab2_lib.baseboard_fab2(sch_1):page203_i57:a" )
			)
			( pin "C6P20.2"
				( objectStatus "@baseboard_fab2_lib.baseboard_fab2(sch_1):page203_i57:b" )
			)
			( pin "C6P15.1"
				( objectStatus "@baseboard_fab2_lib.baseboard_fab2(sch_1):page203_i58:a" )
			)
			( pin "C6P15.2"
				( objectStatus "@baseboard_fab2_lib.baseboard_fab2(sch_1):page203_i58:b" )
			)
			( pin "C6P7.1"
				( objectStatus "@baseboard_fab2_lib.baseboard_fab2(sch_1):page203_i59:a" )
			)
			( pin "C6P7.2"
				( objectStatus "@baseboard_fab2_lib.baseboard_fab2(sch_1):page203_i59:b" )
			)
			( pin "C6P21.1"
				( objectStatus "@baseboard_fab2_lib.baseboard_fab2(sch_1):page203_i66:a" )
			)
			( pin "C6P21.2"
				( objectStatus "@baseboard_fab2_lib.baseboard_fab2(sch_1):page203_i66:b" )
			)
			( pin "R4E13.1"
				( objectStatus "@baseboard_fab2_lib.baseboard_fab2(sch_1):page203_i67:a" )
			)
			( pin "R4E13.2"
				( objectStatus "@baseboard_fab2_lib.baseboard_fab2(sch_1):page203_i67:b" )
			)
			( pin "C4D34.1"
				( objectStatus "@baseboard_fab2_lib.baseboard_fab2(sch_1):page203_i68:a" )
			)
			( pin "C4D34.2"
				( objectStatus "@baseboard_fab2_lib.baseboard_fab2(sch_1):page203_i68:b" )
			)
			( pin "C4D4.1"
				( objectStatus "@baseboard_fab2_lib.baseboard_fab2(sch_1):page203_i69:a" )
			)
			( pin "C4D4.2"
				( objectStatus "@baseboard_fab2_lib.baseboard_fab2(sch_1):page203_i69:b" )
			)
			( pin "EU4D3.33"
				( objectStatus "@baseboard_fab2_lib.baseboard_fab2(sch_1):page203_i70:boost" )
			)
			( pin "EU4D3.35"
				( objectStatus "@baseboard_fab2_lib.baseboard_fab2(sch_1):page203_i70:en" )
			)
			( pin "EU4D3.6"
				( objectStatus "@baseboard_fab2_lib.baseboard_fab2(sch_1):page203_i70:gl(0)" )
			)
			( pin "EU4D3.41"
				( objectStatus "@baseboard_fab2_lib.baseboard_fab2(sch_1):page203_i70:gl(1)" )
			)
			( pin "EU4D3.38"
				( objectStatus "@baseboard_fab2_lib.baseboard_fab2(sch_1):page203_i70:iout" )
			)
			( pin "EU4D3.2"
				( objectStatus "@baseboard_fab2_lib.baseboard_fab2(sch_1):page203_i70:lgnd" )
			)
			( pin "EU4D3.31"
				( objectStatus "@baseboard_fab2_lib.baseboard_fab2(sch_1):page203_i70:nc" )
			)
			( pin "EU4D3.37"
				( objectStatus "@baseboard_fab2_lib.baseboard_fab2(sch_1):page203_i70:ocset" )
			)
			( pin "EU4D3.5"
				( objectStatus "@baseboard_fab2_lib.baseboard_fab2(sch_1):page203_i70:pgnd(0)" )
			)
			( pin "EU4D3.7"
				( objectStatus "@baseboard_fab2_lib.baseboard_fab2(sch_1):page203_i70:pgnd(1)" )
			)
			( pin "EU4D3.40"
				( objectStatus "@baseboard_fab2_lib.baseboard_fab2(sch_1):page203_i70:pgnd(2)" )
			)
			( pin "EU4D3.32"
				( objectStatus "@baseboard_fab2_lib.baseboard_fab2(sch_1):page203_i70:phase" )
			)
			( pin "EU4D3.34"
				( objectStatus "@baseboard_fab2_lib.baseboard_fab2(sch_1):page203_i70:pwm" )
			)
			( pin "EU4D3.39"
				( objectStatus "@baseboard_fab2_lib.baseboard_fab2(sch_1):page203_i70:refin" )
			)
			( pin "EU4D3.10"
				( objectStatus "@baseboard_fab2_lib.baseboard_fab2(sch_1):page203_i70:sw" )
			)
			( pin "EU4D3.36"
				( objectStatus "@baseboard_fab2_lib.baseboard_fab2(sch_1):page203_i70:tout_flt" )
			)
			( pin "EU4D3.3"
				( objectStatus "@baseboard_fab2_lib.baseboard_fab2(sch_1):page203_i70:vcc" )
			)
			( pin "EU4D3.4"
				( objectStatus "@baseboard_fab2_lib.baseboard_fab2(sch_1):page203_i70:vdrv" )
			)
			( pin "EU4D3.25"
				( objectStatus "@baseboard_fab2_lib.baseboard_fab2(sch_1):page203_i70:vin(0)" )
			)
			( pin "EU4D3.30"
				( objectStatus "@baseboard_fab2_lib.baseboard_fab2(sch_1):page203_i70:vin(1)" )
			)
			( pin "EU4D3.1"
				( objectStatus "@baseboard_fab2_lib.baseboard_fab2(sch_1):page203_i70:vos" )
			)
			( pin "EU4D1.33"
				( objectStatus "@baseboard_fab2_lib.baseboard_fab2(sch_1):page203_i71:boost" )
			)
			( pin "EU4D1.35"
				( objectStatus "@baseboard_fab2_lib.baseboard_fab2(sch_1):page203_i71:en" )
			)
			( pin "EU4D1.6"
				( objectStatus "@baseboard_fab2_lib.baseboard_fab2(sch_1):page203_i71:gl(0)" )
			)
			( pin "EU4D1.41"
				( objectStatus "@baseboard_fab2_lib.baseboard_fab2(sch_1):page203_i71:gl(1)" )
			)
			( pin "EU4D1.38"
				( objectStatus "@baseboard_fab2_lib.baseboard_fab2(sch_1):page203_i71:iout" )
			)
			( pin "EU4D1.2"
				( objectStatus "@baseboard_fab2_lib.baseboard_fab2(sch_1):page203_i71:lgnd" )
			)
			( pin "EU4D1.31"
				( objectStatus "@baseboard_fab2_lib.baseboard_fab2(sch_1):page203_i71:nc" )
			)
			( pin "EU4D1.37"
				( objectStatus "@baseboard_fab2_lib.baseboard_fab2(sch_1):page203_i71:ocset" )
			)
			( pin "EU4D1.5"
				( objectStatus "@baseboard_fab2_lib.baseboard_fab2(sch_1):page203_i71:pgnd(0)" )
			)
			( pin "EU4D1.7"
				( objectStatus "@baseboard_fab2_lib.baseboard_fab2(sch_1):page203_i71:pgnd(1)" )
			)
			( pin "EU4D1.40"
				( objectStatus "@baseboard_fab2_lib.baseboard_fab2(sch_1):page203_i71:pgnd(2)" )
			)
			( pin "EU4D1.32"
				( objectStatus "@baseboard_fab2_lib.baseboard_fab2(sch_1):page203_i71:phase" )
			)
			( pin "EU4D1.34"
				( objectStatus "@baseboard_fab2_lib.baseboard_fab2(sch_1):page203_i71:pwm" )
			)
			( pin "EU4D1.39"
				( objectStatus "@baseboard_fab2_lib.baseboard_fab2(sch_1):page203_i71:refin" )
			)
			( pin "EU4D1.10"
				( objectStatus "@baseboard_fab2_lib.baseboard_fab2(sch_1):page203_i71:sw" )
			)
			( pin "EU4D1.36"
				( objectStatus "@baseboard_fab2_lib.baseboard_fab2(sch_1):page203_i71:tout_flt" )
			)
			( pin "EU4D1.3"
				( objectStatus "@baseboard_fab2_lib.baseboard_fab2(sch_1):page203_i71:vcc" )
			)
			( pin "EU4D1.4"
				( objectStatus "@baseboard_fab2_lib.baseboard_fab2(sch_1):page203_i71:vdrv" )
			)
			( pin "EU4D1.25"
				( objectStatus "@baseboard_fab2_lib.baseboard_fab2(sch_1):page203_i71:vin(0)" )
			)
			( pin "EU4D1.30"
				( objectStatus "@baseboard_fab2_lib.baseboard_fab2(sch_1):page203_i71:vin(1)" )
			)
			( pin "EU4D1.1"
				( objectStatus "@baseboard_fab2_lib.baseboard_fab2(sch_1):page203_i71:vos" )
			)
			( pin "R4D72.1"
				( objectStatus "@baseboard_fab2_lib.baseboard_fab2(sch_1):page203_i89:a" )
			)
			( pin "R4D72.2"
				( objectStatus "@baseboard_fab2_lib.baseboard_fab2(sch_1):page203_i89:b" )
			)
			( pin "R4D71.1"
				( objectStatus "@baseboard_fab2_lib.baseboard_fab2(sch_1):page203_i91:a" )
			)
			( pin "R4D71.2"
				( objectStatus "@baseboard_fab2_lib.baseboard_fab2(sch_1):page203_i91:b" )
			)
			( pin "L4C3.1"
				( objectStatus "@baseboard_fab2_lib.baseboard_fab2(sch_1):page204_i5:ina" )
			)
			( pin "L4C3.2"
				( objectStatus "@baseboard_fab2_lib.baseboard_fab2(sch_1):page204_i5:inb" )
			)
			( pin "C4D12.1"
				( objectStatus "@baseboard_fab2_lib.baseboard_fab2(sch_1):page204_i9:a" )
			)
			( pin "C4D12.2"
				( objectStatus "@baseboard_fab2_lib.baseboard_fab2(sch_1):page204_i9:b" )
			)
			( pin "C4D47.1"
				( objectStatus "@baseboard_fab2_lib.baseboard_fab2(sch_1):page204_i18:a" )
			)
			( pin "C4D47.2"
				( objectStatus "@baseboard_fab2_lib.baseboard_fab2(sch_1):page204_i18:b" )
			)
			( pin "C4C14.1"
				( objectStatus "@baseboard_fab2_lib.baseboard_fab2(sch_1):page204_i19:a" )
			)
			( pin "C4C14.2"
				( objectStatus "@baseboard_fab2_lib.baseboard_fab2(sch_1):page204_i19:b" )
			)
			( pin "C4C17.1"
				( objectStatus "@baseboard_fab2_lib.baseboard_fab2(sch_1):page204_i22:a" )
			)
			( pin "C4C17.2"
				( objectStatus "@baseboard_fab2_lib.baseboard_fab2(sch_1):page204_i22:b" )
			)
			( pin "R6P47.1"
				( objectStatus "@baseboard_fab2_lib.baseboard_fab2(sch_1):page204_i33:a" )
			)
			( pin "R6P47.2"
				( objectStatus "@baseboard_fab2_lib.baseboard_fab2(sch_1):page204_i33:b" )
			)
			( pin "C4D46.1"
				( objectStatus "@baseboard_fab2_lib.baseboard_fab2(sch_1):page204_i34:a" )
			)
			( pin "C4D46.2"
				( objectStatus "@baseboard_fab2_lib.baseboard_fab2(sch_1):page204_i34:b" )
			)
			( pin "C4C19.1"
				( objectStatus "@baseboard_fab2_lib.baseboard_fab2(sch_1):page204_i35:a" )
			)
			( pin "C4C19.2"
				( objectStatus "@baseboard_fab2_lib.baseboard_fab2(sch_1):page204_i35:b" )
			)
			( pin "C4C18.1"
				( objectStatus "@baseboard_fab2_lib.baseboard_fab2(sch_1):page204_i36:a" )
			)
			( pin "C4C18.2"
				( objectStatus "@baseboard_fab2_lib.baseboard_fab2(sch_1):page204_i36:b" )
			)
			( pin "C6N10.1"
				( objectStatus "@baseboard_fab2_lib.baseboard_fab2(sch_1):page204_i37:a" )
			)
			( pin "C6N10.2"
				( objectStatus "@baseboard_fab2_lib.baseboard_fab2(sch_1):page204_i37:b" )
			)
			( pin "C6P17.1"
				( objectStatus "@baseboard_fab2_lib.baseboard_fab2(sch_1):page204_i38:a" )
			)
			( pin "C6P17.2"
				( objectStatus "@baseboard_fab2_lib.baseboard_fab2(sch_1):page204_i38:b" )
			)
			( pin "C6N11.1"
				( objectStatus "@baseboard_fab2_lib.baseboard_fab2(sch_1):page204_i42:a" )
			)
			( pin "C6N11.2"
				( objectStatus "@baseboard_fab2_lib.baseboard_fab2(sch_1):page204_i42:b" )
			)
			( pin "R4C6.1"
				( objectStatus "@baseboard_fab2_lib.baseboard_fab2(sch_1):page204_i45:a" )
			)
			( pin "R4C6.2"
				( objectStatus "@baseboard_fab2_lib.baseboard_fab2(sch_1):page204_i45:b" )
			)
			( pin "L4C1.1"
				( objectStatus "@baseboard_fab2_lib.baseboard_fab2(sch_1):page204_i46:ina" )
			)
			( pin "L4C1.2"
				( objectStatus "@baseboard_fab2_lib.baseboard_fab2(sch_1):page204_i46:inb" )
			)
			( pin "C4D2.1"
				( objectStatus "@baseboard_fab2_lib.baseboard_fab2(sch_1):page204_i48:a" )
			)
			( pin "C4D2.2"
				( objectStatus "@baseboard_fab2_lib.baseboard_fab2(sch_1):page204_i48:b" )
			)
			( pin "C4E16.1"
				( objectStatus "@baseboard_fab2_lib.baseboard_fab2(sch_1):page204_i50:a" )
			)
			( pin "C4E16.2"
				( objectStatus "@baseboard_fab2_lib.baseboard_fab2(sch_1):page204_i50:b" )
			)
			( pin "C4C2.1"
				( objectStatus "@baseboard_fab2_lib.baseboard_fab2(sch_1):page204_i51:a" )
			)
			( pin "C4C2.2"
				( objectStatus "@baseboard_fab2_lib.baseboard_fab2(sch_1):page204_i51:b" )
			)
			( pin "U4C1.1"
				( objectStatus "@baseboard_fab2_lib.baseboard_fab2(sch_1):page204_i53:gnd(0)" )
			)
			( pin "U4C1.2"
				( objectStatus "@baseboard_fab2_lib.baseboard_fab2(sch_1):page204_i53:gnd(1)" )
			)
			( pin "U4C1.6"
				( objectStatus "@baseboard_fab2_lib.baseboard_fab2(sch_1):page204_i53:\out\" )
			)
			( pin "U4C1.5"
				( objectStatus "@baseboard_fab2_lib.baseboard_fab2(sch_1):page204_i53:rsn" )
			)
			( pin "U4C1.4"
				( objectStatus "@baseboard_fab2_lib.baseboard_fab2(sch_1):page204_i53:rsp" )
			)
			( pin "U4C1.3"
				( objectStatus "@baseboard_fab2_lib.baseboard_fab2(sch_1):page204_i53:vcc" )
			)
			( pin "R4E14.1"
				( objectStatus "@baseboard_fab2_lib.baseboard_fab2(sch_1):page204_i60:a" )
			)
			( pin "R4E14.2"
				( objectStatus "@baseboard_fab2_lib.baseboard_fab2(sch_1):page204_i60:b" )
			)
			( pin "R4E16.1"
				( objectStatus "@baseboard_fab2_lib.baseboard_fab2(sch_1):page204_i61:a" )
			)
			( pin "R4E16.2"
				( objectStatus "@baseboard_fab2_lib.baseboard_fab2(sch_1):page204_i61:b" )
			)
			( pin "R4E17.1"
				( objectStatus "@baseboard_fab2_lib.baseboard_fab2(sch_1):page204_i62:a" )
			)
			( pin "R4E17.2"
				( objectStatus "@baseboard_fab2_lib.baseboard_fab2(sch_1):page204_i62:b" )
			)
			( pin "R4E15.1"
				( objectStatus "@baseboard_fab2_lib.baseboard_fab2(sch_1):page204_i63:a" )
			)
			( pin "R4E15.2"
				( objectStatus "@baseboard_fab2_lib.baseboard_fab2(sch_1):page204_i63:b" )
			)
			( pin "R4E18.1"
				( objectStatus "@baseboard_fab2_lib.baseboard_fab2(sch_1):page204_i64:a" )
			)
			( pin "R4E18.2"
				( objectStatus "@baseboard_fab2_lib.baseboard_fab2(sch_1):page204_i64:b" )
			)
			( pin "C4C12.1"
				( objectStatus "@baseboard_fab2_lib.baseboard_fab2(sch_1):page204_i67:a" )
			)
			( pin "C4C12.2"
				( objectStatus "@baseboard_fab2_lib.baseboard_fab2(sch_1):page204_i67:b" )
			)
			( pin "C6R2.1"
				( objectStatus "@baseboard_fab2_lib.baseboard_fab2(sch_1):page204_i70:a" )
			)
			( pin "C6R2.2"
				( objectStatus "@baseboard_fab2_lib.baseboard_fab2(sch_1):page204_i70:b" )
			)
			( pin "EU4C2.33"
				( objectStatus "@baseboard_fab2_lib.baseboard_fab2(sch_1):page204_i71:boost" )
			)
			( pin "EU4C2.35"
				( objectStatus "@baseboard_fab2_lib.baseboard_fab2(sch_1):page204_i71:en" )
			)
			( pin "EU4C2.6"
				( objectStatus "@baseboard_fab2_lib.baseboard_fab2(sch_1):page204_i71:gl(0)" )
			)
			( pin "EU4C2.41"
				( objectStatus "@baseboard_fab2_lib.baseboard_fab2(sch_1):page204_i71:gl(1)" )
			)
			( pin "EU4C2.38"
				( objectStatus "@baseboard_fab2_lib.baseboard_fab2(sch_1):page204_i71:iout" )
			)
			( pin "EU4C2.2"
				( objectStatus "@baseboard_fab2_lib.baseboard_fab2(sch_1):page204_i71:lgnd" )
			)
			( pin "EU4C2.31"
				( objectStatus "@baseboard_fab2_lib.baseboard_fab2(sch_1):page204_i71:nc" )
			)
			( pin "EU4C2.37"
				( objectStatus "@baseboard_fab2_lib.baseboard_fab2(sch_1):page204_i71:ocset" )
			)
			( pin "EU4C2.5"
				( objectStatus "@baseboard_fab2_lib.baseboard_fab2(sch_1):page204_i71:pgnd(0)" )
			)
			( pin "EU4C2.7"
				( objectStatus "@baseboard_fab2_lib.baseboard_fab2(sch_1):page204_i71:pgnd(1)" )
			)
			( pin "EU4C2.40"
				( objectStatus "@baseboard_fab2_lib.baseboard_fab2(sch_1):page204_i71:pgnd(2)" )
			)
			( pin "EU4C2.32"
				( objectStatus "@baseboard_fab2_lib.baseboard_fab2(sch_1):page204_i71:phase" )
			)
			( pin "EU4C2.34"
				( objectStatus "@baseboard_fab2_lib.baseboard_fab2(sch_1):page204_i71:pwm" )
			)
			( pin "EU4C2.39"
				( objectStatus "@baseboard_fab2_lib.baseboard_fab2(sch_1):page204_i71:refin" )
			)
			( pin "EU4C2.10"
				( objectStatus "@baseboard_fab2_lib.baseboard_fab2(sch_1):page204_i71:sw" )
			)
			( pin "EU4C2.36"
				( objectStatus "@baseboard_fab2_lib.baseboard_fab2(sch_1):page204_i71:tout_flt" )
			)
			( pin "EU4C2.3"
				( objectStatus "@baseboard_fab2_lib.baseboard_fab2(sch_1):page204_i71:vcc" )
			)
			( pin "EU4C2.4"
				( objectStatus "@baseboard_fab2_lib.baseboard_fab2(sch_1):page204_i71:vdrv" )
			)
			( pin "EU4C2.25"
				( objectStatus "@baseboard_fab2_lib.baseboard_fab2(sch_1):page204_i71:vin(0)" )
			)
			( pin "EU4C2.30"
				( objectStatus "@baseboard_fab2_lib.baseboard_fab2(sch_1):page204_i71:vin(1)" )
			)
			( pin "EU4C2.1"
				( objectStatus "@baseboard_fab2_lib.baseboard_fab2(sch_1):page204_i71:vos" )
			)
			( pin "R4D68.1"
				( objectStatus "@baseboard_fab2_lib.baseboard_fab2(sch_1):page204_i83:a" )
			)
			( pin "R4D68.2"
				( objectStatus "@baseboard_fab2_lib.baseboard_fab2(sch_1):page204_i83:b" )
			)
			( pin "C6N7.1"
				( objectStatus "@baseboard_fab2_lib.baseboard_fab2(sch_1):page205_i5:a" )
			)
			( pin "C6N7.2"
				( objectStatus "@baseboard_fab2_lib.baseboard_fab2(sch_1):page205_i5:b" )
			)
			( pin "L4C2.1"
				( objectStatus "@baseboard_fab2_lib.baseboard_fab2(sch_1):page205_i7:ina" )
			)
			( pin "L4C2.2"
				( objectStatus "@baseboard_fab2_lib.baseboard_fab2(sch_1):page205_i7:inb" )
			)
			( pin "C6N1.1"
				( objectStatus "@baseboard_fab2_lib.baseboard_fab2(sch_1):page205_i12:a" )
			)
			( pin "C6N1.2"
				( objectStatus "@baseboard_fab2_lib.baseboard_fab2(sch_1):page205_i12:b" )
			)
			( pin "C6N4.1"
				( objectStatus "@baseboard_fab2_lib.baseboard_fab2(sch_1):page205_i14:a" )
			)
			( pin "C6N4.2"
				( objectStatus "@baseboard_fab2_lib.baseboard_fab2(sch_1):page205_i14:b" )
			)
			( pin "C4C5.1"
				( objectStatus "@baseboard_fab2_lib.baseboard_fab2(sch_1):page205_i16:a" )
			)
			( pin "C4C5.2"
				( objectStatus "@baseboard_fab2_lib.baseboard_fab2(sch_1):page205_i16:b" )
			)
			( pin "C4C4.1"
				( objectStatus "@baseboard_fab2_lib.baseboard_fab2(sch_1):page205_i18:a" )
			)
			( pin "C4C4.2"
				( objectStatus "@baseboard_fab2_lib.baseboard_fab2(sch_1):page205_i18:b" )
			)
			( pin "R6N3.1"
				( objectStatus "@baseboard_fab2_lib.baseboard_fab2(sch_1):page205_i19:a" )
			)
			( pin "R6N3.2"
				( objectStatus "@baseboard_fab2_lib.baseboard_fab2(sch_1):page205_i19:b" )
			)
			( pin "C4C6.1"
				( objectStatus "@baseboard_fab2_lib.baseboard_fab2(sch_1):page205_i20:a" )
			)
			( pin "C4C6.2"
				( objectStatus "@baseboard_fab2_lib.baseboard_fab2(sch_1):page205_i20:b" )
			)
			( pin "R4C5.1"
				( objectStatus "@baseboard_fab2_lib.baseboard_fab2(sch_1):page205_i24:a" )
			)
			( pin "R4C5.2"
				( objectStatus "@baseboard_fab2_lib.baseboard_fab2(sch_1):page205_i24:b" )
			)
			( pin "C4C8.1"
				( objectStatus "@baseboard_fab2_lib.baseboard_fab2(sch_1):page205_i25:a" )
			)
			( pin "C4C8.2"
				( objectStatus "@baseboard_fab2_lib.baseboard_fab2(sch_1):page205_i25:b" )
			)
			( pin "R4C4.1"
				( objectStatus "@baseboard_fab2_lib.baseboard_fab2(sch_1):page205_i26:a" )
			)
			( pin "R4C4.2"
				( objectStatus "@baseboard_fab2_lib.baseboard_fab2(sch_1):page205_i26:b" )
			)
			( pin "R4C1.1"
				( objectStatus "@baseboard_fab2_lib.baseboard_fab2(sch_1):page205_i29:a" )
			)
			( pin "R4C1.2"
				( objectStatus "@baseboard_fab2_lib.baseboard_fab2(sch_1):page205_i29:b" )
			)
			( pin "R4C2.1"
				( objectStatus "@baseboard_fab2_lib.baseboard_fab2(sch_1):page205_i30:a" )
			)
			( pin "R4C2.2"
				( objectStatus "@baseboard_fab2_lib.baseboard_fab2(sch_1):page205_i30:b" )
			)
			( pin "C4C10.1"
				( objectStatus "@baseboard_fab2_lib.baseboard_fab2(sch_1):page205_i31:a" )
			)
			( pin "C4C10.2"
				( objectStatus "@baseboard_fab2_lib.baseboard_fab2(sch_1):page205_i31:b" )
			)
			( pin "C4C9.1"
				( objectStatus "@baseboard_fab2_lib.baseboard_fab2(sch_1):page205_i32:a" )
			)
			( pin "C4C9.2"
				( objectStatus "@baseboard_fab2_lib.baseboard_fab2(sch_1):page205_i32:b" )
			)
			( pin "C6N2.1"
				( objectStatus "@baseboard_fab2_lib.baseboard_fab2(sch_1):page205_i33:a" )
			)
			( pin "C6N2.2"
				( objectStatus "@baseboard_fab2_lib.baseboard_fab2(sch_1):page205_i33:b" )
			)
			( pin "C6N3.1"
				( objectStatus "@baseboard_fab2_lib.baseboard_fab2(sch_1):page205_i34:a" )
			)
			( pin "C6N3.2"
				( objectStatus "@baseboard_fab2_lib.baseboard_fab2(sch_1):page205_i34:b" )
			)
			( pin "C6N6.1"
				( objectStatus "@baseboard_fab2_lib.baseboard_fab2(sch_1):page205_i35:a" )
			)
			( pin "C6N6.2"
				( objectStatus "@baseboard_fab2_lib.baseboard_fab2(sch_1):page205_i35:b" )
			)
			( pin "R4C3.1"
				( objectStatus "@baseboard_fab2_lib.baseboard_fab2(sch_1):page205_i37:a" )
			)
			( pin "R4C3.2"
				( objectStatus "@baseboard_fab2_lib.baseboard_fab2(sch_1):page205_i37:b" )
			)
			( pin "C4C11.1"
				( objectStatus "@baseboard_fab2_lib.baseboard_fab2(sch_1):page205_i43:a" )
			)
			( pin "C4C11.2"
				( objectStatus "@baseboard_fab2_lib.baseboard_fab2(sch_1):page205_i43:b" )
			)
			( pin "R6N4.1"
				( objectStatus "@baseboard_fab2_lib.baseboard_fab2(sch_1):page205_i45:a" )
			)
			( pin "R6N4.2"
				( objectStatus "@baseboard_fab2_lib.baseboard_fab2(sch_1):page205_i45:b" )
			)
			( pin "EU4C1.33"
				( objectStatus "@baseboard_fab2_lib.baseboard_fab2(sch_1):page205_i46:boost" )
			)
			( pin "EU4C1.35"
				( objectStatus "@baseboard_fab2_lib.baseboard_fab2(sch_1):page205_i46:en" )
			)
			( pin "EU4C1.6"
				( objectStatus "@baseboard_fab2_lib.baseboard_fab2(sch_1):page205_i46:gl(0)" )
			)
			( pin "EU4C1.41"
				( objectStatus "@baseboard_fab2_lib.baseboard_fab2(sch_1):page205_i46:gl(1)" )
			)
			( pin "EU4C1.38"
				( objectStatus "@baseboard_fab2_lib.baseboard_fab2(sch_1):page205_i46:iout" )
			)
			( pin "EU4C1.2"
				( objectStatus "@baseboard_fab2_lib.baseboard_fab2(sch_1):page205_i46:lgnd" )
			)
			( pin "EU4C1.31"
				( objectStatus "@baseboard_fab2_lib.baseboard_fab2(sch_1):page205_i46:nc" )
			)
			( pin "EU4C1.37"
				( objectStatus "@baseboard_fab2_lib.baseboard_fab2(sch_1):page205_i46:ocset" )
			)
			( pin "EU4C1.5"
				( objectStatus "@baseboard_fab2_lib.baseboard_fab2(sch_1):page205_i46:pgnd(0)" )
			)
			( pin "EU4C1.7"
				( objectStatus "@baseboard_fab2_lib.baseboard_fab2(sch_1):page205_i46:pgnd(1)" )
			)
			( pin "EU4C1.40"
				( objectStatus "@baseboard_fab2_lib.baseboard_fab2(sch_1):page205_i46:pgnd(2)" )
			)
			( pin "EU4C1.32"
				( objectStatus "@baseboard_fab2_lib.baseboard_fab2(sch_1):page205_i46:phase" )
			)
			( pin "EU4C1.34"
				( objectStatus "@baseboard_fab2_lib.baseboard_fab2(sch_1):page205_i46:pwm" )
			)
			( pin "EU4C1.39"
				( objectStatus "@baseboard_fab2_lib.baseboard_fab2(sch_1):page205_i46:refin" )
			)
			( pin "EU4C1.10"
				( objectStatus "@baseboard_fab2_lib.baseboard_fab2(sch_1):page205_i46:sw" )
			)
			( pin "EU4C1.36"
				( objectStatus "@baseboard_fab2_lib.baseboard_fab2(sch_1):page205_i46:tout_flt" )
			)
			( pin "EU4C1.3"
				( objectStatus "@baseboard_fab2_lib.baseboard_fab2(sch_1):page205_i46:vcc" )
			)
			( pin "EU4C1.4"
				( objectStatus "@baseboard_fab2_lib.baseboard_fab2(sch_1):page205_i46:vdrv" )
			)
			( pin "EU4C1.25"
				( objectStatus "@baseboard_fab2_lib.baseboard_fab2(sch_1):page205_i46:vin(0)" )
			)
			( pin "EU4C1.30"
				( objectStatus "@baseboard_fab2_lib.baseboard_fab2(sch_1):page205_i46:vin(1)" )
			)
			( pin "EU4C1.1"
				( objectStatus "@baseboard_fab2_lib.baseboard_fab2(sch_1):page205_i46:vos" )
			)
			( pin "R4C13.1"
				( objectStatus "@baseboard_fab2_lib.baseboard_fab2(sch_1):page205_i62:a" )
			)
			( pin "R4C13.2"
				( objectStatus "@baseboard_fab2_lib.baseboard_fab2(sch_1):page205_i62:b" )
			)
			( pin "R9P1.1"
				( objectStatus "@baseboard_fab2_lib.baseboard_fab2(sch_1):page206_i4:a" )
			)
			( pin "R9P1.2"
				( objectStatus "@baseboard_fab2_lib.baseboard_fab2(sch_1):page206_i4:b" )
			)
			( pin "R1D6.1"
				( objectStatus "@baseboard_fab2_lib.baseboard_fab2(sch_1):page206_i6:a" )
			)
			( pin "R1D6.2"
				( objectStatus "@baseboard_fab2_lib.baseboard_fab2(sch_1):page206_i6:b" )
			)
			( pin "R1D7.1"
				( objectStatus "@baseboard_fab2_lib.baseboard_fab2(sch_1):page206_i7:a" )
			)
			( pin "R1D7.2"
				( objectStatus "@baseboard_fab2_lib.baseboard_fab2(sch_1):page206_i7:b" )
			)
			( pin "R1C23.1"
				( objectStatus "@baseboard_fab2_lib.baseboard_fab2(sch_1):page206_i27:a" )
			)
			( pin "R1C23.2"
				( objectStatus "@baseboard_fab2_lib.baseboard_fab2(sch_1):page206_i27:b" )
			)
			( pin "R1C25.1"
				( objectStatus "@baseboard_fab2_lib.baseboard_fab2(sch_1):page206_i28:a" )
			)
			( pin "R1C25.2"
				( objectStatus "@baseboard_fab2_lib.baseboard_fab2(sch_1):page206_i28:b" )
			)
			( pin "C1C13.1"
				( objectStatus "@baseboard_fab2_lib.baseboard_fab2(sch_1):page206_i29:a" )
			)
			( pin "C1C13.2"
				( objectStatus "@baseboard_fab2_lib.baseboard_fab2(sch_1):page206_i29:b" )
			)
			( pin "C1C14.1"
				( objectStatus "@baseboard_fab2_lib.baseboard_fab2(sch_1):page206_i31:a" )
			)
			( pin "C1C14.2"
				( objectStatus "@baseboard_fab2_lib.baseboard_fab2(sch_1):page206_i31:b" )
			)
			( pin "R1D53.1"
				( objectStatus "@baseboard_fab2_lib.baseboard_fab2(sch_1):page206_i33:a" )
			)
			( pin "R1D53.2"
				( objectStatus "@baseboard_fab2_lib.baseboard_fab2(sch_1):page206_i33:b" )
			)
			( pin "R1C18.1"
				( objectStatus "@baseboard_fab2_lib.baseboard_fab2(sch_1):page206_i34:a" )
			)
			( pin "R1C18.2"
				( objectStatus "@baseboard_fab2_lib.baseboard_fab2(sch_1):page206_i34:b" )
			)
			( pin "R1C28.1"
				( objectStatus "@baseboard_fab2_lib.baseboard_fab2(sch_1):page206_i35:a" )
			)
			( pin "R1C28.2"
				( objectStatus "@baseboard_fab2_lib.baseboard_fab2(sch_1):page206_i35:b" )
			)
			( pin "R1D8.1"
				( objectStatus "@baseboard_fab2_lib.baseboard_fab2(sch_1):page206_i36:a" )
			)
			( pin "R1D8.2"
				( objectStatus "@baseboard_fab2_lib.baseboard_fab2(sch_1):page206_i36:b" )
			)
			( pin "R1D3.1"
				( objectStatus "@baseboard_fab2_lib.baseboard_fab2(sch_1):page206_i37:a" )
			)
			( pin "R1D3.2"
				( objectStatus "@baseboard_fab2_lib.baseboard_fab2(sch_1):page206_i37:b" )
			)
			( pin "R1D2.1"
				( objectStatus "@baseboard_fab2_lib.baseboard_fab2(sch_1):page206_i38:a" )
			)
			( pin "R1D2.2"
				( objectStatus "@baseboard_fab2_lib.baseboard_fab2(sch_1):page206_i38:b" )
			)
			( pin "C1C7.1"
				( objectStatus "@baseboard_fab2_lib.baseboard_fab2(sch_1):page206_i41:a" )
			)
			( pin "C1C7.2"
				( objectStatus "@baseboard_fab2_lib.baseboard_fab2(sch_1):page206_i41:b" )
			)
			( pin "C1C9.1"
				( objectStatus "@baseboard_fab2_lib.baseboard_fab2(sch_1):page206_i42:a" )
			)
			( pin "C1C9.2"
				( objectStatus "@baseboard_fab2_lib.baseboard_fab2(sch_1):page206_i42:b" )
			)
			( pin "R1C14.1"
				( objectStatus "@baseboard_fab2_lib.baseboard_fab2(sch_1):page206_i46:a" )
			)
			( pin "R1C14.2"
				( objectStatus "@baseboard_fab2_lib.baseboard_fab2(sch_1):page206_i46:b" )
			)
			( pin "R1C13.1"
				( objectStatus "@baseboard_fab2_lib.baseboard_fab2(sch_1):page206_i49:a" )
			)
			( pin "R1C13.2"
				( objectStatus "@baseboard_fab2_lib.baseboard_fab2(sch_1):page206_i49:b" )
			)
			( pin "R9P2.1"
				( objectStatus "@baseboard_fab2_lib.baseboard_fab2(sch_1):page206_i53:a" )
			)
			( pin "R9P2.2"
				( objectStatus "@baseboard_fab2_lib.baseboard_fab2(sch_1):page206_i53:b" )
			)
			( pin "R1D9.1"
				( objectStatus "@baseboard_fab2_lib.baseboard_fab2(sch_1):page206_i54:a" )
			)
			( pin "R1D9.2"
				( objectStatus "@baseboard_fab2_lib.baseboard_fab2(sch_1):page206_i54:b" )
			)
			( pin "R1C16.1"
				( objectStatus "@baseboard_fab2_lib.baseboard_fab2(sch_1):page206_i56:a" )
			)
			( pin "R1C16.2"
				( objectStatus "@baseboard_fab2_lib.baseboard_fab2(sch_1):page206_i56:b" )
			)
			( pin "C1C16.1"
				( objectStatus "@baseboard_fab2_lib.baseboard_fab2(sch_1):page206_i68:a" )
			)
			( pin "C1C16.2"
				( objectStatus "@baseboard_fab2_lib.baseboard_fab2(sch_1):page206_i68:b" )
			)
			( pin "C1C10.1"
				( objectStatus "@baseboard_fab2_lib.baseboard_fab2(sch_1):page206_i69:a" )
			)
			( pin "C1C10.2"
				( objectStatus "@baseboard_fab2_lib.baseboard_fab2(sch_1):page206_i69:b" )
			)
			( pin "C1C11.1"
				( objectStatus "@baseboard_fab2_lib.baseboard_fab2(sch_1):page206_i71:a" )
			)
			( pin "C1C11.2"
				( objectStatus "@baseboard_fab2_lib.baseboard_fab2(sch_1):page206_i71:b" )
			)
			( pin "C1C8.1"
				( objectStatus "@baseboard_fab2_lib.baseboard_fab2(sch_1):page206_i73:a" )
			)
			( pin "C1C8.2"
				( objectStatus "@baseboard_fab2_lib.baseboard_fab2(sch_1):page206_i73:b" )
			)
			( pin "R1C21.1"
				( objectStatus "@baseboard_fab2_lib.baseboard_fab2(sch_1):page206_i77:a" )
			)
			( pin "R1C21.2"
				( objectStatus "@baseboard_fab2_lib.baseboard_fab2(sch_1):page206_i77:b" )
			)
			( pin "C1D1.1"
				( objectStatus "@baseboard_fab2_lib.baseboard_fab2(sch_1):page206_i78:a" )
			)
			( pin "C1D1.2"
				( objectStatus "@baseboard_fab2_lib.baseboard_fab2(sch_1):page206_i78:b" )
			)
			( pin "R1D4.1"
				( objectStatus "@baseboard_fab2_lib.baseboard_fab2(sch_1):page206_i79:a" )
			)
			( pin "R1D4.2"
				( objectStatus "@baseboard_fab2_lib.baseboard_fab2(sch_1):page206_i79:b" )
			)
			( pin "R9N7.1"
				( objectStatus "@baseboard_fab2_lib.baseboard_fab2(sch_1):page206_i111:a" )
			)
			( pin "R9N7.2"
				( objectStatus "@baseboard_fab2_lib.baseboard_fab2(sch_1):page206_i111:b" )
			)
			( pin "R9N8.1"
				( objectStatus "@baseboard_fab2_lib.baseboard_fab2(sch_1):page206_i112:a" )
			)
			( pin "R9N8.2"
				( objectStatus "@baseboard_fab2_lib.baseboard_fab2(sch_1):page206_i112:b" )
			)
			( pin "R1C30.1"
				( objectStatus "@baseboard_fab2_lib.baseboard_fab2(sch_1):page206_i113:a" )
			)
			( pin "R1C30.2"
				( objectStatus "@baseboard_fab2_lib.baseboard_fab2(sch_1):page206_i113:b" )
			)
			( pin "C1C23.1"
				( objectStatus "@baseboard_fab2_lib.baseboard_fab2(sch_1):page206_i114:a" )
			)
			( pin "C1C23.2"
				( objectStatus "@baseboard_fab2_lib.baseboard_fab2(sch_1):page206_i114:b" )
			)
			( pin "R1D1.1"
				( objectStatus "@baseboard_fab2_lib.baseboard_fab2(sch_1):page206_i116:a" )
			)
			( pin "R1D1.2"
				( objectStatus "@baseboard_fab2_lib.baseboard_fab2(sch_1):page206_i116:b" )
			)
			( pin "R9P3.1"
				( objectStatus "@baseboard_fab2_lib.baseboard_fab2(sch_1):page206_i117:a" )
			)
			( pin "R9P3.2"
				( objectStatus "@baseboard_fab2_lib.baseboard_fab2(sch_1):page206_i117:b" )
			)
			( pin "R9N16.1"
				( objectStatus "@baseboard_fab2_lib.baseboard_fab2(sch_1):page206_i119:a" )
			)
			( pin "R9N16.2"
				( objectStatus "@baseboard_fab2_lib.baseboard_fab2(sch_1):page206_i119:b" )
			)
			( pin "R9N14.1"
				( objectStatus "@baseboard_fab2_lib.baseboard_fab2(sch_1):page206_i120:a" )
			)
			( pin "R9N14.2"
				( objectStatus "@baseboard_fab2_lib.baseboard_fab2(sch_1):page206_i120:b" )
			)
			( pin "R9N15.1"
				( objectStatus "@baseboard_fab2_lib.baseboard_fab2(sch_1):page206_i122:a" )
			)
			( pin "R9N15.2"
				( objectStatus "@baseboard_fab2_lib.baseboard_fab2(sch_1):page206_i122:b" )
			)
			( pin "R9N17.1"
				( objectStatus "@baseboard_fab2_lib.baseboard_fab2(sch_1):page206_i123:a" )
			)
			( pin "R9N17.2"
				( objectStatus "@baseboard_fab2_lib.baseboard_fab2(sch_1):page206_i123:b" )
			)
			( pin "R9N12.1"
				( objectStatus "@baseboard_fab2_lib.baseboard_fab2(sch_1):page206_i124:a" )
			)
			( pin "R9N12.2"
				( objectStatus "@baseboard_fab2_lib.baseboard_fab2(sch_1):page206_i124:b" )
			)
			( pin "R9N10.1"
				( objectStatus "@baseboard_fab2_lib.baseboard_fab2(sch_1):page206_i125:a" )
			)
			( pin "R9N10.2"
				( objectStatus "@baseboard_fab2_lib.baseboard_fab2(sch_1):page206_i125:b" )
			)
			( pin "R9N9.1"
				( objectStatus "@baseboard_fab2_lib.baseboard_fab2(sch_1):page206_i126:a" )
			)
			( pin "R9N9.2"
				( objectStatus "@baseboard_fab2_lib.baseboard_fab2(sch_1):page206_i126:b" )
			)
			( pin "R9N5.1"
				( objectStatus "@baseboard_fab2_lib.baseboard_fab2(sch_1):page206_i128:a" )
			)
			( pin "R9N5.2"
				( objectStatus "@baseboard_fab2_lib.baseboard_fab2(sch_1):page206_i128:b" )
			)
			( pin "EU1C2.23"
				( objectStatus "@baseboard_fab2_lib.baseboard_fab2(sch_1):page206_i130:airef1" )
			)
			( pin "EU1C2.25"
				( objectStatus "@baseboard_fab2_lib.baseboard_fab2(sch_1):page206_i130:airef2" )
			)
			( pin "EU1C2.27"
				( objectStatus "@baseboard_fab2_lib.baseboard_fab2(sch_1):page206_i130:airef3" )
			)
			( pin "EU1C2.29"
				( objectStatus "@baseboard_fab2_lib.baseboard_fab2(sch_1):page206_i130:airef4" )
			)
			( pin "EU1C2.31"
				( objectStatus "@baseboard_fab2_lib.baseboard_fab2(sch_1):page206_i130:airef5" )
			)
			( pin "EU1C2.33"
				( objectStatus "@baseboard_fab2_lib.baseboard_fab2(sch_1):page206_i130:airef6" )
			)
			( pin "EU1C2.24"
				( objectStatus "@baseboard_fab2_lib.baseboard_fab2(sch_1):page206_i130:aisen1" )
			)
			( pin "EU1C2.26"
				( objectStatus "@baseboard_fab2_lib.baseboard_fab2(sch_1):page206_i130:aisen2" )
			)
			( pin "EU1C2.28"
				( objectStatus "@baseboard_fab2_lib.baseboard_fab2(sch_1):page206_i130:aisen3" )
			)
			( pin "EU1C2.30"
				( objectStatus "@baseboard_fab2_lib.baseboard_fab2(sch_1):page206_i130:aisen4" )
			)
			( pin "EU1C2.32"
				( objectStatus "@baseboard_fab2_lib.baseboard_fab2(sch_1):page206_i130:aisen5" )
			)
			( pin "EU1C2.34"
				( objectStatus "@baseboard_fab2_lib.baseboard_fab2(sch_1):page206_i130:aisen6" )
			)
			( pin "EU1C2.7"
				( objectStatus "@baseboard_fab2_lib.baseboard_fab2(sch_1):page206_i130:apwm1" )
			)
			( pin "EU1C2.6"
				( objectStatus "@baseboard_fab2_lib.baseboard_fab2(sch_1):page206_i130:apwm2" )
			)
			( pin "EU1C2.5"
				( objectStatus "@baseboard_fab2_lib.baseboard_fab2(sch_1):page206_i130:apwm3" )
			)
			( pin "EU1C2.4"
				( objectStatus "@baseboard_fab2_lib.baseboard_fab2(sch_1):page206_i130:apwm4" )
			)
			( pin "EU1C2.3"
				( objectStatus "@baseboard_fab2_lib.baseboard_fab2(sch_1):page206_i130:apwm5" )
			)
			( pin "EU1C2.2"
				( objectStatus "@baseboard_fab2_lib.baseboard_fab2(sch_1):page206_i130:apwm6" )
			)
			( pin "EU1C2.43"
				( objectStatus "@baseboard_fab2_lib.baseboard_fab2(sch_1):page206_i130:atsen" )
			)
			( pin "EU1C2.22"
				( objectStatus "@baseboard_fab2_lib.baseboard_fab2(sch_1):page206_i130:avref" )
			)
			( pin "EU1C2.12"
				( objectStatus "@baseboard_fab2_lib.baseboard_fab2(sch_1):page206_i130:avren" )
			)
			( pin "EU1C2.11"
				( objectStatus "@baseboard_fab2_lib.baseboard_fab2(sch_1):page206_i130:avrrdy" )
			)
			( pin "EU1C2.21"
				( objectStatus "@baseboard_fab2_lib.baseboard_fab2(sch_1):page206_i130:avsen" )
			)
			( pin "EU1C2.37"
				( objectStatus "@baseboard_fab2_lib.baseboard_fab2(sch_1):page206_i130:biref1" )
			)
			( pin "EU1C2.38"
				( objectStatus "@baseboard_fab2_lib.baseboard_fab2(sch_1):page206_i130:bisen1" )
			)
			( pin "EU1C2.1"
				( objectStatus "@baseboard_fab2_lib.baseboard_fab2(sch_1):page206_i130:bpwm1" )
			)
			( pin "EU1C2.42"
				( objectStatus "@baseboard_fab2_lib.baseboard_fab2(sch_1):page206_i130:btsen" )
			)
			( pin "EU1C2.36"
				( objectStatus "@baseboard_fab2_lib.baseboard_fab2(sch_1):page206_i130:bvref" )
			)
			( pin "EU1C2.35"
				( objectStatus "@baseboard_fab2_lib.baseboard_fab2(sch_1):page206_i130:bvsen" )
			)
			( pin "EU1C2.46"
				( objectStatus "@baseboard_fab2_lib.baseboard_fab2(sch_1):page206_i130:iinsen" )
			)
			( pin "EU1C2.15"
				( objectStatus "@baseboard_fab2_lib.baseboard_fab2(sch_1):page206_i130:mp0" )
			)
			( pin "EU1C2.16"
				( objectStatus "@baseboard_fab2_lib.baseboard_fab2(sch_1):page206_i130:mp1" )
			)
			( pin "EU1C2.20"
				( objectStatus "@baseboard_fab2_lib.baseboard_fab2(sch_1):page206_i130:mp2" )
			)
			( pin "EU1C2.39"
				( objectStatus "@baseboard_fab2_lib.baseboard_fab2(sch_1):page206_i130:mp3" )
			)
			( pin "EU1C2.40"
				( objectStatus "@baseboard_fab2_lib.baseboard_fab2(sch_1):page206_i130:mp4" )
			)
			( pin "EU1C2.14"
				( objectStatus "@baseboard_fab2_lib.baseboard_fab2(sch_1):page206_i130:pinalrt_n" )
			)
			( pin "EU1C2.10"
				( objectStatus "@baseboard_fab2_lib.baseboard_fab2(sch_1):page206_i130:reset_n" )
			)
			( pin "EU1C2.9"
				( objectStatus "@baseboard_fab2_lib.baseboard_fab2(sch_1):page206_i130:scl" )
			)
			( pin "EU1C2.8"
				( objectStatus "@baseboard_fab2_lib.baseboard_fab2(sch_1):page206_i130:sda" )
			)
			( pin "EU1C2.49"
				( objectStatus "@baseboard_fab2_lib.baseboard_fab2(sch_1):page206_i130:thpad" )
			)
			( pin "EU1C2.19"
				( objectStatus "@baseboard_fab2_lib.baseboard_fab2(sch_1):page206_i130:valrt_n" )
			)
			( pin "EU1C2.17"
				( objectStatus "@baseboard_fab2_lib.baseboard_fab2(sch_1):page206_i130:vclk" )
			)
			( pin "EU1C2.48"
				( objectStatus "@baseboard_fab2_lib.baseboard_fab2(sch_1):page206_i130:vd12" )
			)
			( pin "EU1C2.47"
				( objectStatus "@baseboard_fab2_lib.baseboard_fab2(sch_1):page206_i130:vdd" )
			)
			( pin "EU1C2.18"
				( objectStatus "@baseboard_fab2_lib.baseboard_fab2(sch_1):page206_i130:vdio" )
			)
			( pin "EU1C2.45"
				( objectStatus "@baseboard_fab2_lib.baseboard_fab2(sch_1):page206_i130:vinsen" )
			)
			( pin "EU1C2.13"
				( objectStatus "@baseboard_fab2_lib.baseboard_fab2(sch_1):page206_i130:vrhot_n" )
			)
			( pin "EU1C2.44"
				( objectStatus "@baseboard_fab2_lib.baseboard_fab2(sch_1):page206_i130:xaddr1" )
			)
			( pin "EU1C2.41"
				( objectStatus "@baseboard_fab2_lib.baseboard_fab2(sch_1):page206_i130:xaddr2" )
			)
			( pin "C9R8.1"
				( objectStatus "@baseboard_fab2_lib.baseboard_fab2(sch_1):page207_i8:a" )
			)
			( pin "C9R8.2"
				( objectStatus "@baseboard_fab2_lib.baseboard_fab2(sch_1):page207_i8:b" )
			)
			( pin "L1E1.1"
				( objectStatus "@baseboard_fab2_lib.baseboard_fab2(sch_1):page207_i10:ina" )
			)
			( pin "L1E1.2"
				( objectStatus "@baseboard_fab2_lib.baseboard_fab2(sch_1):page207_i10:inb" )
			)
			( pin "L1D3.1"
				( objectStatus "@baseboard_fab2_lib.baseboard_fab2(sch_1):page207_i16:ina" )
			)
			( pin "L1D3.2"
				( objectStatus "@baseboard_fab2_lib.baseboard_fab2(sch_1):page207_i16:inb" )
			)
			( pin "C1E3.1"
				( objectStatus "@baseboard_fab2_lib.baseboard_fab2(sch_1):page207_i18:a" )
			)
			( pin "C1E3.2"
				( objectStatus "@baseboard_fab2_lib.baseboard_fab2(sch_1):page207_i18:b" )
			)
			( pin "EU1E2.33"
				( objectStatus "@baseboard_fab2_lib.baseboard_fab2(sch_1):page207_i20:boost" )
			)
			( pin "EU1E2.35"
				( objectStatus "@baseboard_fab2_lib.baseboard_fab2(sch_1):page207_i20:en" )
			)
			( pin "EU1E2.6"
				( objectStatus "@baseboard_fab2_lib.baseboard_fab2(sch_1):page207_i20:gl(0)" )
			)
			( pin "EU1E2.41"
				( objectStatus "@baseboard_fab2_lib.baseboard_fab2(sch_1):page207_i20:gl(1)" )
			)
			( pin "EU1E2.38"
				( objectStatus "@baseboard_fab2_lib.baseboard_fab2(sch_1):page207_i20:iout" )
			)
			( pin "EU1E2.2"
				( objectStatus "@baseboard_fab2_lib.baseboard_fab2(sch_1):page207_i20:lgnd" )
			)
			( pin "EU1E2.31"
				( objectStatus "@baseboard_fab2_lib.baseboard_fab2(sch_1):page207_i20:nc" )
			)
			( pin "EU1E2.37"
				( objectStatus "@baseboard_fab2_lib.baseboard_fab2(sch_1):page207_i20:ocset" )
			)
			( pin "EU1E2.5"
				( objectStatus "@baseboard_fab2_lib.baseboard_fab2(sch_1):page207_i20:pgnd(0)" )
			)
			( pin "EU1E2.7"
				( objectStatus "@baseboard_fab2_lib.baseboard_fab2(sch_1):page207_i20:pgnd(1)" )
			)
			( pin "EU1E2.40"
				( objectStatus "@baseboard_fab2_lib.baseboard_fab2(sch_1):page207_i20:pgnd(2)" )
			)
			( pin "EU1E2.32"
				( objectStatus "@baseboard_fab2_lib.baseboard_fab2(sch_1):page207_i20:phase" )
			)
			( pin "EU1E2.34"
				( objectStatus "@baseboard_fab2_lib.baseboard_fab2(sch_1):page207_i20:pwm" )
			)
			( pin "EU1E2.39"
				( objectStatus "@baseboard_fab2_lib.baseboard_fab2(sch_1):page207_i20:refin" )
			)
			( pin "EU1E2.10"
				( objectStatus "@baseboard_fab2_lib.baseboard_fab2(sch_1):page207_i20:sw" )
			)
			( pin "EU1E2.36"
				( objectStatus "@baseboard_fab2_lib.baseboard_fab2(sch_1):page207_i20:tout_flt" )
			)
			( pin "EU1E2.3"
				( objectStatus "@baseboard_fab2_lib.baseboard_fab2(sch_1):page207_i20:vcc" )
			)
			( pin "EU1E2.4"
				( objectStatus "@baseboard_fab2_lib.baseboard_fab2(sch_1):page207_i20:vdrv" )
			)
			( pin "EU1E2.25"
				( objectStatus "@baseboard_fab2_lib.baseboard_fab2(sch_1):page207_i20:vin(0)" )
			)
			( pin "EU1E2.30"
				( objectStatus "@baseboard_fab2_lib.baseboard_fab2(sch_1):page207_i20:vin(1)" )
			)
			( pin "EU1E2.1"
				( objectStatus "@baseboard_fab2_lib.baseboard_fab2(sch_1):page207_i20:vos" )
			)
			( pin "EU1D4.33"
				( objectStatus "@baseboard_fab2_lib.baseboard_fab2(sch_1):page207_i24:boost" )
			)
			( pin "EU1D4.35"
				( objectStatus "@baseboard_fab2_lib.baseboard_fab2(sch_1):page207_i24:en" )
			)
			( pin "EU1D4.6"
				( objectStatus "@baseboard_fab2_lib.baseboard_fab2(sch_1):page207_i24:gl(0)" )
			)
			( pin "EU1D4.41"
				( objectStatus "@baseboard_fab2_lib.baseboard_fab2(sch_1):page207_i24:gl(1)" )
			)
			( pin "EU1D4.38"
				( objectStatus "@baseboard_fab2_lib.baseboard_fab2(sch_1):page207_i24:iout" )
			)
			( pin "EU1D4.2"
				( objectStatus "@baseboard_fab2_lib.baseboard_fab2(sch_1):page207_i24:lgnd" )
			)
			( pin "EU1D4.31"
				( objectStatus "@baseboard_fab2_lib.baseboard_fab2(sch_1):page207_i24:nc" )
			)
			( pin "EU1D4.37"
				( objectStatus "@baseboard_fab2_lib.baseboard_fab2(sch_1):page207_i24:ocset" )
			)
			( pin "EU1D4.5"
				( objectStatus "@baseboard_fab2_lib.baseboard_fab2(sch_1):page207_i24:pgnd(0)" )
			)
			( pin "EU1D4.7"
				( objectStatus "@baseboard_fab2_lib.baseboard_fab2(sch_1):page207_i24:pgnd(1)" )
			)
			( pin "EU1D4.40"
				( objectStatus "@baseboard_fab2_lib.baseboard_fab2(sch_1):page207_i24:pgnd(2)" )
			)
			( pin "EU1D4.32"
				( objectStatus "@baseboard_fab2_lib.baseboard_fab2(sch_1):page207_i24:phase" )
			)
			( pin "EU1D4.34"
				( objectStatus "@baseboard_fab2_lib.baseboard_fab2(sch_1):page207_i24:pwm" )
			)
			( pin "EU1D4.39"
				( objectStatus "@baseboard_fab2_lib.baseboard_fab2(sch_1):page207_i24:refin" )
			)
			( pin "EU1D4.10"
				( objectStatus "@baseboard_fab2_lib.baseboard_fab2(sch_1):page207_i24:sw" )
			)
			( pin "EU1D4.36"
				( objectStatus "@baseboard_fab2_lib.baseboard_fab2(sch_1):page207_i24:tout_flt" )
			)
			( pin "EU1D4.3"
				( objectStatus "@baseboard_fab2_lib.baseboard_fab2(sch_1):page207_i24:vcc" )
			)
			( pin "EU1D4.4"
				( objectStatus "@baseboard_fab2_lib.baseboard_fab2(sch_1):page207_i24:vdrv" )
			)
			( pin "EU1D4.25"
				( objectStatus "@baseboard_fab2_lib.baseboard_fab2(sch_1):page207_i24:vin(0)" )
			)
			( pin "EU1D4.30"
				( objectStatus "@baseboard_fab2_lib.baseboard_fab2(sch_1):page207_i24:vin(1)" )
			)
			( pin "EU1D4.1"
				( objectStatus "@baseboard_fab2_lib.baseboard_fab2(sch_1):page207_i24:vos" )
			)
			( pin "R9R2.1"
				( objectStatus "@baseboard_fab2_lib.baseboard_fab2(sch_1):page207_i26:a" )
			)
			( pin "R9R2.2"
				( objectStatus "@baseboard_fab2_lib.baseboard_fab2(sch_1):page207_i26:b" )
			)
			( pin "C1E7.1"
				( objectStatus "@baseboard_fab2_lib.baseboard_fab2(sch_1):page207_i28:a" )
			)
			( pin "C1E7.2"
				( objectStatus "@baseboard_fab2_lib.baseboard_fab2(sch_1):page207_i28:b" )
			)
			( pin "C1E6.1"
				( objectStatus "@baseboard_fab2_lib.baseboard_fab2(sch_1):page207_i29:a" )
			)
			( pin "C1E6.2"
				( objectStatus "@baseboard_fab2_lib.baseboard_fab2(sch_1):page207_i29:b" )
			)
			( pin "C1E11.1"
				( objectStatus "@baseboard_fab2_lib.baseboard_fab2(sch_1):page207_i30:a" )
			)
			( pin "C1E11.2"
				( objectStatus "@baseboard_fab2_lib.baseboard_fab2(sch_1):page207_i30:b" )
			)
			( pin "C1E8.1"
				( objectStatus "@baseboard_fab2_lib.baseboard_fab2(sch_1):page207_i32:a" )
			)
			( pin "C1E8.2"
				( objectStatus "@baseboard_fab2_lib.baseboard_fab2(sch_1):page207_i32:b" )
			)
			( pin "C1E14.1"
				( objectStatus "@baseboard_fab2_lib.baseboard_fab2(sch_1):page207_i33:a" )
			)
			( pin "C1E14.2"
				( objectStatus "@baseboard_fab2_lib.baseboard_fab2(sch_1):page207_i33:b" )
			)
			( pin "C1E13.1"
				( objectStatus "@baseboard_fab2_lib.baseboard_fab2(sch_1):page207_i34:a" )
			)
			( pin "C1E13.2"
				( objectStatus "@baseboard_fab2_lib.baseboard_fab2(sch_1):page207_i34:b" )
			)
			( pin "C1E25.1"
				( objectStatus "@baseboard_fab2_lib.baseboard_fab2(sch_1):page207_i36:a" )
			)
			( pin "C1E25.2"
				( objectStatus "@baseboard_fab2_lib.baseboard_fab2(sch_1):page207_i36:b" )
			)
			( pin "C1E23.1"
				( objectStatus "@baseboard_fab2_lib.baseboard_fab2(sch_1):page207_i37:a" )
			)
			( pin "C1E23.2"
				( objectStatus "@baseboard_fab2_lib.baseboard_fab2(sch_1):page207_i37:b" )
			)
			( pin "C1D36.1"
				( objectStatus "@baseboard_fab2_lib.baseboard_fab2(sch_1):page207_i38:a" )
			)
			( pin "C1D36.2"
				( objectStatus "@baseboard_fab2_lib.baseboard_fab2(sch_1):page207_i38:b" )
			)
			( pin "R9R11.1"
				( objectStatus "@baseboard_fab2_lib.baseboard_fab2(sch_1):page207_i39:a" )
			)
			( pin "R9R11.2"
				( objectStatus "@baseboard_fab2_lib.baseboard_fab2(sch_1):page207_i39:b" )
			)
			( pin "C1E24.1"
				( objectStatus "@baseboard_fab2_lib.baseboard_fab2(sch_1):page207_i40:a" )
			)
			( pin "C1E24.2"
				( objectStatus "@baseboard_fab2_lib.baseboard_fab2(sch_1):page207_i40:b" )
			)
			( pin "C1D34.1"
				( objectStatus "@baseboard_fab2_lib.baseboard_fab2(sch_1):page207_i41:a" )
			)
			( pin "C1D34.2"
				( objectStatus "@baseboard_fab2_lib.baseboard_fab2(sch_1):page207_i41:b" )
			)
			( pin "C1D35.1"
				( objectStatus "@baseboard_fab2_lib.baseboard_fab2(sch_1):page207_i42:a" )
			)
			( pin "C1D35.2"
				( objectStatus "@baseboard_fab2_lib.baseboard_fab2(sch_1):page207_i42:b" )
			)
			( pin "C9R7.1"
				( objectStatus "@baseboard_fab2_lib.baseboard_fab2(sch_1):page207_i43:a" )
			)
			( pin "C9R7.2"
				( objectStatus "@baseboard_fab2_lib.baseboard_fab2(sch_1):page207_i43:b" )
			)
			( pin "C9R10.1"
				( objectStatus "@baseboard_fab2_lib.baseboard_fab2(sch_1):page207_i44:a" )
			)
			( pin "C9R10.2"
				( objectStatus "@baseboard_fab2_lib.baseboard_fab2(sch_1):page207_i44:b" )
			)
			( pin "C9R11.1"
				( objectStatus "@baseboard_fab2_lib.baseboard_fab2(sch_1):page207_i48:a" )
			)
			( pin "C9R11.2"
				( objectStatus "@baseboard_fab2_lib.baseboard_fab2(sch_1):page207_i48:b" )
			)
			( pin "C9P22.1"
				( objectStatus "@baseboard_fab2_lib.baseboard_fab2(sch_1):page207_i50:a" )
			)
			( pin "C9P22.2"
				( objectStatus "@baseboard_fab2_lib.baseboard_fab2(sch_1):page207_i50:b" )
			)
			( pin "C9P25.1"
				( objectStatus "@baseboard_fab2_lib.baseboard_fab2(sch_1):page207_i51:a" )
			)
			( pin "C9P25.2"
				( objectStatus "@baseboard_fab2_lib.baseboard_fab2(sch_1):page207_i51:b" )
			)
			( pin "C9P26.1"
				( objectStatus "@baseboard_fab2_lib.baseboard_fab2(sch_1):page207_i54:a" )
			)
			( pin "C9P26.2"
				( objectStatus "@baseboard_fab2_lib.baseboard_fab2(sch_1):page207_i54:b" )
			)
			( pin "C1E9.1"
				( objectStatus "@baseboard_fab2_lib.baseboard_fab2(sch_1):page207_i58:a" )
			)
			( pin "C1E9.2"
				( objectStatus "@baseboard_fab2_lib.baseboard_fab2(sch_1):page207_i58:b" )
			)
			( pin "C9P3.1"
				( objectStatus "@baseboard_fab2_lib.baseboard_fab2(sch_1):page207_i59:a" )
			)
			( pin "C9P3.2"
				( objectStatus "@baseboard_fab2_lib.baseboard_fab2(sch_1):page207_i59:b" )
			)
			( pin "R1E13.1"
				( objectStatus "@baseboard_fab2_lib.baseboard_fab2(sch_1):page207_i67:a" )
			)
			( pin "R1E13.2"
				( objectStatus "@baseboard_fab2_lib.baseboard_fab2(sch_1):page207_i67:b" )
			)
			( pin "R1E14.1"
				( objectStatus "@baseboard_fab2_lib.baseboard_fab2(sch_1):page207_i68:a" )
			)
			( pin "R1E14.2"
				( objectStatus "@baseboard_fab2_lib.baseboard_fab2(sch_1):page207_i68:b" )
			)
			( pin "R1E3.1"
				( objectStatus "@baseboard_fab2_lib.baseboard_fab2(sch_1):page208_i7:a" )
			)
			( pin "R1E3.2"
				( objectStatus "@baseboard_fab2_lib.baseboard_fab2(sch_1):page208_i7:b" )
			)
			( pin "C1D14.1"
				( objectStatus "@baseboard_fab2_lib.baseboard_fab2(sch_1):page208_i9:a" )
			)
			( pin "C1D14.2"
				( objectStatus "@baseboard_fab2_lib.baseboard_fab2(sch_1):page208_i9:b" )
			)
			( pin "L1D2.1"
				( objectStatus "@baseboard_fab2_lib.baseboard_fab2(sch_1):page208_i11:ina" )
			)
			( pin "L1D2.2"
				( objectStatus "@baseboard_fab2_lib.baseboard_fab2(sch_1):page208_i11:inb" )
			)
			( pin "C9P8.1"
				( objectStatus "@baseboard_fab2_lib.baseboard_fab2(sch_1):page208_i12:a" )
			)
			( pin "C9P8.2"
				( objectStatus "@baseboard_fab2_lib.baseboard_fab2(sch_1):page208_i12:b" )
			)
			( pin "C9P5.1"
				( objectStatus "@baseboard_fab2_lib.baseboard_fab2(sch_1):page208_i14:a" )
			)
			( pin "C9P5.2"
				( objectStatus "@baseboard_fab2_lib.baseboard_fab2(sch_1):page208_i14:b" )
			)
			( pin "L1D1.1"
				( objectStatus "@baseboard_fab2_lib.baseboard_fab2(sch_1):page208_i20:ina" )
			)
			( pin "L1D1.2"
				( objectStatus "@baseboard_fab2_lib.baseboard_fab2(sch_1):page208_i20:inb" )
			)
			( pin "C1D3.1"
				( objectStatus "@baseboard_fab2_lib.baseboard_fab2(sch_1):page208_i22:a" )
			)
			( pin "C1D3.2"
				( objectStatus "@baseboard_fab2_lib.baseboard_fab2(sch_1):page208_i22:b" )
			)
			( pin "C9N24.1"
				( objectStatus "@baseboard_fab2_lib.baseboard_fab2(sch_1):page208_i24:a" )
			)
			( pin "C9N24.2"
				( objectStatus "@baseboard_fab2_lib.baseboard_fab2(sch_1):page208_i24:b" )
			)
			( pin "C9R9.1"
				( objectStatus "@baseboard_fab2_lib.baseboard_fab2(sch_1):page208_i25:a" )
			)
			( pin "C9R9.2"
				( objectStatus "@baseboard_fab2_lib.baseboard_fab2(sch_1):page208_i25:b" )
			)
			( pin "C9R3.1"
				( objectStatus "@baseboard_fab2_lib.baseboard_fab2(sch_1):page208_i26:a" )
			)
			( pin "C9R3.2"
				( objectStatus "@baseboard_fab2_lib.baseboard_fab2(sch_1):page208_i26:b" )
			)
			( pin "EU1D3.33"
				( objectStatus "@baseboard_fab2_lib.baseboard_fab2(sch_1):page208_i27:boost" )
			)
			( pin "EU1D3.35"
				( objectStatus "@baseboard_fab2_lib.baseboard_fab2(sch_1):page208_i27:en" )
			)
			( pin "EU1D3.6"
				( objectStatus "@baseboard_fab2_lib.baseboard_fab2(sch_1):page208_i27:gl(0)" )
			)
			( pin "EU1D3.41"
				( objectStatus "@baseboard_fab2_lib.baseboard_fab2(sch_1):page208_i27:gl(1)" )
			)
			( pin "EU1D3.38"
				( objectStatus "@baseboard_fab2_lib.baseboard_fab2(sch_1):page208_i27:iout" )
			)
			( pin "EU1D3.2"
				( objectStatus "@baseboard_fab2_lib.baseboard_fab2(sch_1):page208_i27:lgnd" )
			)
			( pin "EU1D3.31"
				( objectStatus "@baseboard_fab2_lib.baseboard_fab2(sch_1):page208_i27:nc" )
			)
			( pin "EU1D3.37"
				( objectStatus "@baseboard_fab2_lib.baseboard_fab2(sch_1):page208_i27:ocset" )
			)
			( pin "EU1D3.5"
				( objectStatus "@baseboard_fab2_lib.baseboard_fab2(sch_1):page208_i27:pgnd(0)" )
			)
			( pin "EU1D3.7"
				( objectStatus "@baseboard_fab2_lib.baseboard_fab2(sch_1):page208_i27:pgnd(1)" )
			)
			( pin "EU1D3.40"
				( objectStatus "@baseboard_fab2_lib.baseboard_fab2(sch_1):page208_i27:pgnd(2)" )
			)
			( pin "EU1D3.32"
				( objectStatus "@baseboard_fab2_lib.baseboard_fab2(sch_1):page208_i27:phase" )
			)
			( pin "EU1D3.34"
				( objectStatus "@baseboard_fab2_lib.baseboard_fab2(sch_1):page208_i27:pwm" )
			)
			( pin "EU1D3.39"
				( objectStatus "@baseboard_fab2_lib.baseboard_fab2(sch_1):page208_i27:refin" )
			)
			( pin "EU1D3.10"
				( objectStatus "@baseboard_fab2_lib.baseboard_fab2(sch_1):page208_i27:sw" )
			)
			( pin "EU1D3.36"
				( objectStatus "@baseboard_fab2_lib.baseboard_fab2(sch_1):page208_i27:tout_flt" )
			)
			( pin "EU1D3.3"
				( objectStatus "@baseboard_fab2_lib.baseboard_fab2(sch_1):page208_i27:vcc" )
			)
			( pin "EU1D3.4"
				( objectStatus "@baseboard_fab2_lib.baseboard_fab2(sch_1):page208_i27:vdrv" )
			)
			( pin "EU1D3.25"
				( objectStatus "@baseboard_fab2_lib.baseboard_fab2(sch_1):page208_i27:vin(0)" )
			)
			( pin "EU1D3.30"
				( objectStatus "@baseboard_fab2_lib.baseboard_fab2(sch_1):page208_i27:vin(1)" )
			)
			( pin "EU1D3.1"
				( objectStatus "@baseboard_fab2_lib.baseboard_fab2(sch_1):page208_i27:vos" )
			)
			( pin "C9P23.1"
				( objectStatus "@baseboard_fab2_lib.baseboard_fab2(sch_1):page208_i28:a" )
			)
			( pin "C9P23.2"
				( objectStatus "@baseboard_fab2_lib.baseboard_fab2(sch_1):page208_i28:b" )
			)
			( pin "C9P18.1"
				( objectStatus "@baseboard_fab2_lib.baseboard_fab2(sch_1):page208_i30:a" )
			)
			( pin "C9P18.2"
				( objectStatus "@baseboard_fab2_lib.baseboard_fab2(sch_1):page208_i30:b" )
			)
			( pin "R9P22.1"
				( objectStatus "@baseboard_fab2_lib.baseboard_fab2(sch_1):page208_i36:a" )
			)
			( pin "R9P22.2"
				( objectStatus "@baseboard_fab2_lib.baseboard_fab2(sch_1):page208_i36:b" )
			)
			( pin "C1D16.1"
				( objectStatus "@baseboard_fab2_lib.baseboard_fab2(sch_1):page208_i38:a" )
			)
			( pin "C1D16.2"
				( objectStatus "@baseboard_fab2_lib.baseboard_fab2(sch_1):page208_i38:b" )
			)
			( pin "C1D15.1"
				( objectStatus "@baseboard_fab2_lib.baseboard_fab2(sch_1):page208_i39:a" )
			)
			( pin "C1D15.2"
				( objectStatus "@baseboard_fab2_lib.baseboard_fab2(sch_1):page208_i39:b" )
			)
			( pin "C1D20.1"
				( objectStatus "@baseboard_fab2_lib.baseboard_fab2(sch_1):page208_i40:a" )
			)
			( pin "C1D20.2"
				( objectStatus "@baseboard_fab2_lib.baseboard_fab2(sch_1):page208_i40:b" )
			)
			( pin "C1D17.1"
				( objectStatus "@baseboard_fab2_lib.baseboard_fab2(sch_1):page208_i43:a" )
			)
			( pin "C1D17.2"
				( objectStatus "@baseboard_fab2_lib.baseboard_fab2(sch_1):page208_i43:b" )
			)
			( pin "C1D28.1"
				( objectStatus "@baseboard_fab2_lib.baseboard_fab2(sch_1):page208_i44:a" )
			)
			( pin "C1D28.2"
				( objectStatus "@baseboard_fab2_lib.baseboard_fab2(sch_1):page208_i44:b" )
			)
			( pin "C1D23.1"
				( objectStatus "@baseboard_fab2_lib.baseboard_fab2(sch_1):page208_i45:a" )
			)
			( pin "C1D23.2"
				( objectStatus "@baseboard_fab2_lib.baseboard_fab2(sch_1):page208_i45:b" )
			)
			( pin "C1D6.1"
				( objectStatus "@baseboard_fab2_lib.baseboard_fab2(sch_1):page208_i46:a" )
			)
			( pin "C1D6.2"
				( objectStatus "@baseboard_fab2_lib.baseboard_fab2(sch_1):page208_i46:b" )
			)
			( pin "C1D5.1"
				( objectStatus "@baseboard_fab2_lib.baseboard_fab2(sch_1):page208_i47:a" )
			)
			( pin "C1D5.2"
				( objectStatus "@baseboard_fab2_lib.baseboard_fab2(sch_1):page208_i47:b" )
			)
			( pin "C1D10.1"
				( objectStatus "@baseboard_fab2_lib.baseboard_fab2(sch_1):page208_i48:a" )
			)
			( pin "C1D10.2"
				( objectStatus "@baseboard_fab2_lib.baseboard_fab2(sch_1):page208_i48:b" )
			)
			( pin "R9P8.1"
				( objectStatus "@baseboard_fab2_lib.baseboard_fab2(sch_1):page208_i49:a" )
			)
			( pin "R9P8.2"
				( objectStatus "@baseboard_fab2_lib.baseboard_fab2(sch_1):page208_i49:b" )
			)
			( pin "C1D7.1"
				( objectStatus "@baseboard_fab2_lib.baseboard_fab2(sch_1):page208_i50:a" )
			)
			( pin "C1D7.2"
				( objectStatus "@baseboard_fab2_lib.baseboard_fab2(sch_1):page208_i50:b" )
			)
			( pin "C1D13.1"
				( objectStatus "@baseboard_fab2_lib.baseboard_fab2(sch_1):page208_i51:a" )
			)
			( pin "C1D13.2"
				( objectStatus "@baseboard_fab2_lib.baseboard_fab2(sch_1):page208_i51:b" )
			)
			( pin "C1D12.1"
				( objectStatus "@baseboard_fab2_lib.baseboard_fab2(sch_1):page208_i52:a" )
			)
			( pin "C1D12.2"
				( objectStatus "@baseboard_fab2_lib.baseboard_fab2(sch_1):page208_i52:b" )
			)
			( pin "C9P4.1"
				( objectStatus "@baseboard_fab2_lib.baseboard_fab2(sch_1):page208_i53:a" )
			)
			( pin "C9P4.2"
				( objectStatus "@baseboard_fab2_lib.baseboard_fab2(sch_1):page208_i53:b" )
			)
			( pin "C9P7.1"
				( objectStatus "@baseboard_fab2_lib.baseboard_fab2(sch_1):page208_i54:a" )
			)
			( pin "C9P7.2"
				( objectStatus "@baseboard_fab2_lib.baseboard_fab2(sch_1):page208_i54:b" )
			)
			( pin "C9P9.1"
				( objectStatus "@baseboard_fab2_lib.baseboard_fab2(sch_1):page208_i55:a" )
			)
			( pin "C9P9.2"
				( objectStatus "@baseboard_fab2_lib.baseboard_fab2(sch_1):page208_i55:b" )
			)
			( pin "C9P24.1"
				( objectStatus "@baseboard_fab2_lib.baseboard_fab2(sch_1):page208_i58:a" )
			)
			( pin "C9P24.2"
				( objectStatus "@baseboard_fab2_lib.baseboard_fab2(sch_1):page208_i58:b" )
			)
			( pin "C9P1.1"
				( objectStatus "@baseboard_fab2_lib.baseboard_fab2(sch_1):page208_i59:a" )
			)
			( pin "C9P1.2"
				( objectStatus "@baseboard_fab2_lib.baseboard_fab2(sch_1):page208_i59:b" )
			)
			( pin "C9P2.1"
				( objectStatus "@baseboard_fab2_lib.baseboard_fab2(sch_1):page208_i60:a" )
			)
			( pin "C9P2.2"
				( objectStatus "@baseboard_fab2_lib.baseboard_fab2(sch_1):page208_i60:b" )
			)
			( pin "C9P10.1"
				( objectStatus "@baseboard_fab2_lib.baseboard_fab2(sch_1):page208_i66:a" )
			)
			( pin "C9P10.2"
				( objectStatus "@baseboard_fab2_lib.baseboard_fab2(sch_1):page208_i66:b" )
			)
			( pin "C9R2.1"
				( objectStatus "@baseboard_fab2_lib.baseboard_fab2(sch_1):page208_i67:a" )
			)
			( pin "C9R2.2"
				( objectStatus "@baseboard_fab2_lib.baseboard_fab2(sch_1):page208_i67:b" )
			)
			( pin "EU1D1.33"
				( objectStatus "@baseboard_fab2_lib.baseboard_fab2(sch_1):page208_i71:boost" )
			)
			( pin "EU1D1.35"
				( objectStatus "@baseboard_fab2_lib.baseboard_fab2(sch_1):page208_i71:en" )
			)
			( pin "EU1D1.6"
				( objectStatus "@baseboard_fab2_lib.baseboard_fab2(sch_1):page208_i71:gl(0)" )
			)
			( pin "EU1D1.41"
				( objectStatus "@baseboard_fab2_lib.baseboard_fab2(sch_1):page208_i71:gl(1)" )
			)
			( pin "EU1D1.38"
				( objectStatus "@baseboard_fab2_lib.baseboard_fab2(sch_1):page208_i71:iout" )
			)
			( pin "EU1D1.2"
				( objectStatus "@baseboard_fab2_lib.baseboard_fab2(sch_1):page208_i71:lgnd" )
			)
			( pin "EU1D1.31"
				( objectStatus "@baseboard_fab2_lib.baseboard_fab2(sch_1):page208_i71:nc" )
			)
			( pin "EU1D1.37"
				( objectStatus "@baseboard_fab2_lib.baseboard_fab2(sch_1):page208_i71:ocset" )
			)
			( pin "EU1D1.5"
				( objectStatus "@baseboard_fab2_lib.baseboard_fab2(sch_1):page208_i71:pgnd(0)" )
			)
			( pin "EU1D1.7"
				( objectStatus "@baseboard_fab2_lib.baseboard_fab2(sch_1):page208_i71:pgnd(1)" )
			)
			( pin "EU1D1.40"
				( objectStatus "@baseboard_fab2_lib.baseboard_fab2(sch_1):page208_i71:pgnd(2)" )
			)
			( pin "EU1D1.32"
				( objectStatus "@baseboard_fab2_lib.baseboard_fab2(sch_1):page208_i71:phase" )
			)
			( pin "EU1D1.34"
				( objectStatus "@baseboard_fab2_lib.baseboard_fab2(sch_1):page208_i71:pwm" )
			)
			( pin "EU1D1.39"
				( objectStatus "@baseboard_fab2_lib.baseboard_fab2(sch_1):page208_i71:refin" )
			)
			( pin "EU1D1.10"
				( objectStatus "@baseboard_fab2_lib.baseboard_fab2(sch_1):page208_i71:sw" )
			)
			( pin "EU1D1.36"
				( objectStatus "@baseboard_fab2_lib.baseboard_fab2(sch_1):page208_i71:tout_flt" )
			)
			( pin "EU1D1.3"
				( objectStatus "@baseboard_fab2_lib.baseboard_fab2(sch_1):page208_i71:vcc" )
			)
			( pin "EU1D1.4"
				( objectStatus "@baseboard_fab2_lib.baseboard_fab2(sch_1):page208_i71:vdrv" )
			)
			( pin "EU1D1.25"
				( objectStatus "@baseboard_fab2_lib.baseboard_fab2(sch_1):page208_i71:vin(0)" )
			)
			( pin "EU1D1.30"
				( objectStatus "@baseboard_fab2_lib.baseboard_fab2(sch_1):page208_i71:vin(1)" )
			)
			( pin "EU1D1.1"
				( objectStatus "@baseboard_fab2_lib.baseboard_fab2(sch_1):page208_i71:vos" )
			)
			( pin "R1D54.1"
				( objectStatus "@baseboard_fab2_lib.baseboard_fab2(sch_1):page208_i75:a" )
			)
			( pin "R1D54.2"
				( objectStatus "@baseboard_fab2_lib.baseboard_fab2(sch_1):page208_i75:b" )
			)
			( pin "R1D55.1"
				( objectStatus "@baseboard_fab2_lib.baseboard_fab2(sch_1):page208_i76:a" )
			)
			( pin "R1D55.2"
				( objectStatus "@baseboard_fab2_lib.baseboard_fab2(sch_1):page208_i76:b" )
			)
			( pin "R1E5.1"
				( objectStatus "@baseboard_fab2_lib.baseboard_fab2(sch_1):page209_i3:a" )
			)
			( pin "R1E5.2"
				( objectStatus "@baseboard_fab2_lib.baseboard_fab2(sch_1):page209_i3:b" )
			)
			( pin "C9N27.1"
				( objectStatus "@baseboard_fab2_lib.baseboard_fab2(sch_1):page209_i5:a" )
			)
			( pin "C9N27.2"
				( objectStatus "@baseboard_fab2_lib.baseboard_fab2(sch_1):page209_i5:b" )
			)
			( pin "C9N26.1"
				( objectStatus "@baseboard_fab2_lib.baseboard_fab2(sch_1):page209_i7:a" )
			)
			( pin "C9N26.2"
				( objectStatus "@baseboard_fab2_lib.baseboard_fab2(sch_1):page209_i7:b" )
			)
			( pin "C9N25.1"
				( objectStatus "@baseboard_fab2_lib.baseboard_fab2(sch_1):page209_i8:a" )
			)
			( pin "C9N25.2"
				( objectStatus "@baseboard_fab2_lib.baseboard_fab2(sch_1):page209_i8:b" )
			)
			( pin "R1E8.1"
				( objectStatus "@baseboard_fab2_lib.baseboard_fab2(sch_1):page209_i9:a" )
			)
			( pin "R1E8.2"
				( objectStatus "@baseboard_fab2_lib.baseboard_fab2(sch_1):page209_i9:b" )
			)
			( pin "R1E7.1"
				( objectStatus "@baseboard_fab2_lib.baseboard_fab2(sch_1):page209_i10:a" )
			)
			( pin "R1E7.2"
				( objectStatus "@baseboard_fab2_lib.baseboard_fab2(sch_1):page209_i10:b" )
			)
			( pin "R1E6.1"
				( objectStatus "@baseboard_fab2_lib.baseboard_fab2(sch_1):page209_i11:a" )
			)
			( pin "R1E6.2"
				( objectStatus "@baseboard_fab2_lib.baseboard_fab2(sch_1):page209_i11:b" )
			)
			( pin "R1E4.1"
				( objectStatus "@baseboard_fab2_lib.baseboard_fab2(sch_1):page209_i15:a" )
			)
			( pin "R1E4.2"
				( objectStatus "@baseboard_fab2_lib.baseboard_fab2(sch_1):page209_i15:b" )
			)
			( pin "C1C26.1"
				( objectStatus "@baseboard_fab2_lib.baseboard_fab2(sch_1):page209_i16:a" )
			)
			( pin "C1C26.2"
				( objectStatus "@baseboard_fab2_lib.baseboard_fab2(sch_1):page209_i16:b" )
			)
			( pin "C1C25.1"
				( objectStatus "@baseboard_fab2_lib.baseboard_fab2(sch_1):page209_i17:a" )
			)
			( pin "C1C25.2"
				( objectStatus "@baseboard_fab2_lib.baseboard_fab2(sch_1):page209_i17:b" )
			)
			( pin "C1D32.1"
				( objectStatus "@baseboard_fab2_lib.baseboard_fab2(sch_1):page209_i18:a" )
			)
			( pin "C1D32.2"
				( objectStatus "@baseboard_fab2_lib.baseboard_fab2(sch_1):page209_i18:b" )
			)
			( pin "C1C24.1"
				( objectStatus "@baseboard_fab2_lib.baseboard_fab2(sch_1):page209_i20:a" )
			)
			( pin "C1C24.2"
				( objectStatus "@baseboard_fab2_lib.baseboard_fab2(sch_1):page209_i20:b" )
			)
			( pin "C1C18.1"
				( objectStatus "@baseboard_fab2_lib.baseboard_fab2(sch_1):page209_i21:a" )
			)
			( pin "C1C18.2"
				( objectStatus "@baseboard_fab2_lib.baseboard_fab2(sch_1):page209_i21:b" )
			)
			( pin "C1D33.1"
				( objectStatus "@baseboard_fab2_lib.baseboard_fab2(sch_1):page209_i22:a" )
			)
			( pin "C1D33.2"
				( objectStatus "@baseboard_fab2_lib.baseboard_fab2(sch_1):page209_i22:b" )
			)
			( pin "R9P32.1"
				( objectStatus "@baseboard_fab2_lib.baseboard_fab2(sch_1):page209_i24:a" )
			)
			( pin "R9P32.2"
				( objectStatus "@baseboard_fab2_lib.baseboard_fab2(sch_1):page209_i24:b" )
			)
			( pin "C1B16.1"
				( objectStatus "@baseboard_fab2_lib.baseboard_fab2(sch_1):page209_i30:a" )
			)
			( pin "C1B16.2"
				( objectStatus "@baseboard_fab2_lib.baseboard_fab2(sch_1):page209_i30:b" )
			)
			( pin "L1B2.1"
				( objectStatus "@baseboard_fab2_lib.baseboard_fab2(sch_1):page209_i32:ina" )
			)
			( pin "L1B2.2"
				( objectStatus "@baseboard_fab2_lib.baseboard_fab2(sch_1):page209_i32:inb" )
			)
			( pin "C1C1.1"
				( objectStatus "@baseboard_fab2_lib.baseboard_fab2(sch_1):page209_i35:a" )
			)
			( pin "C1C1.2"
				( objectStatus "@baseboard_fab2_lib.baseboard_fab2(sch_1):page209_i35:b" )
			)
			( pin "C1E18.1"
				( objectStatus "@baseboard_fab2_lib.baseboard_fab2(sch_1):page209_i37:a" )
			)
			( pin "C1E18.2"
				( objectStatus "@baseboard_fab2_lib.baseboard_fab2(sch_1):page209_i37:b" )
			)
			( pin "C1C2.1"
				( objectStatus "@baseboard_fab2_lib.baseboard_fab2(sch_1):page209_i38:a" )
			)
			( pin "C1C2.2"
				( objectStatus "@baseboard_fab2_lib.baseboard_fab2(sch_1):page209_i38:b" )
			)
			( pin "R1B20.1"
				( objectStatus "@baseboard_fab2_lib.baseboard_fab2(sch_1):page209_i39:a" )
			)
			( pin "R1B20.2"
				( objectStatus "@baseboard_fab2_lib.baseboard_fab2(sch_1):page209_i39:b" )
			)
			( pin "L1C2.1"
				( objectStatus "@baseboard_fab2_lib.baseboard_fab2(sch_1):page209_i40:ina" )
			)
			( pin "L1C2.2"
				( objectStatus "@baseboard_fab2_lib.baseboard_fab2(sch_1):page209_i40:inb" )
			)
			( pin "C1D24.1"
				( objectStatus "@baseboard_fab2_lib.baseboard_fab2(sch_1):page209_i42:a" )
			)
			( pin "C1D24.2"
				( objectStatus "@baseboard_fab2_lib.baseboard_fab2(sch_1):page209_i42:b" )
			)
			( pin "U1B3.1"
				( objectStatus "@baseboard_fab2_lib.baseboard_fab2(sch_1):page209_i52:gnd(0)" )
			)
			( pin "U1B3.2"
				( objectStatus "@baseboard_fab2_lib.baseboard_fab2(sch_1):page209_i52:gnd(1)" )
			)
			( pin "U1B3.6"
				( objectStatus "@baseboard_fab2_lib.baseboard_fab2(sch_1):page209_i52:\out\" )
			)
			( pin "U1B3.5"
				( objectStatus "@baseboard_fab2_lib.baseboard_fab2(sch_1):page209_i52:rsn" )
			)
			( pin "U1B3.4"
				( objectStatus "@baseboard_fab2_lib.baseboard_fab2(sch_1):page209_i52:rsp" )
			)
			( pin "U1B3.3"
				( objectStatus "@baseboard_fab2_lib.baseboard_fab2(sch_1):page209_i52:vcc" )
			)
			( pin "C9P20.1"
				( objectStatus "@baseboard_fab2_lib.baseboard_fab2(sch_1):page209_i55:a" )
			)
			( pin "C9P20.2"
				( objectStatus "@baseboard_fab2_lib.baseboard_fab2(sch_1):page209_i55:b" )
			)
			( pin "EU1C3.33"
				( objectStatus "@baseboard_fab2_lib.baseboard_fab2(sch_1):page209_i56:boost" )
			)
			( pin "EU1C3.35"
				( objectStatus "@baseboard_fab2_lib.baseboard_fab2(sch_1):page209_i56:en" )
			)
			( pin "EU1C3.6"
				( objectStatus "@baseboard_fab2_lib.baseboard_fab2(sch_1):page209_i56:gl(0)" )
			)
			( pin "EU1C3.41"
				( objectStatus "@baseboard_fab2_lib.baseboard_fab2(sch_1):page209_i56:gl(1)" )
			)
			( pin "EU1C3.38"
				( objectStatus "@baseboard_fab2_lib.baseboard_fab2(sch_1):page209_i56:iout" )
			)
			( pin "EU1C3.2"
				( objectStatus "@baseboard_fab2_lib.baseboard_fab2(sch_1):page209_i56:lgnd" )
			)
			( pin "EU1C3.31"
				( objectStatus "@baseboard_fab2_lib.baseboard_fab2(sch_1):page209_i56:nc" )
			)
			( pin "EU1C3.37"
				( objectStatus "@baseboard_fab2_lib.baseboard_fab2(sch_1):page209_i56:ocset" )
			)
			( pin "EU1C3.5"
				( objectStatus "@baseboard_fab2_lib.baseboard_fab2(sch_1):page209_i56:pgnd(0)" )
			)
			( pin "EU1C3.7"
				( objectStatus "@baseboard_fab2_lib.baseboard_fab2(sch_1):page209_i56:pgnd(1)" )
			)
			( pin "EU1C3.40"
				( objectStatus "@baseboard_fab2_lib.baseboard_fab2(sch_1):page209_i56:pgnd(2)" )
			)
			( pin "EU1C3.32"
				( objectStatus "@baseboard_fab2_lib.baseboard_fab2(sch_1):page209_i56:phase" )
			)
			( pin "EU1C3.34"
				( objectStatus "@baseboard_fab2_lib.baseboard_fab2(sch_1):page209_i56:pwm" )
			)
			( pin "EU1C3.39"
				( objectStatus "@baseboard_fab2_lib.baseboard_fab2(sch_1):page209_i56:refin" )
			)
			( pin "EU1C3.10"
				( objectStatus "@baseboard_fab2_lib.baseboard_fab2(sch_1):page209_i56:sw" )
			)
			( pin "EU1C3.36"
				( objectStatus "@baseboard_fab2_lib.baseboard_fab2(sch_1):page209_i56:tout_flt" )
			)
			( pin "EU1C3.3"
				( objectStatus "@baseboard_fab2_lib.baseboard_fab2(sch_1):page209_i56:vcc" )
			)
			( pin "EU1C3.4"
				( objectStatus "@baseboard_fab2_lib.baseboard_fab2(sch_1):page209_i56:vdrv" )
			)
			( pin "EU1C3.25"
				( objectStatus "@baseboard_fab2_lib.baseboard_fab2(sch_1):page209_i56:vin(0)" )
			)
			( pin "EU1C3.30"
				( objectStatus "@baseboard_fab2_lib.baseboard_fab2(sch_1):page209_i56:vin(1)" )
			)
			( pin "EU1C3.1"
				( objectStatus "@baseboard_fab2_lib.baseboard_fab2(sch_1):page209_i56:vos" )
			)
			( pin "R1D52.1"
				( objectStatus "@baseboard_fab2_lib.baseboard_fab2(sch_1):page209_i59:a" )
			)
			( pin "R1D52.2"
				( objectStatus "@baseboard_fab2_lib.baseboard_fab2(sch_1):page209_i59:b" )
			)
			( pin "C1C19.1"
				( objectStatus "@baseboard_fab2_lib.baseboard_fab2(sch_1):page210_i8:a" )
			)
			( pin "C1C19.2"
				( objectStatus "@baseboard_fab2_lib.baseboard_fab2(sch_1):page210_i8:b" )
			)
			( pin "L1C1.1"
				( objectStatus "@baseboard_fab2_lib.baseboard_fab2(sch_1):page210_i10:ina" )
			)
			( pin "L1C1.2"
				( objectStatus "@baseboard_fab2_lib.baseboard_fab2(sch_1):page210_i10:inb" )
			)
			( pin "C9N11.1"
				( objectStatus "@baseboard_fab2_lib.baseboard_fab2(sch_1):page210_i12:a" )
			)
			( pin "C9N11.2"
				( objectStatus "@baseboard_fab2_lib.baseboard_fab2(sch_1):page210_i12:b" )
			)
			( pin "C9N20.1"
				( objectStatus "@baseboard_fab2_lib.baseboard_fab2(sch_1):page210_i14:a" )
			)
			( pin "C9N20.2"
				( objectStatus "@baseboard_fab2_lib.baseboard_fab2(sch_1):page210_i14:b" )
			)
			( pin "R9N3.1"
				( objectStatus "@baseboard_fab2_lib.baseboard_fab2(sch_1):page210_i20:a" )
			)
			( pin "R9N3.2"
				( objectStatus "@baseboard_fab2_lib.baseboard_fab2(sch_1):page210_i20:b" )
			)
			( pin "C1C4.1"
				( objectStatus "@baseboard_fab2_lib.baseboard_fab2(sch_1):page210_i22:a" )
			)
			( pin "C1C4.2"
				( objectStatus "@baseboard_fab2_lib.baseboard_fab2(sch_1):page210_i22:b" )
			)
			( pin "C1C3.1"
				( objectStatus "@baseboard_fab2_lib.baseboard_fab2(sch_1):page210_i23:a" )
			)
			( pin "C1C3.2"
				( objectStatus "@baseboard_fab2_lib.baseboard_fab2(sch_1):page210_i23:b" )
			)
			( pin "C1C12.1"
				( objectStatus "@baseboard_fab2_lib.baseboard_fab2(sch_1):page210_i24:a" )
			)
			( pin "C1C12.2"
				( objectStatus "@baseboard_fab2_lib.baseboard_fab2(sch_1):page210_i24:b" )
			)
			( pin "C1C5.1"
				( objectStatus "@baseboard_fab2_lib.baseboard_fab2(sch_1):page210_i26:a" )
			)
			( pin "C1C5.2"
				( objectStatus "@baseboard_fab2_lib.baseboard_fab2(sch_1):page210_i26:b" )
			)
			( pin "C1C17.1"
				( objectStatus "@baseboard_fab2_lib.baseboard_fab2(sch_1):page210_i27:a" )
			)
			( pin "C1C17.2"
				( objectStatus "@baseboard_fab2_lib.baseboard_fab2(sch_1):page210_i27:b" )
			)
			( pin "C1C15.1"
				( objectStatus "@baseboard_fab2_lib.baseboard_fab2(sch_1):page210_i28:a" )
			)
			( pin "C1C15.2"
				( objectStatus "@baseboard_fab2_lib.baseboard_fab2(sch_1):page210_i28:b" )
			)
			( pin "R1C12.1"
				( objectStatus "@baseboard_fab2_lib.baseboard_fab2(sch_1):page210_i29:a" )
			)
			( pin "R1C12.2"
				( objectStatus "@baseboard_fab2_lib.baseboard_fab2(sch_1):page210_i29:b" )
			)
			( pin "R1C7.1"
				( objectStatus "@baseboard_fab2_lib.baseboard_fab2(sch_1):page210_i31:a" )
			)
			( pin "R1C7.2"
				( objectStatus "@baseboard_fab2_lib.baseboard_fab2(sch_1):page210_i31:b" )
			)
			( pin "R1C5.1"
				( objectStatus "@baseboard_fab2_lib.baseboard_fab2(sch_1):page210_i32:a" )
			)
			( pin "R1C5.2"
				( objectStatus "@baseboard_fab2_lib.baseboard_fab2(sch_1):page210_i32:b" )
			)
			( pin "R1C4.1"
				( objectStatus "@baseboard_fab2_lib.baseboard_fab2(sch_1):page210_i33:a" )
			)
			( pin "R1C4.2"
				( objectStatus "@baseboard_fab2_lib.baseboard_fab2(sch_1):page210_i33:b" )
			)
			( pin "R1C6.1"
				( objectStatus "@baseboard_fab2_lib.baseboard_fab2(sch_1):page210_i34:a" )
			)
			( pin "R1C6.2"
				( objectStatus "@baseboard_fab2_lib.baseboard_fab2(sch_1):page210_i34:b" )
			)
			( pin "C9N13.1"
				( objectStatus "@baseboard_fab2_lib.baseboard_fab2(sch_1):page210_i35:a" )
			)
			( pin "C9N13.2"
				( objectStatus "@baseboard_fab2_lib.baseboard_fab2(sch_1):page210_i35:b" )
			)
			( pin "C9N19.1"
				( objectStatus "@baseboard_fab2_lib.baseboard_fab2(sch_1):page210_i36:a" )
			)
			( pin "C9N19.2"
				( objectStatus "@baseboard_fab2_lib.baseboard_fab2(sch_1):page210_i36:b" )
			)
			( pin "C9N21.1"
				( objectStatus "@baseboard_fab2_lib.baseboard_fab2(sch_1):page210_i38:a" )
			)
			( pin "C9N21.2"
				( objectStatus "@baseboard_fab2_lib.baseboard_fab2(sch_1):page210_i38:b" )
			)
			( pin "C9N22.1"
				( objectStatus "@baseboard_fab2_lib.baseboard_fab2(sch_1):page210_i44:a" )
			)
			( pin "C9N22.2"
				( objectStatus "@baseboard_fab2_lib.baseboard_fab2(sch_1):page210_i44:b" )
			)
			( pin "R9N4.1"
				( objectStatus "@baseboard_fab2_lib.baseboard_fab2(sch_1):page210_i45:a" )
			)
			( pin "R9N4.2"
				( objectStatus "@baseboard_fab2_lib.baseboard_fab2(sch_1):page210_i45:b" )
			)
			( pin "EU1C1.33"
				( objectStatus "@baseboard_fab2_lib.baseboard_fab2(sch_1):page210_i51:boost" )
			)
			( pin "EU1C1.35"
				( objectStatus "@baseboard_fab2_lib.baseboard_fab2(sch_1):page210_i51:en" )
			)
			( pin "EU1C1.6"
				( objectStatus "@baseboard_fab2_lib.baseboard_fab2(sch_1):page210_i51:gl(0)" )
			)
			( pin "EU1C1.41"
				( objectStatus "@baseboard_fab2_lib.baseboard_fab2(sch_1):page210_i51:gl(1)" )
			)
			( pin "EU1C1.38"
				( objectStatus "@baseboard_fab2_lib.baseboard_fab2(sch_1):page210_i51:iout" )
			)
			( pin "EU1C1.2"
				( objectStatus "@baseboard_fab2_lib.baseboard_fab2(sch_1):page210_i51:lgnd" )
			)
			( pin "EU1C1.31"
				( objectStatus "@baseboard_fab2_lib.baseboard_fab2(sch_1):page210_i51:nc" )
			)
			( pin "EU1C1.37"
				( objectStatus "@baseboard_fab2_lib.baseboard_fab2(sch_1):page210_i51:ocset" )
			)
			( pin "EU1C1.5"
				( objectStatus "@baseboard_fab2_lib.baseboard_fab2(sch_1):page210_i51:pgnd(0)" )
			)
			( pin "EU1C1.7"
				( objectStatus "@baseboard_fab2_lib.baseboard_fab2(sch_1):page210_i51:pgnd(1)" )
			)
			( pin "EU1C1.40"
				( objectStatus "@baseboard_fab2_lib.baseboard_fab2(sch_1):page210_i51:pgnd(2)" )
			)
			( pin "EU1C1.32"
				( objectStatus "@baseboard_fab2_lib.baseboard_fab2(sch_1):page210_i51:phase" )
			)
			( pin "EU1C1.34"
				( objectStatus "@baseboard_fab2_lib.baseboard_fab2(sch_1):page210_i51:pwm" )
			)
			( pin "EU1C1.39"
				( objectStatus "@baseboard_fab2_lib.baseboard_fab2(sch_1):page210_i51:refin" )
			)
			( pin "EU1C1.10"
				( objectStatus "@baseboard_fab2_lib.baseboard_fab2(sch_1):page210_i51:sw" )
			)
			( pin "EU1C1.36"
				( objectStatus "@baseboard_fab2_lib.baseboard_fab2(sch_1):page210_i51:tout_flt" )
			)
			( pin "EU1C1.3"
				( objectStatus "@baseboard_fab2_lib.baseboard_fab2(sch_1):page210_i51:vcc" )
			)
			( pin "EU1C1.4"
				( objectStatus "@baseboard_fab2_lib.baseboard_fab2(sch_1):page210_i51:vdrv" )
			)
			( pin "EU1C1.25"
				( objectStatus "@baseboard_fab2_lib.baseboard_fab2(sch_1):page210_i51:vin(0)" )
			)
			( pin "EU1C1.30"
				( objectStatus "@baseboard_fab2_lib.baseboard_fab2(sch_1):page210_i51:vin(1)" )
			)
			( pin "EU1C1.1"
				( objectStatus "@baseboard_fab2_lib.baseboard_fab2(sch_1):page210_i51:vos" )
			)
			( pin "R1C37.1"
				( objectStatus "@baseboard_fab2_lib.baseboard_fab2(sch_1):page210_i52:a" )
			)
			( pin "R1C37.2"
				( objectStatus "@baseboard_fab2_lib.baseboard_fab2(sch_1):page210_i52:b" )
			)
			( pin "C3P4.1"
				( objectStatus "@baseboard_fab2_lib.baseboard_fab2(sch_1):page211_i11:a" )
			)
			( pin "C3P4.2"
				( objectStatus "@baseboard_fab2_lib.baseboard_fab2(sch_1):page211_i11:b" )
			)
			( pin "C3P5.1"
				( objectStatus "@baseboard_fab2_lib.baseboard_fab2(sch_1):page211_i13:a" )
			)
			( pin "C3P5.2"
				( objectStatus "@baseboard_fab2_lib.baseboard_fab2(sch_1):page211_i13:b" )
			)
			( pin "R3P11.1"
				( objectStatus "@baseboard_fab2_lib.baseboard_fab2(sch_1):page211_i16:a" )
			)
			( pin "R3P11.2"
				( objectStatus "@baseboard_fab2_lib.baseboard_fab2(sch_1):page211_i16:b" )
			)
			( pin "R3P13.1"
				( objectStatus "@baseboard_fab2_lib.baseboard_fab2(sch_1):page211_i17:a" )
			)
			( pin "R3P13.2"
				( objectStatus "@baseboard_fab2_lib.baseboard_fab2(sch_1):page211_i17:b" )
			)
			( pin "C3P3.1"
				( objectStatus "@baseboard_fab2_lib.baseboard_fab2(sch_1):page211_i20:a" )
			)
			( pin "C3P3.2"
				( objectStatus "@baseboard_fab2_lib.baseboard_fab2(sch_1):page211_i20:b" )
			)
			( pin "C3P7.1"
				( objectStatus "@baseboard_fab2_lib.baseboard_fab2(sch_1):page211_i22:a" )
			)
			( pin "C3P7.2"
				( objectStatus "@baseboard_fab2_lib.baseboard_fab2(sch_1):page211_i22:b" )
			)
			( pin "R3P22.1"
				( objectStatus "@baseboard_fab2_lib.baseboard_fab2(sch_1):page211_i24:a" )
			)
			( pin "R3P22.2"
				( objectStatus "@baseboard_fab2_lib.baseboard_fab2(sch_1):page211_i24:b" )
			)
			( pin "R3P17.1"
				( objectStatus "@baseboard_fab2_lib.baseboard_fab2(sch_1):page211_i28:a" )
			)
			( pin "R3P17.2"
				( objectStatus "@baseboard_fab2_lib.baseboard_fab2(sch_1):page211_i28:b" )
			)
			( pin "R3P15.1"
				( objectStatus "@baseboard_fab2_lib.baseboard_fab2(sch_1):page211_i29:a" )
			)
			( pin "R3P15.2"
				( objectStatus "@baseboard_fab2_lib.baseboard_fab2(sch_1):page211_i29:b" )
			)
			( pin "R3P12.1"
				( objectStatus "@baseboard_fab2_lib.baseboard_fab2(sch_1):page211_i31:a" )
			)
			( pin "R3P12.2"
				( objectStatus "@baseboard_fab2_lib.baseboard_fab2(sch_1):page211_i31:b" )
			)
			( pin "R3P16.1"
				( objectStatus "@baseboard_fab2_lib.baseboard_fab2(sch_1):page211_i32:a" )
			)
			( pin "R3P16.2"
				( objectStatus "@baseboard_fab2_lib.baseboard_fab2(sch_1):page211_i32:b" )
			)
			( pin "C3P2.1"
				( objectStatus "@baseboard_fab2_lib.baseboard_fab2(sch_1):page211_i33:a" )
			)
			( pin "C3P2.2"
				( objectStatus "@baseboard_fab2_lib.baseboard_fab2(sch_1):page211_i33:b" )
			)
			( pin "R3P24.1"
				( objectStatus "@baseboard_fab2_lib.baseboard_fab2(sch_1):page211_i46:a" )
			)
			( pin "R3P24.2"
				( objectStatus "@baseboard_fab2_lib.baseboard_fab2(sch_1):page211_i46:b" )
			)
			( pin "R3P23.1"
				( objectStatus "@baseboard_fab2_lib.baseboard_fab2(sch_1):page211_i47:a" )
			)
			( pin "R3P23.2"
				( objectStatus "@baseboard_fab2_lib.baseboard_fab2(sch_1):page211_i47:b" )
			)
			( pin "R3N31.1"
				( objectStatus "@baseboard_fab2_lib.baseboard_fab2(sch_1):page211_i52:a" )
			)
			( pin "R3N31.2"
				( objectStatus "@baseboard_fab2_lib.baseboard_fab2(sch_1):page211_i52:b" )
			)
			( pin "R3P25.1"
				( objectStatus "@baseboard_fab2_lib.baseboard_fab2(sch_1):page211_i56:a" )
			)
			( pin "R3P25.2"
				( objectStatus "@baseboard_fab2_lib.baseboard_fab2(sch_1):page211_i56:b" )
			)
			( pin "R3P20.1"
				( objectStatus "@baseboard_fab2_lib.baseboard_fab2(sch_1):page211_i58:a" )
			)
			( pin "R3P20.2"
				( objectStatus "@baseboard_fab2_lib.baseboard_fab2(sch_1):page211_i58:b" )
			)
			( pin "R3N23.1"
				( objectStatus "@baseboard_fab2_lib.baseboard_fab2(sch_1):page211_i60:a" )
			)
			( pin "R3N23.2"
				( objectStatus "@baseboard_fab2_lib.baseboard_fab2(sch_1):page211_i60:b" )
			)
			( pin "R3P1.1"
				( objectStatus "@baseboard_fab2_lib.baseboard_fab2(sch_1):page211_i61:a" )
			)
			( pin "R3P1.2"
				( objectStatus "@baseboard_fab2_lib.baseboard_fab2(sch_1):page211_i61:b" )
			)
			( pin "R3P18.1"
				( objectStatus "@baseboard_fab2_lib.baseboard_fab2(sch_1):page211_i64:a" )
			)
			( pin "R3P18.2"
				( objectStatus "@baseboard_fab2_lib.baseboard_fab2(sch_1):page211_i64:b" )
			)
			( pin "R3N22.1"
				( objectStatus "@baseboard_fab2_lib.baseboard_fab2(sch_1):page211_i65:a" )
			)
			( pin "R3N22.2"
				( objectStatus "@baseboard_fab2_lib.baseboard_fab2(sch_1):page211_i65:b" )
			)
			( pin "C3P6.1"
				( objectStatus "@baseboard_fab2_lib.baseboard_fab2(sch_1):page211_i71:a" )
			)
			( pin "C3P6.2"
				( objectStatus "@baseboard_fab2_lib.baseboard_fab2(sch_1):page211_i71:b" )
			)
			( pin "R3N19.1"
				( objectStatus "@baseboard_fab2_lib.baseboard_fab2(sch_1):page211_i81:a" )
			)
			( pin "R3N19.2"
				( objectStatus "@baseboard_fab2_lib.baseboard_fab2(sch_1):page211_i81:b" )
			)
			( pin "C3N39.1"
				( objectStatus "@baseboard_fab2_lib.baseboard_fab2(sch_1):page211_i83:a" )
			)
			( pin "C3N39.2"
				( objectStatus "@baseboard_fab2_lib.baseboard_fab2(sch_1):page211_i83:b" )
			)
			( pin "R3P26.1"
				( objectStatus "@baseboard_fab2_lib.baseboard_fab2(sch_1):page211_i87:a" )
			)
			( pin "R3P26.2"
				( objectStatus "@baseboard_fab2_lib.baseboard_fab2(sch_1):page211_i87:b" )
			)
			( pin "R3P21.1"
				( objectStatus "@baseboard_fab2_lib.baseboard_fab2(sch_1):page211_i88:a" )
			)
			( pin "R3P21.2"
				( objectStatus "@baseboard_fab2_lib.baseboard_fab2(sch_1):page211_i88:b" )
			)
			( pin "R3P57.1"
				( objectStatus "@baseboard_fab2_lib.baseboard_fab2(sch_1):page211_i91:a" )
			)
			( pin "R3P57.2"
				( objectStatus "@baseboard_fab2_lib.baseboard_fab2(sch_1):page211_i91:b" )
			)
			( pin "EU3P1.21"
				( objectStatus "@baseboard_fab2_lib.baseboard_fab2(sch_1):page211_i93:airef1" )
			)
			( pin "EU3P1.22"
				( objectStatus "@baseboard_fab2_lib.baseboard_fab2(sch_1):page211_i93:aisen1" )
			)
			( pin "EU3P1.5"
				( objectStatus "@baseboard_fab2_lib.baseboard_fab2(sch_1):page211_i93:apwm1" )
			)
			( pin "EU3P1.35"
				( objectStatus "@baseboard_fab2_lib.baseboard_fab2(sch_1):page211_i93:atsen" )
			)
			( pin "EU3P1.20"
				( objectStatus "@baseboard_fab2_lib.baseboard_fab2(sch_1):page211_i93:avref" )
			)
			( pin "EU3P1.10"
				( objectStatus "@baseboard_fab2_lib.baseboard_fab2(sch_1):page211_i93:avren" )
			)
			( pin "EU3P1.9"
				( objectStatus "@baseboard_fab2_lib.baseboard_fab2(sch_1):page211_i93:avrrdy" )
			)
			( pin "EU3P1.19"
				( objectStatus "@baseboard_fab2_lib.baseboard_fab2(sch_1):page211_i93:avsen" )
			)
			( pin "EU3P1.25"
				( objectStatus "@baseboard_fab2_lib.baseboard_fab2(sch_1):page211_i93:biref1" )
			)
			( pin "EU3P1.26"
				( objectStatus "@baseboard_fab2_lib.baseboard_fab2(sch_1):page211_i93:bisen1" )
			)
			( pin "EU3P1.3"
				( objectStatus "@baseboard_fab2_lib.baseboard_fab2(sch_1):page211_i93:bpwm1" )
			)
			( pin "EU3P1.34"
				( objectStatus "@baseboard_fab2_lib.baseboard_fab2(sch_1):page211_i93:btsen" )
			)
			( pin "EU3P1.30"
				( objectStatus "@baseboard_fab2_lib.baseboard_fab2(sch_1):page211_i93:bvref" )
			)
			( pin "EU3P1.29"
				( objectStatus "@baseboard_fab2_lib.baseboard_fab2(sch_1):page211_i93:bvsen" )
			)
			( pin "EU3P1.1"
				( objectStatus "@baseboard_fab2_lib.baseboard_fab2(sch_1):page211_i93:dnc(0)" )
			)
			( pin "EU3P1.2"
				( objectStatus "@baseboard_fab2_lib.baseboard_fab2(sch_1):page211_i93:dnc(1)" )
			)
			( pin "EU3P1.4"
				( objectStatus "@baseboard_fab2_lib.baseboard_fab2(sch_1):page211_i93:dnc(2)" )
			)
			( pin "EU3P1.24"
				( objectStatus "@baseboard_fab2_lib.baseboard_fab2(sch_1):page211_i93:dnc(3)" )
			)
			( pin "EU3P1.28"
				( objectStatus "@baseboard_fab2_lib.baseboard_fab2(sch_1):page211_i93:dnc(4)" )
			)
			( pin "EU3P1.27"
				( objectStatus "@baseboard_fab2_lib.baseboard_fab2(sch_1):page211_i93:gnd(0)" )
			)
			( pin "EU3P1.23"
				( objectStatus "@baseboard_fab2_lib.baseboard_fab2(sch_1):page211_i93:gnd(1)" )
			)
			( pin "EU3P1.38"
				( objectStatus "@baseboard_fab2_lib.baseboard_fab2(sch_1):page211_i93:iinsen" )
			)
			( pin "EU3P1.13"
				( objectStatus "@baseboard_fab2_lib.baseboard_fab2(sch_1):page211_i93:mp0" )
			)
			( pin "EU3P1.14"
				( objectStatus "@baseboard_fab2_lib.baseboard_fab2(sch_1):page211_i93:mp1" )
			)
			( pin "EU3P1.18"
				( objectStatus "@baseboard_fab2_lib.baseboard_fab2(sch_1):page211_i93:mp2" )
			)
			( pin "EU3P1.31"
				( objectStatus "@baseboard_fab2_lib.baseboard_fab2(sch_1):page211_i93:mp3" )
			)
			( pin "EU3P1.32"
				( objectStatus "@baseboard_fab2_lib.baseboard_fab2(sch_1):page211_i93:mp4" )
			)
			( pin "EU3P1.12"
				( objectStatus "@baseboard_fab2_lib.baseboard_fab2(sch_1):page211_i93:pinalrt_n" )
			)
			( pin "EU3P1.8"
				( objectStatus "@baseboard_fab2_lib.baseboard_fab2(sch_1):page211_i93:reset_n" )
			)
			( pin "EU3P1.7"
				( objectStatus "@baseboard_fab2_lib.baseboard_fab2(sch_1):page211_i93:scl" )
			)
			( pin "EU3P1.6"
				( objectStatus "@baseboard_fab2_lib.baseboard_fab2(sch_1):page211_i93:sda" )
			)
			( pin "EU3P1.41"
				( objectStatus "@baseboard_fab2_lib.baseboard_fab2(sch_1):page211_i93:thpad" )
			)
			( pin "EU3P1.17"
				( objectStatus "@baseboard_fab2_lib.baseboard_fab2(sch_1):page211_i93:valrt_n" )
			)
			( pin "EU3P1.15"
				( objectStatus "@baseboard_fab2_lib.baseboard_fab2(sch_1):page211_i93:vclk" )
			)
			( pin "EU3P1.40"
				( objectStatus "@baseboard_fab2_lib.baseboard_fab2(sch_1):page211_i93:vd12" )
			)
			( pin "EU3P1.39"
				( objectStatus "@baseboard_fab2_lib.baseboard_fab2(sch_1):page211_i93:vdd" )
			)
			( pin "EU3P1.16"
				( objectStatus "@baseboard_fab2_lib.baseboard_fab2(sch_1):page211_i93:vdio" )
			)
			( pin "EU3P1.37"
				( objectStatus "@baseboard_fab2_lib.baseboard_fab2(sch_1):page211_i93:vinsen" )
			)
			( pin "EU3P1.11"
				( objectStatus "@baseboard_fab2_lib.baseboard_fab2(sch_1):page211_i93:vrhot_n" )
			)
			( pin "EU3P1.36"
				( objectStatus "@baseboard_fab2_lib.baseboard_fab2(sch_1):page211_i93:xaddr1" )
			)
			( pin "EU3P1.33"
				( objectStatus "@baseboard_fab2_lib.baseboard_fab2(sch_1):page211_i93:xaddr2" )
			)
			( pin "C3N38.1"
				( objectStatus "@baseboard_fab2_lib.baseboard_fab2(sch_1):page212_i16:a" )
			)
			( pin "C3N38.2"
				( objectStatus "@baseboard_fab2_lib.baseboard_fab2(sch_1):page212_i16:b" )
			)
			( pin "C3N26.1"
				( objectStatus "@baseboard_fab2_lib.baseboard_fab2(sch_1):page212_i17:a" )
			)
			( pin "C3N26.2"
				( objectStatus "@baseboard_fab2_lib.baseboard_fab2(sch_1):page212_i17:b" )
			)
			( pin "C3N35.1"
				( objectStatus "@baseboard_fab2_lib.baseboard_fab2(sch_1):page212_i18:a" )
			)
			( pin "C3N35.2"
				( objectStatus "@baseboard_fab2_lib.baseboard_fab2(sch_1):page212_i18:b" )
			)
			( pin "C7C6.1"
				( objectStatus "@baseboard_fab2_lib.baseboard_fab2(sch_1):page212_i23:a" )
			)
			( pin "C7C6.2"
				( objectStatus "@baseboard_fab2_lib.baseboard_fab2(sch_1):page212_i23:b" )
			)
			( pin "L7C2.1"
				( objectStatus "@baseboard_fab2_lib.baseboard_fab2(sch_1):page212_i25:ina" )
			)
			( pin "L7C2.2"
				( objectStatus "@baseboard_fab2_lib.baseboard_fab2(sch_1):page212_i25:inb" )
			)
			( pin "R3N7.1"
				( objectStatus "@baseboard_fab2_lib.baseboard_fab2(sch_1):page212_i32:a" )
			)
			( pin "R3N7.2"
				( objectStatus "@baseboard_fab2_lib.baseboard_fab2(sch_1):page212_i32:b" )
			)
			( pin "C7C18.1"
				( objectStatus "@baseboard_fab2_lib.baseboard_fab2(sch_1):page212_i33:a" )
			)
			( pin "C7C18.2"
				( objectStatus "@baseboard_fab2_lib.baseboard_fab2(sch_1):page212_i33:b" )
			)
			( pin "C7C20.1"
				( objectStatus "@baseboard_fab2_lib.baseboard_fab2(sch_1):page212_i34:a" )
			)
			( pin "C7C20.2"
				( objectStatus "@baseboard_fab2_lib.baseboard_fab2(sch_1):page212_i34:b" )
			)
			( pin "C7C17.1"
				( objectStatus "@baseboard_fab2_lib.baseboard_fab2(sch_1):page212_i36:a" )
			)
			( pin "C7C17.2"
				( objectStatus "@baseboard_fab2_lib.baseboard_fab2(sch_1):page212_i36:b" )
			)
			( pin "C7C14.1"
				( objectStatus "@baseboard_fab2_lib.baseboard_fab2(sch_1):page212_i37:a" )
			)
			( pin "C7C14.2"
				( objectStatus "@baseboard_fab2_lib.baseboard_fab2(sch_1):page212_i37:b" )
			)
			( pin "C7C11.1"
				( objectStatus "@baseboard_fab2_lib.baseboard_fab2(sch_1):page212_i38:a" )
			)
			( pin "C7C11.2"
				( objectStatus "@baseboard_fab2_lib.baseboard_fab2(sch_1):page212_i38:b" )
			)
			( pin "C7C12.1"
				( objectStatus "@baseboard_fab2_lib.baseboard_fab2(sch_1):page212_i39:a" )
			)
			( pin "C7C12.2"
				( objectStatus "@baseboard_fab2_lib.baseboard_fab2(sch_1):page212_i39:b" )
			)
			( pin "C3N36.1"
				( objectStatus "@baseboard_fab2_lib.baseboard_fab2(sch_1):page212_i40:a" )
			)
			( pin "C3N36.2"
				( objectStatus "@baseboard_fab2_lib.baseboard_fab2(sch_1):page212_i40:b" )
			)
			( pin "C3N33.1"
				( objectStatus "@baseboard_fab2_lib.baseboard_fab2(sch_1):page212_i41:a" )
			)
			( pin "C3N33.2"
				( objectStatus "@baseboard_fab2_lib.baseboard_fab2(sch_1):page212_i41:b" )
			)
			( pin "C3N34.1"
				( objectStatus "@baseboard_fab2_lib.baseboard_fab2(sch_1):page212_i43:a" )
			)
			( pin "C3N34.2"
				( objectStatus "@baseboard_fab2_lib.baseboard_fab2(sch_1):page212_i43:b" )
			)
			( pin "C7C8.1"
				( objectStatus "@baseboard_fab2_lib.baseboard_fab2(sch_1):page212_i51:a" )
			)
			( pin "C7C8.2"
				( objectStatus "@baseboard_fab2_lib.baseboard_fab2(sch_1):page212_i51:b" )
			)
			( pin "C7C7.1"
				( objectStatus "@baseboard_fab2_lib.baseboard_fab2(sch_1):page212_i54:a" )
			)
			( pin "C7C7.2"
				( objectStatus "@baseboard_fab2_lib.baseboard_fab2(sch_1):page212_i54:b" )
			)
			( pin "L7C1.1"
				( objectStatus "@baseboard_fab2_lib.baseboard_fab2(sch_1):page212_i56:ina" )
			)
			( pin "L7C1.2"
				( objectStatus "@baseboard_fab2_lib.baseboard_fab2(sch_1):page212_i56:inb" )
			)
			( pin "C3P1.1"
				( objectStatus "@baseboard_fab2_lib.baseboard_fab2(sch_1):page212_i60:a" )
			)
			( pin "C3P1.2"
				( objectStatus "@baseboard_fab2_lib.baseboard_fab2(sch_1):page212_i60:b" )
			)
			( pin "R3N20.1"
				( objectStatus "@baseboard_fab2_lib.baseboard_fab2(sch_1):page212_i68:a" )
			)
			( pin "R3N20.2"
				( objectStatus "@baseboard_fab2_lib.baseboard_fab2(sch_1):page212_i68:b" )
			)
			( pin "R3N21.1"
				( objectStatus "@baseboard_fab2_lib.baseboard_fab2(sch_1):page212_i74:a" )
			)
			( pin "R3N21.2"
				( objectStatus "@baseboard_fab2_lib.baseboard_fab2(sch_1):page212_i74:b" )
			)
			( pin "C7C10.1"
				( objectStatus "@baseboard_fab2_lib.baseboard_fab2(sch_1):page212_i77:a" )
			)
			( pin "C7C10.2"
				( objectStatus "@baseboard_fab2_lib.baseboard_fab2(sch_1):page212_i77:b" )
			)
			( pin "R7C3.1"
				( objectStatus "@baseboard_fab2_lib.baseboard_fab2(sch_1):page212_i78:a" )
			)
			( pin "R7C3.2"
				( objectStatus "@baseboard_fab2_lib.baseboard_fab2(sch_1):page212_i78:b" )
			)
			( pin "EU7C1.33"
				( objectStatus "@baseboard_fab2_lib.baseboard_fab2(sch_1):page212_i101:boost" )
			)
			( pin "EU7C1.35"
				( objectStatus "@baseboard_fab2_lib.baseboard_fab2(sch_1):page212_i101:en" )
			)
			( pin "EU7C1.6"
				( objectStatus "@baseboard_fab2_lib.baseboard_fab2(sch_1):page212_i101:gl(0)" )
			)
			( pin "EU7C1.41"
				( objectStatus "@baseboard_fab2_lib.baseboard_fab2(sch_1):page212_i101:gl(1)" )
			)
			( pin "EU7C1.38"
				( objectStatus "@baseboard_fab2_lib.baseboard_fab2(sch_1):page212_i101:iout" )
			)
			( pin "EU7C1.2"
				( objectStatus "@baseboard_fab2_lib.baseboard_fab2(sch_1):page212_i101:lgnd" )
			)
			( pin "EU7C1.31"
				( objectStatus "@baseboard_fab2_lib.baseboard_fab2(sch_1):page212_i101:nc" )
			)
			( pin "EU7C1.37"
				( objectStatus "@baseboard_fab2_lib.baseboard_fab2(sch_1):page212_i101:ocset" )
			)
			( pin "EU7C1.5"
				( objectStatus "@baseboard_fab2_lib.baseboard_fab2(sch_1):page212_i101:pgnd(0)" )
			)
			( pin "EU7C1.7"
				( objectStatus "@baseboard_fab2_lib.baseboard_fab2(sch_1):page212_i101:pgnd(1)" )
			)
			( pin "EU7C1.40"
				( objectStatus "@baseboard_fab2_lib.baseboard_fab2(sch_1):page212_i101:pgnd(2)" )
			)
			( pin "EU7C1.32"
				( objectStatus "@baseboard_fab2_lib.baseboard_fab2(sch_1):page212_i101:phase" )
			)
			( pin "EU7C1.34"
				( objectStatus "@baseboard_fab2_lib.baseboard_fab2(sch_1):page212_i101:pwm" )
			)
			( pin "EU7C1.39"
				( objectStatus "@baseboard_fab2_lib.baseboard_fab2(sch_1):page212_i101:refin" )
			)
			( pin "EU7C1.10"
				( objectStatus "@baseboard_fab2_lib.baseboard_fab2(sch_1):page212_i101:sw" )
			)
			( pin "EU7C1.36"
				( objectStatus "@baseboard_fab2_lib.baseboard_fab2(sch_1):page212_i101:tout_flt" )
			)
			( pin "EU7C1.3"
				( objectStatus "@baseboard_fab2_lib.baseboard_fab2(sch_1):page212_i101:vcc" )
			)
			( pin "EU7C1.4"
				( objectStatus "@baseboard_fab2_lib.baseboard_fab2(sch_1):page212_i101:vdrv" )
			)
			( pin "EU7C1.25"
				( objectStatus "@baseboard_fab2_lib.baseboard_fab2(sch_1):page212_i101:vin(0)" )
			)
			( pin "EU7C1.30"
				( objectStatus "@baseboard_fab2_lib.baseboard_fab2(sch_1):page212_i101:vin(1)" )
			)
			( pin "EU7C1.1"
				( objectStatus "@baseboard_fab2_lib.baseboard_fab2(sch_1):page212_i101:vos" )
			)
			( pin "R7C25.1"
				( objectStatus "@baseboard_fab2_lib.baseboard_fab2(sch_1):page212_i103:a" )
			)
			( pin "R7C25.2"
				( objectStatus "@baseboard_fab2_lib.baseboard_fab2(sch_1):page212_i103:b" )
			)
			( pin "SH3P1.1"
				( objectStatus "@baseboard_fab2_lib.baseboard_fab2(sch_1):page212_i104:a" )
			)
			( pin "SH3P1.2"
				( objectStatus "@baseboard_fab2_lib.baseboard_fab2(sch_1):page212_i104:b" )
			)
			( pin "SH3P2.1"
				( objectStatus "@baseboard_fab2_lib.baseboard_fab2(sch_1):page212_i105:a" )
			)
			( pin "SH3P2.2"
				( objectStatus "@baseboard_fab2_lib.baseboard_fab2(sch_1):page212_i105:b" )
			)
			( pin "C4D31.1"
				( objectStatus "@baseboard_fab2_lib.baseboard_fab2(sch_1):page213_i9:a" )
			)
			( pin "C4D31.2"
				( objectStatus "@baseboard_fab2_lib.baseboard_fab2(sch_1):page213_i9:b" )
			)
			( pin "C4D32.1"
				( objectStatus "@baseboard_fab2_lib.baseboard_fab2(sch_1):page213_i11:a" )
			)
			( pin "C4D32.2"
				( objectStatus "@baseboard_fab2_lib.baseboard_fab2(sch_1):page213_i11:b" )
			)
			( pin "R4D46.1"
				( objectStatus "@baseboard_fab2_lib.baseboard_fab2(sch_1):page213_i13:a" )
			)
			( pin "R4D46.2"
				( objectStatus "@baseboard_fab2_lib.baseboard_fab2(sch_1):page213_i13:b" )
			)
			( pin "R6P49.1"
				( objectStatus "@baseboard_fab2_lib.baseboard_fab2(sch_1):page213_i14:a" )
			)
			( pin "R6P49.2"
				( objectStatus "@baseboard_fab2_lib.baseboard_fab2(sch_1):page213_i14:b" )
			)
			( pin "R4D42.1"
				( objectStatus "@baseboard_fab2_lib.baseboard_fab2(sch_1):page213_i15:a" )
			)
			( pin "R4D42.2"
				( objectStatus "@baseboard_fab2_lib.baseboard_fab2(sch_1):page213_i15:b" )
			)
			( pin "R4D56.1"
				( objectStatus "@baseboard_fab2_lib.baseboard_fab2(sch_1):page213_i16:a" )
			)
			( pin "R4D56.2"
				( objectStatus "@baseboard_fab2_lib.baseboard_fab2(sch_1):page213_i16:b" )
			)
			( pin "C4D36.1"
				( objectStatus "@baseboard_fab2_lib.baseboard_fab2(sch_1):page213_i17:a" )
			)
			( pin "C4D36.2"
				( objectStatus "@baseboard_fab2_lib.baseboard_fab2(sch_1):page213_i17:b" )
			)
			( pin "R4D47.1"
				( objectStatus "@baseboard_fab2_lib.baseboard_fab2(sch_1):page213_i25:a" )
			)
			( pin "R4D47.2"
				( objectStatus "@baseboard_fab2_lib.baseboard_fab2(sch_1):page213_i25:b" )
			)
			( pin "R6P35.1"
				( objectStatus "@baseboard_fab2_lib.baseboard_fab2(sch_1):page213_i27:a" )
			)
			( pin "R6P35.2"
				( objectStatus "@baseboard_fab2_lib.baseboard_fab2(sch_1):page213_i27:b" )
			)
			( pin "R6P33.1"
				( objectStatus "@baseboard_fab2_lib.baseboard_fab2(sch_1):page213_i30:a" )
			)
			( pin "R6P33.2"
				( objectStatus "@baseboard_fab2_lib.baseboard_fab2(sch_1):page213_i30:b" )
			)
			( pin "R4D60.1"
				( objectStatus "@baseboard_fab2_lib.baseboard_fab2(sch_1):page213_i31:a" )
			)
			( pin "R4D60.2"
				( objectStatus "@baseboard_fab2_lib.baseboard_fab2(sch_1):page213_i31:b" )
			)
			( pin "R4D57.1"
				( objectStatus "@baseboard_fab2_lib.baseboard_fab2(sch_1):page213_i32:a" )
			)
			( pin "R4D57.2"
				( objectStatus "@baseboard_fab2_lib.baseboard_fab2(sch_1):page213_i32:b" )
			)
			( pin "C4D40.1"
				( objectStatus "@baseboard_fab2_lib.baseboard_fab2(sch_1):page213_i33:a" )
			)
			( pin "C4D40.2"
				( objectStatus "@baseboard_fab2_lib.baseboard_fab2(sch_1):page213_i33:b" )
			)
			( pin "C4D38.1"
				( objectStatus "@baseboard_fab2_lib.baseboard_fab2(sch_1):page213_i35:a" )
			)
			( pin "C4D38.2"
				( objectStatus "@baseboard_fab2_lib.baseboard_fab2(sch_1):page213_i35:b" )
			)
			( pin "R4D54.1"
				( objectStatus "@baseboard_fab2_lib.baseboard_fab2(sch_1):page213_i37:a" )
			)
			( pin "R4D54.2"
				( objectStatus "@baseboard_fab2_lib.baseboard_fab2(sch_1):page213_i37:b" )
			)
			( pin "R4D44.1"
				( objectStatus "@baseboard_fab2_lib.baseboard_fab2(sch_1):page213_i38:a" )
			)
			( pin "R4D44.2"
				( objectStatus "@baseboard_fab2_lib.baseboard_fab2(sch_1):page213_i38:b" )
			)
			( pin "R4D43.1"
				( objectStatus "@baseboard_fab2_lib.baseboard_fab2(sch_1):page213_i39:a" )
			)
			( pin "R4D43.2"
				( objectStatus "@baseboard_fab2_lib.baseboard_fab2(sch_1):page213_i39:b" )
			)
			( pin "R4D64.1"
				( objectStatus "@baseboard_fab2_lib.baseboard_fab2(sch_1):page213_i42:a" )
			)
			( pin "R4D64.2"
				( objectStatus "@baseboard_fab2_lib.baseboard_fab2(sch_1):page213_i42:b" )
			)
			( pin "R4D51.1"
				( objectStatus "@baseboard_fab2_lib.baseboard_fab2(sch_1):page213_i46:a" )
			)
			( pin "R4D51.2"
				( objectStatus "@baseboard_fab2_lib.baseboard_fab2(sch_1):page213_i46:b" )
			)
			( pin "R4D49.1"
				( objectStatus "@baseboard_fab2_lib.baseboard_fab2(sch_1):page213_i63:a" )
			)
			( pin "R4D49.2"
				( objectStatus "@baseboard_fab2_lib.baseboard_fab2(sch_1):page213_i63:b" )
			)
			( pin "R4E2.1"
				( objectStatus "@baseboard_fab2_lib.baseboard_fab2(sch_1):page213_i65:a" )
			)
			( pin "R4E2.2"
				( objectStatus "@baseboard_fab2_lib.baseboard_fab2(sch_1):page213_i65:b" )
			)
			( pin "C4D33.1"
				( objectStatus "@baseboard_fab2_lib.baseboard_fab2(sch_1):page213_i73:a" )
			)
			( pin "C4D33.2"
				( objectStatus "@baseboard_fab2_lib.baseboard_fab2(sch_1):page213_i73:b" )
			)
			( pin "C4D44.1"
				( objectStatus "@baseboard_fab2_lib.baseboard_fab2(sch_1):page213_i83:a" )
			)
			( pin "C4D44.2"
				( objectStatus "@baseboard_fab2_lib.baseboard_fab2(sch_1):page213_i83:b" )
			)
			( pin "R4E7.1"
				( objectStatus "@baseboard_fab2_lib.baseboard_fab2(sch_1):page213_i84:a" )
			)
			( pin "R4E7.2"
				( objectStatus "@baseboard_fab2_lib.baseboard_fab2(sch_1):page213_i84:b" )
			)
			( pin "R6P41.1"
				( objectStatus "@baseboard_fab2_lib.baseboard_fab2(sch_1):page213_i90:a" )
			)
			( pin "R6P41.2"
				( objectStatus "@baseboard_fab2_lib.baseboard_fab2(sch_1):page213_i90:b" )
			)
			( pin "R6P40.1"
				( objectStatus "@baseboard_fab2_lib.baseboard_fab2(sch_1):page213_i91:a" )
			)
			( pin "R6P40.2"
				( objectStatus "@baseboard_fab2_lib.baseboard_fab2(sch_1):page213_i91:b" )
			)
			( pin "R4D45.1"
				( objectStatus "@baseboard_fab2_lib.baseboard_fab2(sch_1):page213_i94:a" )
			)
			( pin "R4D45.2"
				( objectStatus "@baseboard_fab2_lib.baseboard_fab2(sch_1):page213_i94:b" )
			)
			( pin "EU4D5.21"
				( objectStatus "@baseboard_fab2_lib.baseboard_fab2(sch_1):page213_i96:airef1" )
			)
			( pin "EU4D5.22"
				( objectStatus "@baseboard_fab2_lib.baseboard_fab2(sch_1):page213_i96:aisen1" )
			)
			( pin "EU4D5.5"
				( objectStatus "@baseboard_fab2_lib.baseboard_fab2(sch_1):page213_i96:apwm1" )
			)
			( pin "EU4D5.35"
				( objectStatus "@baseboard_fab2_lib.baseboard_fab2(sch_1):page213_i96:atsen" )
			)
			( pin "EU4D5.20"
				( objectStatus "@baseboard_fab2_lib.baseboard_fab2(sch_1):page213_i96:avref" )
			)
			( pin "EU4D5.10"
				( objectStatus "@baseboard_fab2_lib.baseboard_fab2(sch_1):page213_i96:avren" )
			)
			( pin "EU4D5.9"
				( objectStatus "@baseboard_fab2_lib.baseboard_fab2(sch_1):page213_i96:avrrdy" )
			)
			( pin "EU4D5.19"
				( objectStatus "@baseboard_fab2_lib.baseboard_fab2(sch_1):page213_i96:avsen" )
			)
			( pin "EU4D5.25"
				( objectStatus "@baseboard_fab2_lib.baseboard_fab2(sch_1):page213_i96:biref1" )
			)
			( pin "EU4D5.26"
				( objectStatus "@baseboard_fab2_lib.baseboard_fab2(sch_1):page213_i96:bisen1" )
			)
			( pin "EU4D5.3"
				( objectStatus "@baseboard_fab2_lib.baseboard_fab2(sch_1):page213_i96:bpwm1" )
			)
			( pin "EU4D5.34"
				( objectStatus "@baseboard_fab2_lib.baseboard_fab2(sch_1):page213_i96:btsen" )
			)
			( pin "EU4D5.30"
				( objectStatus "@baseboard_fab2_lib.baseboard_fab2(sch_1):page213_i96:bvref" )
			)
			( pin "EU4D5.29"
				( objectStatus "@baseboard_fab2_lib.baseboard_fab2(sch_1):page213_i96:bvsen" )
			)
			( pin "EU4D5.1"
				( objectStatus "@baseboard_fab2_lib.baseboard_fab2(sch_1):page213_i96:dnc(0)" )
			)
			( pin "EU4D5.2"
				( objectStatus "@baseboard_fab2_lib.baseboard_fab2(sch_1):page213_i96:dnc(1)" )
			)
			( pin "EU4D5.4"
				( objectStatus "@baseboard_fab2_lib.baseboard_fab2(sch_1):page213_i96:dnc(2)" )
			)
			( pin "EU4D5.24"
				( objectStatus "@baseboard_fab2_lib.baseboard_fab2(sch_1):page213_i96:dnc(3)" )
			)
			( pin "EU4D5.28"
				( objectStatus "@baseboard_fab2_lib.baseboard_fab2(sch_1):page213_i96:dnc(4)" )
			)
			( pin "EU4D5.27"
				( objectStatus "@baseboard_fab2_lib.baseboard_fab2(sch_1):page213_i96:gnd(0)" )
			)
			( pin "EU4D5.23"
				( objectStatus "@baseboard_fab2_lib.baseboard_fab2(sch_1):page213_i96:gnd(1)" )
			)
			( pin "EU4D5.38"
				( objectStatus "@baseboard_fab2_lib.baseboard_fab2(sch_1):page213_i96:iinsen" )
			)
			( pin "EU4D5.13"
				( objectStatus "@baseboard_fab2_lib.baseboard_fab2(sch_1):page213_i96:mp0" )
			)
			( pin "EU4D5.14"
				( objectStatus "@baseboard_fab2_lib.baseboard_fab2(sch_1):page213_i96:mp1" )
			)
			( pin "EU4D5.18"
				( objectStatus "@baseboard_fab2_lib.baseboard_fab2(sch_1):page213_i96:mp2" )
			)
			( pin "EU4D5.31"
				( objectStatus "@baseboard_fab2_lib.baseboard_fab2(sch_1):page213_i96:mp3" )
			)
			( pin "EU4D5.32"
				( objectStatus "@baseboard_fab2_lib.baseboard_fab2(sch_1):page213_i96:mp4" )
			)
			( pin "EU4D5.12"
				( objectStatus "@baseboard_fab2_lib.baseboard_fab2(sch_1):page213_i96:pinalrt_n" )
			)
			( pin "EU4D5.8"
				( objectStatus "@baseboard_fab2_lib.baseboard_fab2(sch_1):page213_i96:reset_n" )
			)
			( pin "EU4D5.7"
				( objectStatus "@baseboard_fab2_lib.baseboard_fab2(sch_1):page213_i96:scl" )
			)
			( pin "EU4D5.6"
				( objectStatus "@baseboard_fab2_lib.baseboard_fab2(sch_1):page213_i96:sda" )
			)
			( pin "EU4D5.41"
				( objectStatus "@baseboard_fab2_lib.baseboard_fab2(sch_1):page213_i96:thpad" )
			)
			( pin "EU4D5.17"
				( objectStatus "@baseboard_fab2_lib.baseboard_fab2(sch_1):page213_i96:valrt_n" )
			)
			( pin "EU4D5.15"
				( objectStatus "@baseboard_fab2_lib.baseboard_fab2(sch_1):page213_i96:vclk" )
			)
			( pin "EU4D5.40"
				( objectStatus "@baseboard_fab2_lib.baseboard_fab2(sch_1):page213_i96:vd12" )
			)
			( pin "EU4D5.39"
				( objectStatus "@baseboard_fab2_lib.baseboard_fab2(sch_1):page213_i96:vdd" )
			)
			( pin "EU4D5.16"
				( objectStatus "@baseboard_fab2_lib.baseboard_fab2(sch_1):page213_i96:vdio" )
			)
			( pin "EU4D5.37"
				( objectStatus "@baseboard_fab2_lib.baseboard_fab2(sch_1):page213_i96:vinsen" )
			)
			( pin "EU4D5.11"
				( objectStatus "@baseboard_fab2_lib.baseboard_fab2(sch_1):page213_i96:vrhot_n" )
			)
			( pin "EU4D5.36"
				( objectStatus "@baseboard_fab2_lib.baseboard_fab2(sch_1):page213_i96:xaddr1" )
			)
			( pin "EU4D5.33"
				( objectStatus "@baseboard_fab2_lib.baseboard_fab2(sch_1):page213_i96:xaddr2" )
			)
			( pin "C4E9.1"
				( objectStatus "@baseboard_fab2_lib.baseboard_fab2(sch_1):page214_i8:a" )
			)
			( pin "C4E9.2"
				( objectStatus "@baseboard_fab2_lib.baseboard_fab2(sch_1):page214_i8:b" )
			)
			( pin "C4E7.1"
				( objectStatus "@baseboard_fab2_lib.baseboard_fab2(sch_1):page214_i20:a" )
			)
			( pin "C4E7.2"
				( objectStatus "@baseboard_fab2_lib.baseboard_fab2(sch_1):page214_i20:b" )
			)
			( pin "C6R12.1"
				( objectStatus "@baseboard_fab2_lib.baseboard_fab2(sch_1):page214_i21:a" )
			)
			( pin "C6R12.2"
				( objectStatus "@baseboard_fab2_lib.baseboard_fab2(sch_1):page214_i21:b" )
			)
			( pin "C6R5.1"
				( objectStatus "@baseboard_fab2_lib.baseboard_fab2(sch_1):page214_i24:a" )
			)
			( pin "C6R5.2"
				( objectStatus "@baseboard_fab2_lib.baseboard_fab2(sch_1):page214_i24:b" )
			)
			( pin "C4E8.1"
				( objectStatus "@baseboard_fab2_lib.baseboard_fab2(sch_1):page214_i29:a" )
			)
			( pin "C4E8.2"
				( objectStatus "@baseboard_fab2_lib.baseboard_fab2(sch_1):page214_i29:b" )
			)
			( pin "C4E14.1"
				( objectStatus "@baseboard_fab2_lib.baseboard_fab2(sch_1):page214_i31:a" )
			)
			( pin "C4E14.2"
				( objectStatus "@baseboard_fab2_lib.baseboard_fab2(sch_1):page214_i31:b" )
			)
			( pin "C7R1.1"
				( objectStatus "@baseboard_fab2_lib.baseboard_fab2(sch_1):page214_i65:a" )
			)
			( pin "C7R1.2"
				( objectStatus "@baseboard_fab2_lib.baseboard_fab2(sch_1):page214_i65:b" )
			)
			( pin "L4E2.1"
				( objectStatus "@baseboard_fab2_lib.baseboard_fab2(sch_1):page214_i67:ina" )
			)
			( pin "L4E2.2"
				( objectStatus "@baseboard_fab2_lib.baseboard_fab2(sch_1):page214_i67:inb" )
			)
			( pin "R6R5.1"
				( objectStatus "@baseboard_fab2_lib.baseboard_fab2(sch_1):page214_i71:a" )
			)
			( pin "R6R5.2"
				( objectStatus "@baseboard_fab2_lib.baseboard_fab2(sch_1):page214_i71:b" )
			)
			( pin "C4E23.1"
				( objectStatus "@baseboard_fab2_lib.baseboard_fab2(sch_1):page214_i73:a" )
			)
			( pin "C4E23.2"
				( objectStatus "@baseboard_fab2_lib.baseboard_fab2(sch_1):page214_i73:b" )
			)
			( pin "C4E28.1"
				( objectStatus "@baseboard_fab2_lib.baseboard_fab2(sch_1):page214_i74:a" )
			)
			( pin "C4E28.2"
				( objectStatus "@baseboard_fab2_lib.baseboard_fab2(sch_1):page214_i74:b" )
			)
			( pin "C4E22.1"
				( objectStatus "@baseboard_fab2_lib.baseboard_fab2(sch_1):page214_i76:a" )
			)
			( pin "C4E22.2"
				( objectStatus "@baseboard_fab2_lib.baseboard_fab2(sch_1):page214_i76:b" )
			)
			( pin "C4E13.1"
				( objectStatus "@baseboard_fab2_lib.baseboard_fab2(sch_1):page214_i77:a" )
			)
			( pin "C4E13.2"
				( objectStatus "@baseboard_fab2_lib.baseboard_fab2(sch_1):page214_i77:b" )
			)
			( pin "C4E18.1"
				( objectStatus "@baseboard_fab2_lib.baseboard_fab2(sch_1):page214_i78:a" )
			)
			( pin "C4E18.2"
				( objectStatus "@baseboard_fab2_lib.baseboard_fab2(sch_1):page214_i78:b" )
			)
			( pin "C4E15.1"
				( objectStatus "@baseboard_fab2_lib.baseboard_fab2(sch_1):page214_i79:a" )
			)
			( pin "C4E15.2"
				( objectStatus "@baseboard_fab2_lib.baseboard_fab2(sch_1):page214_i79:b" )
			)
			( pin "C6R14.1"
				( objectStatus "@baseboard_fab2_lib.baseboard_fab2(sch_1):page214_i80:a" )
			)
			( pin "C6R14.2"
				( objectStatus "@baseboard_fab2_lib.baseboard_fab2(sch_1):page214_i80:b" )
			)
			( pin "C6R10.1"
				( objectStatus "@baseboard_fab2_lib.baseboard_fab2(sch_1):page214_i81:a" )
			)
			( pin "C6R10.2"
				( objectStatus "@baseboard_fab2_lib.baseboard_fab2(sch_1):page214_i81:b" )
			)
			( pin "C6R8.1"
				( objectStatus "@baseboard_fab2_lib.baseboard_fab2(sch_1):page214_i83:a" )
			)
			( pin "C6R8.2"
				( objectStatus "@baseboard_fab2_lib.baseboard_fab2(sch_1):page214_i83:b" )
			)
			( pin "C3D27.1"
				( objectStatus "@baseboard_fab2_lib.baseboard_fab2(sch_1):page214_i96:a" )
			)
			( pin "C3D27.2"
				( objectStatus "@baseboard_fab2_lib.baseboard_fab2(sch_1):page214_i96:b" )
			)
			( pin "R3D28.1"
				( objectStatus "@baseboard_fab2_lib.baseboard_fab2(sch_1):page214_i101:a" )
			)
			( pin "R3D28.2"
				( objectStatus "@baseboard_fab2_lib.baseboard_fab2(sch_1):page214_i101:b" )
			)
			( pin "R3E1.1"
				( objectStatus "@baseboard_fab2_lib.baseboard_fab2(sch_1):page214_i105:a" )
			)
			( pin "R3E1.2"
				( objectStatus "@baseboard_fab2_lib.baseboard_fab2(sch_1):page214_i105:b" )
			)
			( pin "C3E1.1"
				( objectStatus "@baseboard_fab2_lib.baseboard_fab2(sch_1):page214_i108:a" )
			)
			( pin "C3E1.2"
				( objectStatus "@baseboard_fab2_lib.baseboard_fab2(sch_1):page214_i108:b" )
			)
			( pin "R7R1.1"
				( objectStatus "@baseboard_fab2_lib.baseboard_fab2(sch_1):page214_i109:a" )
			)
			( pin "R7R1.2"
				( objectStatus "@baseboard_fab2_lib.baseboard_fab2(sch_1):page214_i109:b" )
			)
			( pin "EU4E2.33"
				( objectStatus "@baseboard_fab2_lib.baseboard_fab2(sch_1):page214_i126:boost" )
			)
			( pin "EU4E2.35"
				( objectStatus "@baseboard_fab2_lib.baseboard_fab2(sch_1):page214_i126:en" )
			)
			( pin "EU4E2.6"
				( objectStatus "@baseboard_fab2_lib.baseboard_fab2(sch_1):page214_i126:gl(0)" )
			)
			( pin "EU4E2.41"
				( objectStatus "@baseboard_fab2_lib.baseboard_fab2(sch_1):page214_i126:gl(1)" )
			)
			( pin "EU4E2.38"
				( objectStatus "@baseboard_fab2_lib.baseboard_fab2(sch_1):page214_i126:iout" )
			)
			( pin "EU4E2.2"
				( objectStatus "@baseboard_fab2_lib.baseboard_fab2(sch_1):page214_i126:lgnd" )
			)
			( pin "EU4E2.31"
				( objectStatus "@baseboard_fab2_lib.baseboard_fab2(sch_1):page214_i126:nc" )
			)
			( pin "EU4E2.37"
				( objectStatus "@baseboard_fab2_lib.baseboard_fab2(sch_1):page214_i126:ocset" )
			)
			( pin "EU4E2.5"
				( objectStatus "@baseboard_fab2_lib.baseboard_fab2(sch_1):page214_i126:pgnd(0)" )
			)
			( pin "EU4E2.7"
				( objectStatus "@baseboard_fab2_lib.baseboard_fab2(sch_1):page214_i126:pgnd(1)" )
			)
			( pin "EU4E2.40"
				( objectStatus "@baseboard_fab2_lib.baseboard_fab2(sch_1):page214_i126:pgnd(2)" )
			)
			( pin "EU4E2.32"
				( objectStatus "@baseboard_fab2_lib.baseboard_fab2(sch_1):page214_i126:phase" )
			)
			( pin "EU4E2.34"
				( objectStatus "@baseboard_fab2_lib.baseboard_fab2(sch_1):page214_i126:pwm" )
			)
			( pin "EU4E2.39"
				( objectStatus "@baseboard_fab2_lib.baseboard_fab2(sch_1):page214_i126:refin" )
			)
			( pin "EU4E2.10"
				( objectStatus "@baseboard_fab2_lib.baseboard_fab2(sch_1):page214_i126:sw" )
			)
			( pin "EU4E2.36"
				( objectStatus "@baseboard_fab2_lib.baseboard_fab2(sch_1):page214_i126:tout_flt" )
			)
			( pin "EU4E2.3"
				( objectStatus "@baseboard_fab2_lib.baseboard_fab2(sch_1):page214_i126:vcc" )
			)
			( pin "EU4E2.4"
				( objectStatus "@baseboard_fab2_lib.baseboard_fab2(sch_1):page214_i126:vdrv" )
			)
			( pin "EU4E2.25"
				( objectStatus "@baseboard_fab2_lib.baseboard_fab2(sch_1):page214_i126:vin(0)" )
			)
			( pin "EU4E2.30"
				( objectStatus "@baseboard_fab2_lib.baseboard_fab2(sch_1):page214_i126:vin(1)" )
			)
			( pin "EU4E2.1"
				( objectStatus "@baseboard_fab2_lib.baseboard_fab2(sch_1):page214_i126:vos" )
			)
			( pin "R4E21.1"
				( objectStatus "@baseboard_fab2_lib.baseboard_fab2(sch_1):page214_i127:a" )
			)
			( pin "R4E21.2"
				( objectStatus "@baseboard_fab2_lib.baseboard_fab2(sch_1):page214_i127:b" )
			)
			( pin "SH3D2.1"
				( objectStatus "@baseboard_fab2_lib.baseboard_fab2(sch_1):page214_i129:a" )
			)
			( pin "SH3D2.2"
				( objectStatus "@baseboard_fab2_lib.baseboard_fab2(sch_1):page214_i129:b" )
			)
			( pin "SH3D1.1"
				( objectStatus "@baseboard_fab2_lib.baseboard_fab2(sch_1):page214_i130:a" )
			)
			( pin "SH3D1.2"
				( objectStatus "@baseboard_fab2_lib.baseboard_fab2(sch_1):page214_i130:b" )
			)
			( pin "R3U2.1"
				( objectStatus "@baseboard_fab2_lib.baseboard_fab2(sch_1):page215_i295:a" )
			)
			( pin "R3U2.2"
				( objectStatus "@baseboard_fab2_lib.baseboard_fab2(sch_1):page215_i295:b" )
			)
			( pin "R7F24.1"
				( objectStatus "@baseboard_fab2_lib.baseboard_fab2(sch_1):page215_i296:a" )
			)
			( pin "R7F24.2"
				( objectStatus "@baseboard_fab2_lib.baseboard_fab2(sch_1):page215_i296:b" )
			)
			( pin "R7F23.1"
				( objectStatus "@baseboard_fab2_lib.baseboard_fab2(sch_1):page215_i297:a" )
			)
			( pin "R7F23.2"
				( objectStatus "@baseboard_fab2_lib.baseboard_fab2(sch_1):page215_i297:b" )
			)
			( pin "R7F25.1"
				( objectStatus "@baseboard_fab2_lib.baseboard_fab2(sch_1):page215_i298:a" )
			)
			( pin "R7F25.2"
				( objectStatus "@baseboard_fab2_lib.baseboard_fab2(sch_1):page215_i298:b" )
			)
			( pin "R7F36.1"
				( objectStatus "@baseboard_fab2_lib.baseboard_fab2(sch_1):page215_i300:a" )
			)
			( pin "R7F36.2"
				( objectStatus "@baseboard_fab2_lib.baseboard_fab2(sch_1):page215_i300:b" )
			)
			( pin "R7F22.1"
				( objectStatus "@baseboard_fab2_lib.baseboard_fab2(sch_1):page215_i301:a" )
			)
			( pin "R7F22.2"
				( objectStatus "@baseboard_fab2_lib.baseboard_fab2(sch_1):page215_i301:b" )
			)
			( pin "R7G4.1"
				( objectStatus "@baseboard_fab2_lib.baseboard_fab2(sch_1):page215_i302:a" )
			)
			( pin "R7G4.2"
				( objectStatus "@baseboard_fab2_lib.baseboard_fab2(sch_1):page215_i302:b" )
			)
			( pin "R7F27.1"
				( objectStatus "@baseboard_fab2_lib.baseboard_fab2(sch_1):page215_i303:a" )
			)
			( pin "R7F27.2"
				( objectStatus "@baseboard_fab2_lib.baseboard_fab2(sch_1):page215_i303:b" )
			)
			( pin "R7F26.1"
				( objectStatus "@baseboard_fab2_lib.baseboard_fab2(sch_1):page215_i304:a" )
			)
			( pin "R7F26.2"
				( objectStatus "@baseboard_fab2_lib.baseboard_fab2(sch_1):page215_i304:b" )
			)
			( pin "C7F14.1"
				( objectStatus "@baseboard_fab2_lib.baseboard_fab2(sch_1):page215_i305:a" )
			)
			( pin "C7F14.2"
				( objectStatus "@baseboard_fab2_lib.baseboard_fab2(sch_1):page215_i305:b" )
			)
			( pin "R7G2.1"
				( objectStatus "@baseboard_fab2_lib.baseboard_fab2(sch_1):page215_i307:a" )
			)
			( pin "R7G2.2"
				( objectStatus "@baseboard_fab2_lib.baseboard_fab2(sch_1):page215_i307:b" )
			)
			( pin "C7F18.1"
				( objectStatus "@baseboard_fab2_lib.baseboard_fab2(sch_1):page215_i309:a" )
			)
			( pin "C7F18.2"
				( objectStatus "@baseboard_fab2_lib.baseboard_fab2(sch_1):page215_i309:b" )
			)
			( pin "C7F17.1"
				( objectStatus "@baseboard_fab2_lib.baseboard_fab2(sch_1):page215_i311:a" )
			)
			( pin "C7F17.2"
				( objectStatus "@baseboard_fab2_lib.baseboard_fab2(sch_1):page215_i311:b" )
			)
			( pin "R3T13.1"
				( objectStatus "@baseboard_fab2_lib.baseboard_fab2(sch_1):page215_i313:a" )
			)
			( pin "R3T13.2"
				( objectStatus "@baseboard_fab2_lib.baseboard_fab2(sch_1):page215_i313:b" )
			)
			( pin "R7F20.1"
				( objectStatus "@baseboard_fab2_lib.baseboard_fab2(sch_1):page215_i315:a" )
			)
			( pin "R7F20.2"
				( objectStatus "@baseboard_fab2_lib.baseboard_fab2(sch_1):page215_i315:b" )
			)
			( pin "R7G10.1"
				( objectStatus "@baseboard_fab2_lib.baseboard_fab2(sch_1):page215_i317:a" )
			)
			( pin "R7G10.2"
				( objectStatus "@baseboard_fab2_lib.baseboard_fab2(sch_1):page215_i317:b" )
			)
			( pin "C7G3.1"
				( objectStatus "@baseboard_fab2_lib.baseboard_fab2(sch_1):page215_i320:a" )
			)
			( pin "C7G3.2"
				( objectStatus "@baseboard_fab2_lib.baseboard_fab2(sch_1):page215_i320:b" )
			)
			( pin "R7G8.1"
				( objectStatus "@baseboard_fab2_lib.baseboard_fab2(sch_1):page215_i321:a" )
			)
			( pin "R7G8.2"
				( objectStatus "@baseboard_fab2_lib.baseboard_fab2(sch_1):page215_i321:b" )
			)
			( pin "C7F16.1"
				( objectStatus "@baseboard_fab2_lib.baseboard_fab2(sch_1):page215_i325:a" )
			)
			( pin "C7F16.2"
				( objectStatus "@baseboard_fab2_lib.baseboard_fab2(sch_1):page215_i325:b" )
			)
			( pin "C7F15.1"
				( objectStatus "@baseboard_fab2_lib.baseboard_fab2(sch_1):page215_i327:a" )
			)
			( pin "C7F15.2"
				( objectStatus "@baseboard_fab2_lib.baseboard_fab2(sch_1):page215_i327:b" )
			)
			( pin "R3T11.1"
				( objectStatus "@baseboard_fab2_lib.baseboard_fab2(sch_1):page215_i330:a" )
			)
			( pin "R3T11.2"
				( objectStatus "@baseboard_fab2_lib.baseboard_fab2(sch_1):page215_i330:b" )
			)
			( pin "R7G24.1"
				( objectStatus "@baseboard_fab2_lib.baseboard_fab2(sch_1):page215_i331:a" )
			)
			( pin "R7G24.2"
				( objectStatus "@baseboard_fab2_lib.baseboard_fab2(sch_1):page215_i331:b" )
			)
			( pin "R3U3.1"
				( objectStatus "@baseboard_fab2_lib.baseboard_fab2(sch_1):page215_i332:a" )
			)
			( pin "R3U3.2"
				( objectStatus "@baseboard_fab2_lib.baseboard_fab2(sch_1):page215_i332:b" )
			)
			( pin "R7F34.1"
				( objectStatus "@baseboard_fab2_lib.baseboard_fab2(sch_1):page215_i336:a" )
			)
			( pin "R7F34.2"
				( objectStatus "@baseboard_fab2_lib.baseboard_fab2(sch_1):page215_i336:b" )
			)
			( pin "R7G3.1"
				( objectStatus "@baseboard_fab2_lib.baseboard_fab2(sch_1):page215_i337:a" )
			)
			( pin "R7G3.2"
				( objectStatus "@baseboard_fab2_lib.baseboard_fab2(sch_1):page215_i337:b" )
			)
			( pin "C7G1.1"
				( objectStatus "@baseboard_fab2_lib.baseboard_fab2(sch_1):page215_i339:a" )
			)
			( pin "C7G1.2"
				( objectStatus "@baseboard_fab2_lib.baseboard_fab2(sch_1):page215_i339:b" )
			)
			( pin "R3U10.1"
				( objectStatus "@baseboard_fab2_lib.baseboard_fab2(sch_1):page215_i341:a" )
			)
			( pin "R3U10.2"
				( objectStatus "@baseboard_fab2_lib.baseboard_fab2(sch_1):page215_i341:b" )
			)
			( pin "C7G4.1"
				( objectStatus "@baseboard_fab2_lib.baseboard_fab2(sch_1):page215_i342:a" )
			)
			( pin "C7G4.2"
				( objectStatus "@baseboard_fab2_lib.baseboard_fab2(sch_1):page215_i342:b" )
			)
			( pin "R7F21.1"
				( objectStatus "@baseboard_fab2_lib.baseboard_fab2(sch_1):page215_i343:a" )
			)
			( pin "R7F21.2"
				( objectStatus "@baseboard_fab2_lib.baseboard_fab2(sch_1):page215_i343:b" )
			)
			( pin "R7G9.1"
				( objectStatus "@baseboard_fab2_lib.baseboard_fab2(sch_1):page215_i344:a" )
			)
			( pin "R7G9.2"
				( objectStatus "@baseboard_fab2_lib.baseboard_fab2(sch_1):page215_i344:b" )
			)
			( pin "EU7G1.21"
				( objectStatus "@baseboard_fab2_lib.baseboard_fab2(sch_1):page215_i358:airef1" )
			)
			( pin "EU7G1.23"
				( objectStatus "@baseboard_fab2_lib.baseboard_fab2(sch_1):page215_i358:airef2" )
			)
			( pin "EU7G1.25"
				( objectStatus "@baseboard_fab2_lib.baseboard_fab2(sch_1):page215_i358:airef3" )
			)
			( pin "EU7G1.22"
				( objectStatus "@baseboard_fab2_lib.baseboard_fab2(sch_1):page215_i358:aisen1" )
			)
			( pin "EU7G1.24"
				( objectStatus "@baseboard_fab2_lib.baseboard_fab2(sch_1):page215_i358:aisen2" )
			)
			( pin "EU7G1.26"
				( objectStatus "@baseboard_fab2_lib.baseboard_fab2(sch_1):page215_i358:aisen3" )
			)
			( pin "EU7G1.5"
				( objectStatus "@baseboard_fab2_lib.baseboard_fab2(sch_1):page215_i358:apwm1" )
			)
			( pin "EU7G1.4"
				( objectStatus "@baseboard_fab2_lib.baseboard_fab2(sch_1):page215_i358:apwm2" )
			)
			( pin "EU7G1.3"
				( objectStatus "@baseboard_fab2_lib.baseboard_fab2(sch_1):page215_i358:apwm3" )
			)
			( pin "EU7G1.35"
				( objectStatus "@baseboard_fab2_lib.baseboard_fab2(sch_1):page215_i358:atsen" )
			)
			( pin "EU7G1.20"
				( objectStatus "@baseboard_fab2_lib.baseboard_fab2(sch_1):page215_i358:avref" )
			)
			( pin "EU7G1.10"
				( objectStatus "@baseboard_fab2_lib.baseboard_fab2(sch_1):page215_i358:avren" )
			)
			( pin "EU7G1.9"
				( objectStatus "@baseboard_fab2_lib.baseboard_fab2(sch_1):page215_i358:avrrdy" )
			)
			( pin "EU7G1.19"
				( objectStatus "@baseboard_fab2_lib.baseboard_fab2(sch_1):page215_i358:avsen" )
			)
			( pin "EU7G1.31"
				( objectStatus "@baseboard_fab2_lib.baseboard_fab2(sch_1):page215_i358:biref1" )
			)
			( pin "EU7G1.32"
				( objectStatus "@baseboard_fab2_lib.baseboard_fab2(sch_1):page215_i358:bisen1" )
			)
			( pin "EU7G1.1"
				( objectStatus "@baseboard_fab2_lib.baseboard_fab2(sch_1):page215_i358:bpwm1" )
			)
			( pin "EU7G1.34"
				( objectStatus "@baseboard_fab2_lib.baseboard_fab2(sch_1):page215_i358:btsen" )
			)
			( pin "EU7G1.30"
				( objectStatus "@baseboard_fab2_lib.baseboard_fab2(sch_1):page215_i358:bvref" )
			)
			( pin "EU7G1.29"
				( objectStatus "@baseboard_fab2_lib.baseboard_fab2(sch_1):page215_i358:bvsen" )
			)
			( pin "EU7G1.2"
				( objectStatus "@baseboard_fab2_lib.baseboard_fab2(sch_1):page215_i358:dnc(0)" )
			)
			( pin "EU7G1.28"
				( objectStatus "@baseboard_fab2_lib.baseboard_fab2(sch_1):page215_i358:dnc(1)" )
			)
			( pin "EU7G1.27"
				( objectStatus "@baseboard_fab2_lib.baseboard_fab2(sch_1):page215_i358:gnd" )
			)
			( pin "EU7G1.38"
				( objectStatus "@baseboard_fab2_lib.baseboard_fab2(sch_1):page215_i358:iinsen" )
			)
			( pin "EU7G1.13"
				( objectStatus "@baseboard_fab2_lib.baseboard_fab2(sch_1):page215_i358:mp0" )
			)
			( pin "EU7G1.14"
				( objectStatus "@baseboard_fab2_lib.baseboard_fab2(sch_1):page215_i358:mp1" )
			)
			( pin "EU7G1.18"
				( objectStatus "@baseboard_fab2_lib.baseboard_fab2(sch_1):page215_i358:mp2" )
			)
			( pin "EU7G1.12"
				( objectStatus "@baseboard_fab2_lib.baseboard_fab2(sch_1):page215_i358:pinalrt_n" )
			)
			( pin "EU7G1.8"
				( objectStatus "@baseboard_fab2_lib.baseboard_fab2(sch_1):page215_i358:reset_n" )
			)
			( pin "EU7G1.7"
				( objectStatus "@baseboard_fab2_lib.baseboard_fab2(sch_1):page215_i358:scl" )
			)
			( pin "EU7G1.6"
				( objectStatus "@baseboard_fab2_lib.baseboard_fab2(sch_1):page215_i358:sda" )
			)
			( pin "EU7G1.41"
				( objectStatus "@baseboard_fab2_lib.baseboard_fab2(sch_1):page215_i358:thpad" )
			)
			( pin "EU7G1.17"
				( objectStatus "@baseboard_fab2_lib.baseboard_fab2(sch_1):page215_i358:valrt_n" )
			)
			( pin "EU7G1.15"
				( objectStatus "@baseboard_fab2_lib.baseboard_fab2(sch_1):page215_i358:vclk" )
			)
			( pin "EU7G1.40"
				( objectStatus "@baseboard_fab2_lib.baseboard_fab2(sch_1):page215_i358:vd12" )
			)
			( pin "EU7G1.39"
				( objectStatus "@baseboard_fab2_lib.baseboard_fab2(sch_1):page215_i358:vdd" )
			)
			( pin "EU7G1.16"
				( objectStatus "@baseboard_fab2_lib.baseboard_fab2(sch_1):page215_i358:vdio" )
			)
			( pin "EU7G1.37"
				( objectStatus "@baseboard_fab2_lib.baseboard_fab2(sch_1):page215_i358:vinsen" )
			)
			( pin "EU7G1.11"
				( objectStatus "@baseboard_fab2_lib.baseboard_fab2(sch_1):page215_i358:vrhot_n" )
			)
			( pin "EU7G1.36"
				( objectStatus "@baseboard_fab2_lib.baseboard_fab2(sch_1):page215_i358:xaddr1" )
			)
			( pin "EU7G1.33"
				( objectStatus "@baseboard_fab2_lib.baseboard_fab2(sch_1):page215_i358:xaddr2" )
			)
			( pin "C3U10.1"
				( objectStatus "@baseboard_fab2_lib.baseboard_fab2(sch_1):page215_i360:a" )
			)
			( pin "C3U10.2"
				( objectStatus "@baseboard_fab2_lib.baseboard_fab2(sch_1):page215_i360:b" )
			)
			( pin "C6G3.1"
				( objectStatus "@baseboard_fab2_lib.baseboard_fab2(sch_1):page216_i6:a" )
			)
			( pin "C6G3.2"
				( objectStatus "@baseboard_fab2_lib.baseboard_fab2(sch_1):page216_i6:b" )
			)
			( pin "C7G31.1"
				( objectStatus "@baseboard_fab2_lib.baseboard_fab2(sch_1):page216_i44:a" )
			)
			( pin "C7G31.2"
				( objectStatus "@baseboard_fab2_lib.baseboard_fab2(sch_1):page216_i44:b" )
			)
			( pin "C3U2.1"
				( objectStatus "@baseboard_fab2_lib.baseboard_fab2(sch_1):page216_i45:a" )
			)
			( pin "C3U2.2"
				( objectStatus "@baseboard_fab2_lib.baseboard_fab2(sch_1):page216_i45:b" )
			)
			( pin "C3U3.1"
				( objectStatus "@baseboard_fab2_lib.baseboard_fab2(sch_1):page216_i46:a" )
			)
			( pin "C3U3.2"
				( objectStatus "@baseboard_fab2_lib.baseboard_fab2(sch_1):page216_i46:b" )
			)
			( pin "C3U4.1"
				( objectStatus "@baseboard_fab2_lib.baseboard_fab2(sch_1):page216_i47:a" )
			)
			( pin "C3U4.2"
				( objectStatus "@baseboard_fab2_lib.baseboard_fab2(sch_1):page216_i47:b" )
			)
			( pin "C7G37.1"
				( objectStatus "@baseboard_fab2_lib.baseboard_fab2(sch_1):page216_i48:a" )
			)
			( pin "C7G37.2"
				( objectStatus "@baseboard_fab2_lib.baseboard_fab2(sch_1):page216_i48:b" )
			)
			( pin "C7G33.1"
				( objectStatus "@baseboard_fab2_lib.baseboard_fab2(sch_1):page216_i50:a" )
			)
			( pin "C7G33.2"
				( objectStatus "@baseboard_fab2_lib.baseboard_fab2(sch_1):page216_i50:b" )
			)
			( pin "C7G29.1"
				( objectStatus "@baseboard_fab2_lib.baseboard_fab2(sch_1):page216_i51:a" )
			)
			( pin "C7G29.2"
				( objectStatus "@baseboard_fab2_lib.baseboard_fab2(sch_1):page216_i51:b" )
			)
			( pin "R3U6.1"
				( objectStatus "@baseboard_fab2_lib.baseboard_fab2(sch_1):page216_i52:a" )
			)
			( pin "R3U6.2"
				( objectStatus "@baseboard_fab2_lib.baseboard_fab2(sch_1):page216_i52:b" )
			)
			( pin "C7G35.1"
				( objectStatus "@baseboard_fab2_lib.baseboard_fab2(sch_1):page216_i53:a" )
			)
			( pin "C7G35.2"
				( objectStatus "@baseboard_fab2_lib.baseboard_fab2(sch_1):page216_i53:b" )
			)
			( pin "C7G34.1"
				( objectStatus "@baseboard_fab2_lib.baseboard_fab2(sch_1):page216_i54:a" )
			)
			( pin "C7G34.2"
				( objectStatus "@baseboard_fab2_lib.baseboard_fab2(sch_1):page216_i54:b" )
			)
			( pin "CT57.1"
				( objectStatus "@baseboard_fab2_lib.baseboard_fab2(sch_1):page210_i55:a" )
			)
			( pin "CT57.2"
				( objectStatus "@baseboard_fab2_lib.baseboard_fab2(sch_1):page210_i55:b" )
			)
			( pin "L7G2.1"
				( objectStatus "@baseboard_fab2_lib.baseboard_fab2(sch_1):page216_i65:ina" )
			)
			( pin "L7G2.2"
				( objectStatus "@baseboard_fab2_lib.baseboard_fab2(sch_1):page216_i65:inb" )
			)
			( pin "C7G27.1"
				( objectStatus "@baseboard_fab2_lib.baseboard_fab2(sch_1):page216_i68:a" )
			)
			( pin "C7G27.2"
				( objectStatus "@baseboard_fab2_lib.baseboard_fab2(sch_1):page216_i68:b" )
			)
			( pin "C7G41.1"
				( objectStatus "@baseboard_fab2_lib.baseboard_fab2(sch_1):page216_i72:a" )
			)
			( pin "C7G41.2"
				( objectStatus "@baseboard_fab2_lib.baseboard_fab2(sch_1):page216_i72:b" )
			)
			( pin "C7G42.1"
				( objectStatus "@baseboard_fab2_lib.baseboard_fab2(sch_1):page216_i73:a" )
			)
			( pin "C7G42.2"
				( objectStatus "@baseboard_fab2_lib.baseboard_fab2(sch_1):page216_i73:b" )
			)
			( pin "RT46.1"
				( objectStatus "@baseboard_fab2_lib.baseboard_fab2(sch_1):page236_i142:a" )
			)
			( pin "RT46.2"
				( objectStatus "@baseboard_fab2_lib.baseboard_fab2(sch_1):page236_i142:b" )
			)
			( pin "R3U9.1"
				( objectStatus "@baseboard_fab2_lib.baseboard_fab2(sch_1):page216_i76:a" )
			)
			( pin "R3U9.2"
				( objectStatus "@baseboard_fab2_lib.baseboard_fab2(sch_1):page216_i76:b" )
			)
			( pin "C7G40.1"
				( objectStatus "@baseboard_fab2_lib.baseboard_fab2(sch_1):page216_i77:a" )
			)
			( pin "C7G40.2"
				( objectStatus "@baseboard_fab2_lib.baseboard_fab2(sch_1):page216_i77:b" )
			)
			( pin "C7G36.1"
				( objectStatus "@baseboard_fab2_lib.baseboard_fab2(sch_1):page216_i78:a" )
			)
			( pin "C7G36.2"
				( objectStatus "@baseboard_fab2_lib.baseboard_fab2(sch_1):page216_i78:b" )
			)
			( pin "C7G30.1"
				( objectStatus "@baseboard_fab2_lib.baseboard_fab2(sch_1):page216_i79:a" )
			)
			( pin "C7G30.2"
				( objectStatus "@baseboard_fab2_lib.baseboard_fab2(sch_1):page216_i79:b" )
			)
			( pin "C3U9.1"
				( objectStatus "@baseboard_fab2_lib.baseboard_fab2(sch_1):page216_i80:a" )
			)
			( pin "C3U9.2"
				( objectStatus "@baseboard_fab2_lib.baseboard_fab2(sch_1):page216_i80:b" )
			)
			( pin "C3U7.1"
				( objectStatus "@baseboard_fab2_lib.baseboard_fab2(sch_1):page216_i81:a" )
			)
			( pin "C3U7.2"
				( objectStatus "@baseboard_fab2_lib.baseboard_fab2(sch_1):page216_i81:b" )
			)
			( pin "C3U6.1"
				( objectStatus "@baseboard_fab2_lib.baseboard_fab2(sch_1):page216_i84:a" )
			)
			( pin "C3U6.2"
				( objectStatus "@baseboard_fab2_lib.baseboard_fab2(sch_1):page216_i84:b" )
			)
			( pin "EU7G2.33"
				( objectStatus "@baseboard_fab2_lib.baseboard_fab2(sch_1):page216_i102:boost" )
			)
			( pin "EU7G2.35"
				( objectStatus "@baseboard_fab2_lib.baseboard_fab2(sch_1):page216_i102:en" )
			)
			( pin "EU7G2.6"
				( objectStatus "@baseboard_fab2_lib.baseboard_fab2(sch_1):page216_i102:gl(0)" )
			)
			( pin "EU7G2.41"
				( objectStatus "@baseboard_fab2_lib.baseboard_fab2(sch_1):page216_i102:gl(1)" )
			)
			( pin "EU7G2.38"
				( objectStatus "@baseboard_fab2_lib.baseboard_fab2(sch_1):page216_i102:iout" )
			)
			( pin "EU7G2.2"
				( objectStatus "@baseboard_fab2_lib.baseboard_fab2(sch_1):page216_i102:lgnd" )
			)
			( pin "EU7G2.31"
				( objectStatus "@baseboard_fab2_lib.baseboard_fab2(sch_1):page216_i102:nc" )
			)
			( pin "EU7G2.37"
				( objectStatus "@baseboard_fab2_lib.baseboard_fab2(sch_1):page216_i102:ocset" )
			)
			( pin "EU7G2.5"
				( objectStatus "@baseboard_fab2_lib.baseboard_fab2(sch_1):page216_i102:pgnd(0)" )
			)
			( pin "EU7G2.7"
				( objectStatus "@baseboard_fab2_lib.baseboard_fab2(sch_1):page216_i102:pgnd(1)" )
			)
			( pin "EU7G2.40"
				( objectStatus "@baseboard_fab2_lib.baseboard_fab2(sch_1):page216_i102:pgnd(2)" )
			)
			( pin "EU7G2.32"
				( objectStatus "@baseboard_fab2_lib.baseboard_fab2(sch_1):page216_i102:phase" )
			)
			( pin "EU7G2.34"
				( objectStatus "@baseboard_fab2_lib.baseboard_fab2(sch_1):page216_i102:pwm" )
			)
			( pin "EU7G2.39"
				( objectStatus "@baseboard_fab2_lib.baseboard_fab2(sch_1):page216_i102:refin" )
			)
			( pin "EU7G2.10"
				( objectStatus "@baseboard_fab2_lib.baseboard_fab2(sch_1):page216_i102:sw" )
			)
			( pin "EU7G2.36"
				( objectStatus "@baseboard_fab2_lib.baseboard_fab2(sch_1):page216_i102:tout_flt" )
			)
			( pin "EU7G2.3"
				( objectStatus "@baseboard_fab2_lib.baseboard_fab2(sch_1):page216_i102:vcc" )
			)
			( pin "EU7G2.4"
				( objectStatus "@baseboard_fab2_lib.baseboard_fab2(sch_1):page216_i102:vdrv" )
			)
			( pin "EU7G2.25"
				( objectStatus "@baseboard_fab2_lib.baseboard_fab2(sch_1):page216_i102:vin(0)" )
			)
			( pin "EU7G2.30"
				( objectStatus "@baseboard_fab2_lib.baseboard_fab2(sch_1):page216_i102:vin(1)" )
			)
			( pin "EU7G2.1"
				( objectStatus "@baseboard_fab2_lib.baseboard_fab2(sch_1):page216_i102:vos" )
			)
			( pin "EU7G3.33"
				( objectStatus "@baseboard_fab2_lib.baseboard_fab2(sch_1):page216_i103:boost" )
			)
			( pin "EU7G3.35"
				( objectStatus "@baseboard_fab2_lib.baseboard_fab2(sch_1):page216_i103:en" )
			)
			( pin "EU7G3.6"
				( objectStatus "@baseboard_fab2_lib.baseboard_fab2(sch_1):page216_i103:gl(0)" )
			)
			( pin "EU7G3.41"
				( objectStatus "@baseboard_fab2_lib.baseboard_fab2(sch_1):page216_i103:gl(1)" )
			)
			( pin "EU7G3.38"
				( objectStatus "@baseboard_fab2_lib.baseboard_fab2(sch_1):page216_i103:iout" )
			)
			( pin "EU7G3.2"
				( objectStatus "@baseboard_fab2_lib.baseboard_fab2(sch_1):page216_i103:lgnd" )
			)
			( pin "EU7G3.31"
				( objectStatus "@baseboard_fab2_lib.baseboard_fab2(sch_1):page216_i103:nc" )
			)
			( pin "EU7G3.37"
				( objectStatus "@baseboard_fab2_lib.baseboard_fab2(sch_1):page216_i103:ocset" )
			)
			( pin "EU7G3.5"
				( objectStatus "@baseboard_fab2_lib.baseboard_fab2(sch_1):page216_i103:pgnd(0)" )
			)
			( pin "EU7G3.7"
				( objectStatus "@baseboard_fab2_lib.baseboard_fab2(sch_1):page216_i103:pgnd(1)" )
			)
			( pin "EU7G3.40"
				( objectStatus "@baseboard_fab2_lib.baseboard_fab2(sch_1):page216_i103:pgnd(2)" )
			)
			( pin "EU7G3.32"
				( objectStatus "@baseboard_fab2_lib.baseboard_fab2(sch_1):page216_i103:phase" )
			)
			( pin "EU7G3.34"
				( objectStatus "@baseboard_fab2_lib.baseboard_fab2(sch_1):page216_i103:pwm" )
			)
			( pin "EU7G3.39"
				( objectStatus "@baseboard_fab2_lib.baseboard_fab2(sch_1):page216_i103:refin" )
			)
			( pin "EU7G3.10"
				( objectStatus "@baseboard_fab2_lib.baseboard_fab2(sch_1):page216_i103:sw" )
			)
			( pin "EU7G3.36"
				( objectStatus "@baseboard_fab2_lib.baseboard_fab2(sch_1):page216_i103:tout_flt" )
			)
			( pin "EU7G3.3"
				( objectStatus "@baseboard_fab2_lib.baseboard_fab2(sch_1):page216_i103:vcc" )
			)
			( pin "EU7G3.4"
				( objectStatus "@baseboard_fab2_lib.baseboard_fab2(sch_1):page216_i103:vdrv" )
			)
			( pin "EU7G3.25"
				( objectStatus "@baseboard_fab2_lib.baseboard_fab2(sch_1):page216_i103:vin(0)" )
			)
			( pin "EU7G3.30"
				( objectStatus "@baseboard_fab2_lib.baseboard_fab2(sch_1):page216_i103:vin(1)" )
			)
			( pin "EU7G3.1"
				( objectStatus "@baseboard_fab2_lib.baseboard_fab2(sch_1):page216_i103:vos" )
			)
			( pin "R7G25.1"
				( objectStatus "@baseboard_fab2_lib.baseboard_fab2(sch_1):page216_i104:a" )
			)
			( pin "R7G25.2"
				( objectStatus "@baseboard_fab2_lib.baseboard_fab2(sch_1):page216_i104:b" )
			)
			( pin "R7G30.1"
				( objectStatus "@baseboard_fab2_lib.baseboard_fab2(sch_1):page216_i106:a" )
			)
			( pin "R7G30.2"
				( objectStatus "@baseboard_fab2_lib.baseboard_fab2(sch_1):page216_i106:b" )
			)
			( pin "R3U4.1"
				( objectStatus "@baseboard_fab2_lib.baseboard_fab2(sch_1):page217_i58:a" )
			)
			( pin "R3U4.2"
				( objectStatus "@baseboard_fab2_lib.baseboard_fab2(sch_1):page217_i58:b" )
			)
			( pin "R4U6.1"
				( objectStatus "@baseboard_fab2_lib.baseboard_fab2(sch_1):page217_i74:a" )
			)
			( pin "R4U6.2"
				( objectStatus "@baseboard_fab2_lib.baseboard_fab2(sch_1):page217_i74:b" )
			)
			( pin "C7G28.1"
				( objectStatus "@baseboard_fab2_lib.baseboard_fab2(sch_1):page217_i75:a" )
			)
			( pin "C7G28.2"
				( objectStatus "@baseboard_fab2_lib.baseboard_fab2(sch_1):page217_i75:b" )
			)
			( pin "C3U1.1"
				( objectStatus "@baseboard_fab2_lib.baseboard_fab2(sch_1):page217_i76:a" )
			)
			( pin "C3U1.2"
				( objectStatus "@baseboard_fab2_lib.baseboard_fab2(sch_1):page217_i76:b" )
			)
			( pin "C3U5.1"
				( objectStatus "@baseboard_fab2_lib.baseboard_fab2(sch_1):page217_i77:a" )
			)
			( pin "C3U5.2"
				( objectStatus "@baseboard_fab2_lib.baseboard_fab2(sch_1):page217_i77:b" )
			)
			( pin "C3U8.1"
				( objectStatus "@baseboard_fab2_lib.baseboard_fab2(sch_1):page217_i78:a" )
			)
			( pin "C3U8.2"
				( objectStatus "@baseboard_fab2_lib.baseboard_fab2(sch_1):page217_i78:b" )
			)
			( pin "C5U13.1"
				( objectStatus "@baseboard_fab2_lib.baseboard_fab2(sch_1):page217_i82:a" )
			)
			( pin "C5U13.2"
				( objectStatus "@baseboard_fab2_lib.baseboard_fab2(sch_1):page217_i82:b" )
			)
			( pin "C5U10.1"
				( objectStatus "@baseboard_fab2_lib.baseboard_fab2(sch_1):page217_i83:a" )
			)
			( pin "C5U10.2"
				( objectStatus "@baseboard_fab2_lib.baseboard_fab2(sch_1):page217_i83:b" )
			)
			( pin "C5U1.1"
				( objectStatus "@baseboard_fab2_lib.baseboard_fab2(sch_1):page217_i88:a" )
			)
			( pin "C5U1.2"
				( objectStatus "@baseboard_fab2_lib.baseboard_fab2(sch_1):page217_i88:b" )
			)
			( pin "C5U14.1"
				( objectStatus "@baseboard_fab2_lib.baseboard_fab2(sch_1):page217_i89:a" )
			)
			( pin "C5U14.2"
				( objectStatus "@baseboard_fab2_lib.baseboard_fab2(sch_1):page217_i89:b" )
			)
			( pin "C5U15.1"
				( objectStatus "@baseboard_fab2_lib.baseboard_fab2(sch_1):page217_i90:a" )
			)
			( pin "C5U15.2"
				( objectStatus "@baseboard_fab2_lib.baseboard_fab2(sch_1):page217_i90:b" )
			)
			( pin "C4T4.1"
				( objectStatus "@baseboard_fab2_lib.baseboard_fab2(sch_1):page217_i91:a" )
			)
			( pin "C4T4.2"
				( objectStatus "@baseboard_fab2_lib.baseboard_fab2(sch_1):page217_i91:b" )
			)
			( pin "C5G9.1"
				( objectStatus "@baseboard_fab2_lib.baseboard_fab2(sch_1):page217_i92:a" )
			)
			( pin "C5G9.2"
				( objectStatus "@baseboard_fab2_lib.baseboard_fab2(sch_1):page217_i92:b" )
			)
			( pin "C5G20.1"
				( objectStatus "@baseboard_fab2_lib.baseboard_fab2(sch_1):page217_i110:a" )
			)
			( pin "C5G20.2"
				( objectStatus "@baseboard_fab2_lib.baseboard_fab2(sch_1):page217_i110:b" )
			)
			( pin "L7F2.1"
				( objectStatus "@baseboard_fab2_lib.baseboard_fab2(sch_1):page217_i124:ina" )
			)
			( pin "L7F2.2"
				( objectStatus "@baseboard_fab2_lib.baseboard_fab2(sch_1):page217_i124:inb" )
			)
			( pin "C7G2.1"
				( objectStatus "@baseboard_fab2_lib.baseboard_fab2(sch_1):page217_i175:a" )
			)
			( pin "C7G2.2"
				( objectStatus "@baseboard_fab2_lib.baseboard_fab2(sch_1):page217_i175:b" )
			)
			( pin "C5P39.1"
				( objectStatus "@baseboard_fab2_lib.baseboard_fab2(sch_1):page217_i184:a" )
			)
			( pin "C5P39.2"
				( objectStatus "@baseboard_fab2_lib.baseboard_fab2(sch_1):page217_i184:b" )
			)
			( pin "C5D57.1"
				( objectStatus "@baseboard_fab2_lib.baseboard_fab2(sch_1):page217_i186:a" )
			)
			( pin "C5D57.2"
				( objectStatus "@baseboard_fab2_lib.baseboard_fab2(sch_1):page217_i186:b" )
			)
			( pin "C5D56.1"
				( objectStatus "@baseboard_fab2_lib.baseboard_fab2(sch_1):page217_i188:a" )
			)
			( pin "C5D56.2"
				( objectStatus "@baseboard_fab2_lib.baseboard_fab2(sch_1):page217_i188:b" )
			)
			( pin "C5D55.1"
				( objectStatus "@baseboard_fab2_lib.baseboard_fab2(sch_1):page217_i189:a" )
			)
			( pin "C5D55.2"
				( objectStatus "@baseboard_fab2_lib.baseboard_fab2(sch_1):page217_i189:b" )
			)
			( pin "C5D54.1"
				( objectStatus "@baseboard_fab2_lib.baseboard_fab2(sch_1):page217_i190:a" )
			)
			( pin "C5D54.2"
				( objectStatus "@baseboard_fab2_lib.baseboard_fab2(sch_1):page217_i190:b" )
			)
			( pin "C5P38.1"
				( objectStatus "@baseboard_fab2_lib.baseboard_fab2(sch_1):page217_i193:a" )
			)
			( pin "C5P38.2"
				( objectStatus "@baseboard_fab2_lib.baseboard_fab2(sch_1):page217_i193:b" )
			)
			( pin "C5F2.1"
				( objectStatus "@baseboard_fab2_lib.baseboard_fab2(sch_1):page217_i205:a" )
			)
			( pin "C5F2.2"
				( objectStatus "@baseboard_fab2_lib.baseboard_fab2(sch_1):page217_i205:b" )
			)
			( pin "C5F1.1"
				( objectStatus "@baseboard_fab2_lib.baseboard_fab2(sch_1):page217_i206:a" )
			)
			( pin "C5F1.2"
				( objectStatus "@baseboard_fab2_lib.baseboard_fab2(sch_1):page217_i206:b" )
			)
			( pin "C5G10.1"
				( objectStatus "@baseboard_fab2_lib.baseboard_fab2(sch_1):page217_i207:a" )
			)
			( pin "C5G10.2"
				( objectStatus "@baseboard_fab2_lib.baseboard_fab2(sch_1):page217_i207:b" )
			)
			( pin "C5T2.1"
				( objectStatus "@baseboard_fab2_lib.baseboard_fab2(sch_1):page217_i208:a" )
			)
			( pin "C5T2.2"
				( objectStatus "@baseboard_fab2_lib.baseboard_fab2(sch_1):page217_i208:b" )
			)
			( pin "C5U11.1"
				( objectStatus "@baseboard_fab2_lib.baseboard_fab2(sch_1):page217_i209:a" )
			)
			( pin "C5U11.2"
				( objectStatus "@baseboard_fab2_lib.baseboard_fab2(sch_1):page217_i209:b" )
			)
			( pin "C5T13.1"
				( objectStatus "@baseboard_fab2_lib.baseboard_fab2(sch_1):page217_i210:a" )
			)
			( pin "C5T13.2"
				( objectStatus "@baseboard_fab2_lib.baseboard_fab2(sch_1):page217_i210:b" )
			)
			( pin "C5T4.1"
				( objectStatus "@baseboard_fab2_lib.baseboard_fab2(sch_1):page217_i211:a" )
			)
			( pin "C5T4.2"
				( objectStatus "@baseboard_fab2_lib.baseboard_fab2(sch_1):page217_i211:b" )
			)
			( pin "C5T1.1"
				( objectStatus "@baseboard_fab2_lib.baseboard_fab2(sch_1):page217_i212:a" )
			)
			( pin "C5T1.2"
				( objectStatus "@baseboard_fab2_lib.baseboard_fab2(sch_1):page217_i212:b" )
			)
			( pin "C5G19.1"
				( objectStatus "@baseboard_fab2_lib.baseboard_fab2(sch_1):page217_i213:a" )
			)
			( pin "C5G19.2"
				( objectStatus "@baseboard_fab2_lib.baseboard_fab2(sch_1):page217_i213:b" )
			)
			( pin "C5T5.1"
				( objectStatus "@baseboard_fab2_lib.baseboard_fab2(sch_1):page217_i216:a" )
			)
			( pin "C5T5.2"
				( objectStatus "@baseboard_fab2_lib.baseboard_fab2(sch_1):page217_i216:b" )
			)
			( pin "C5G3.1"
				( objectStatus "@baseboard_fab2_lib.baseboard_fab2(sch_1):page217_i217:a" )
			)
			( pin "C5G3.2"
				( objectStatus "@baseboard_fab2_lib.baseboard_fab2(sch_1):page217_i217:b" )
			)
			( pin "C5T6.1"
				( objectStatus "@baseboard_fab2_lib.baseboard_fab2(sch_1):page217_i218:a" )
			)
			( pin "C5T6.2"
				( objectStatus "@baseboard_fab2_lib.baseboard_fab2(sch_1):page217_i218:b" )
			)
			( pin "C5T7.1"
				( objectStatus "@baseboard_fab2_lib.baseboard_fab2(sch_1):page217_i219:a" )
			)
			( pin "C5T7.2"
				( objectStatus "@baseboard_fab2_lib.baseboard_fab2(sch_1):page217_i219:b" )
			)
			( pin "C5G15.1"
				( objectStatus "@baseboard_fab2_lib.baseboard_fab2(sch_1):page217_i220:a" )
			)
			( pin "C5G15.2"
				( objectStatus "@baseboard_fab2_lib.baseboard_fab2(sch_1):page217_i220:b" )
			)
			( pin "C5G16.1"
				( objectStatus "@baseboard_fab2_lib.baseboard_fab2(sch_1):page217_i221:a" )
			)
			( pin "C5G16.2"
				( objectStatus "@baseboard_fab2_lib.baseboard_fab2(sch_1):page217_i221:b" )
			)
			( pin "C5T8.1"
				( objectStatus "@baseboard_fab2_lib.baseboard_fab2(sch_1):page217_i222:a" )
			)
			( pin "C5T8.2"
				( objectStatus "@baseboard_fab2_lib.baseboard_fab2(sch_1):page217_i222:b" )
			)
			( pin "C5G14.1"
				( objectStatus "@baseboard_fab2_lib.baseboard_fab2(sch_1):page217_i223:a" )
			)
			( pin "C5G14.2"
				( objectStatus "@baseboard_fab2_lib.baseboard_fab2(sch_1):page217_i223:b" )
			)
			( pin "C5T9.1"
				( objectStatus "@baseboard_fab2_lib.baseboard_fab2(sch_1):page217_i224:a" )
			)
			( pin "C5T9.2"
				( objectStatus "@baseboard_fab2_lib.baseboard_fab2(sch_1):page217_i224:b" )
			)
			( pin "C5T10.1"
				( objectStatus "@baseboard_fab2_lib.baseboard_fab2(sch_1):page217_i225:a" )
			)
			( pin "C5T10.2"
				( objectStatus "@baseboard_fab2_lib.baseboard_fab2(sch_1):page217_i225:b" )
			)
			( pin "C5G17.1"
				( objectStatus "@baseboard_fab2_lib.baseboard_fab2(sch_1):page217_i226:a" )
			)
			( pin "C5G17.2"
				( objectStatus "@baseboard_fab2_lib.baseboard_fab2(sch_1):page217_i226:b" )
			)
			( pin "C5G18.1"
				( objectStatus "@baseboard_fab2_lib.baseboard_fab2(sch_1):page217_i227:a" )
			)
			( pin "C5G18.2"
				( objectStatus "@baseboard_fab2_lib.baseboard_fab2(sch_1):page217_i227:b" )
			)
			( pin "C5T11.1"
				( objectStatus "@baseboard_fab2_lib.baseboard_fab2(sch_1):page217_i228:a" )
			)
			( pin "C5T11.2"
				( objectStatus "@baseboard_fab2_lib.baseboard_fab2(sch_1):page217_i228:b" )
			)
			( pin "C5T12.1"
				( objectStatus "@baseboard_fab2_lib.baseboard_fab2(sch_1):page217_i229:a" )
			)
			( pin "C5T12.2"
				( objectStatus "@baseboard_fab2_lib.baseboard_fab2(sch_1):page217_i229:b" )
			)
			( pin "C5G8.1"
				( objectStatus "@baseboard_fab2_lib.baseboard_fab2(sch_1):page217_i230:a" )
			)
			( pin "C5G8.2"
				( objectStatus "@baseboard_fab2_lib.baseboard_fab2(sch_1):page217_i230:b" )
			)
			( pin "C5G1.1"
				( objectStatus "@baseboard_fab2_lib.baseboard_fab2(sch_1):page217_i231:a" )
			)
			( pin "C5G1.2"
				( objectStatus "@baseboard_fab2_lib.baseboard_fab2(sch_1):page217_i231:b" )
			)
			( pin "C5U9.1"
				( objectStatus "@baseboard_fab2_lib.baseboard_fab2(sch_1):page217_i232:a" )
			)
			( pin "C5U9.2"
				( objectStatus "@baseboard_fab2_lib.baseboard_fab2(sch_1):page217_i232:b" )
			)
			( pin "C5U8.1"
				( objectStatus "@baseboard_fab2_lib.baseboard_fab2(sch_1):page217_i233:a" )
			)
			( pin "C5U8.2"
				( objectStatus "@baseboard_fab2_lib.baseboard_fab2(sch_1):page217_i233:b" )
			)
			( pin "C5G7.1"
				( objectStatus "@baseboard_fab2_lib.baseboard_fab2(sch_1):page217_i234:a" )
			)
			( pin "C5G7.2"
				( objectStatus "@baseboard_fab2_lib.baseboard_fab2(sch_1):page217_i234:b" )
			)
			( pin "C5G5.1"
				( objectStatus "@baseboard_fab2_lib.baseboard_fab2(sch_1):page217_i235:a" )
			)
			( pin "C5G5.2"
				( objectStatus "@baseboard_fab2_lib.baseboard_fab2(sch_1):page217_i235:b" )
			)
			( pin "C5U7.1"
				( objectStatus "@baseboard_fab2_lib.baseboard_fab2(sch_1):page217_i236:a" )
			)
			( pin "C5U7.2"
				( objectStatus "@baseboard_fab2_lib.baseboard_fab2(sch_1):page217_i236:b" )
			)
			( pin "C5G6.1"
				( objectStatus "@baseboard_fab2_lib.baseboard_fab2(sch_1):page217_i237:a" )
			)
			( pin "C5G6.2"
				( objectStatus "@baseboard_fab2_lib.baseboard_fab2(sch_1):page217_i237:b" )
			)
			( pin "C5U6.1"
				( objectStatus "@baseboard_fab2_lib.baseboard_fab2(sch_1):page217_i238:a" )
			)
			( pin "C5U6.2"
				( objectStatus "@baseboard_fab2_lib.baseboard_fab2(sch_1):page217_i238:b" )
			)
			( pin "C5U5.1"
				( objectStatus "@baseboard_fab2_lib.baseboard_fab2(sch_1):page217_i239:a" )
			)
			( pin "C5U5.2"
				( objectStatus "@baseboard_fab2_lib.baseboard_fab2(sch_1):page217_i239:b" )
			)
			( pin "C5G13.1"
				( objectStatus "@baseboard_fab2_lib.baseboard_fab2(sch_1):page217_i240:a" )
			)
			( pin "C5G13.2"
				( objectStatus "@baseboard_fab2_lib.baseboard_fab2(sch_1):page217_i240:b" )
			)
			( pin "C5G4.1"
				( objectStatus "@baseboard_fab2_lib.baseboard_fab2(sch_1):page217_i241:a" )
			)
			( pin "C5G4.2"
				( objectStatus "@baseboard_fab2_lib.baseboard_fab2(sch_1):page217_i241:b" )
			)
			( pin "C5U4.1"
				( objectStatus "@baseboard_fab2_lib.baseboard_fab2(sch_1):page217_i243:a" )
			)
			( pin "C5U4.2"
				( objectStatus "@baseboard_fab2_lib.baseboard_fab2(sch_1):page217_i243:b" )
			)
			( pin "C5U3.1"
				( objectStatus "@baseboard_fab2_lib.baseboard_fab2(sch_1):page217_i244:a" )
			)
			( pin "C5U3.2"
				( objectStatus "@baseboard_fab2_lib.baseboard_fab2(sch_1):page217_i244:b" )
			)
			( pin "C5G2.1"
				( objectStatus "@baseboard_fab2_lib.baseboard_fab2(sch_1):page217_i245:a" )
			)
			( pin "C5G2.2"
				( objectStatus "@baseboard_fab2_lib.baseboard_fab2(sch_1):page217_i245:b" )
			)
			( pin "C5G12.1"
				( objectStatus "@baseboard_fab2_lib.baseboard_fab2(sch_1):page217_i246:a" )
			)
			( pin "C5G12.2"
				( objectStatus "@baseboard_fab2_lib.baseboard_fab2(sch_1):page217_i246:b" )
			)
			( pin "C5U2.1"
				( objectStatus "@baseboard_fab2_lib.baseboard_fab2(sch_1):page217_i247:a" )
			)
			( pin "C5U2.2"
				( objectStatus "@baseboard_fab2_lib.baseboard_fab2(sch_1):page217_i247:b" )
			)
			( pin "C5G11.1"
				( objectStatus "@baseboard_fab2_lib.baseboard_fab2(sch_1):page217_i250:a" )
			)
			( pin "C5G11.2"
				( objectStatus "@baseboard_fab2_lib.baseboard_fab2(sch_1):page217_i250:b" )
			)
			( pin "SH4U1.1"
				( objectStatus "@baseboard_fab2_lib.baseboard_fab2(sch_1):page217_i259:a" )
			)
			( pin "SH4U1.2"
				( objectStatus "@baseboard_fab2_lib.baseboard_fab2(sch_1):page217_i259:b" )
			)
			( pin "SH4U2.1"
				( objectStatus "@baseboard_fab2_lib.baseboard_fab2(sch_1):page217_i260:a" )
			)
			( pin "SH4U2.2"
				( objectStatus "@baseboard_fab2_lib.baseboard_fab2(sch_1):page217_i260:b" )
			)
			( pin "R3L11.1"
				( objectStatus "@baseboard_fab2_lib.baseboard_fab2(sch_1):page218_i7:a" )
			)
			( pin "R3L11.2"
				( objectStatus "@baseboard_fab2_lib.baseboard_fab2(sch_1):page218_i7:b" )
			)
			( pin "R3M3.1"
				( objectStatus "@baseboard_fab2_lib.baseboard_fab2(sch_1):page218_i11:a" )
			)
			( pin "R3M3.2"
				( objectStatus "@baseboard_fab2_lib.baseboard_fab2(sch_1):page218_i11:b" )
			)
			( pin "R7B1.1"
				( objectStatus "@baseboard_fab2_lib.baseboard_fab2(sch_1):page218_i12:a" )
			)
			( pin "R7B1.2"
				( objectStatus "@baseboard_fab2_lib.baseboard_fab2(sch_1):page218_i12:b" )
			)
			( pin "R7A9.1"
				( objectStatus "@baseboard_fab2_lib.baseboard_fab2(sch_1):page218_i14:a" )
			)
			( pin "R7A9.2"
				( objectStatus "@baseboard_fab2_lib.baseboard_fab2(sch_1):page218_i14:b" )
			)
			( pin "R7A11.1"
				( objectStatus "@baseboard_fab2_lib.baseboard_fab2(sch_1):page218_i15:a" )
			)
			( pin "R7A11.2"
				( objectStatus "@baseboard_fab2_lib.baseboard_fab2(sch_1):page218_i15:b" )
			)
			( pin "R7B5.1"
				( objectStatus "@baseboard_fab2_lib.baseboard_fab2(sch_1):page218_i16:a" )
			)
			( pin "R7B5.2"
				( objectStatus "@baseboard_fab2_lib.baseboard_fab2(sch_1):page218_i16:b" )
			)
			( pin "R7B4.1"
				( objectStatus "@baseboard_fab2_lib.baseboard_fab2(sch_1):page218_i17:a" )
			)
			( pin "R7B4.2"
				( objectStatus "@baseboard_fab2_lib.baseboard_fab2(sch_1):page218_i17:b" )
			)
			( pin "R7B3.1"
				( objectStatus "@baseboard_fab2_lib.baseboard_fab2(sch_1):page218_i21:a" )
			)
			( pin "R7B3.2"
				( objectStatus "@baseboard_fab2_lib.baseboard_fab2(sch_1):page218_i21:b" )
			)
			( pin "C7B1.1"
				( objectStatus "@baseboard_fab2_lib.baseboard_fab2(sch_1):page218_i22:a" )
			)
			( pin "C7B1.2"
				( objectStatus "@baseboard_fab2_lib.baseboard_fab2(sch_1):page218_i22:b" )
			)
			( pin "C7B2.1"
				( objectStatus "@baseboard_fab2_lib.baseboard_fab2(sch_1):page218_i23:a" )
			)
			( pin "C7B2.2"
				( objectStatus "@baseboard_fab2_lib.baseboard_fab2(sch_1):page218_i23:b" )
			)
			( pin "R7B2.1"
				( objectStatus "@baseboard_fab2_lib.baseboard_fab2(sch_1):page218_i24:a" )
			)
			( pin "R7B2.2"
				( objectStatus "@baseboard_fab2_lib.baseboard_fab2(sch_1):page218_i24:b" )
			)
			( pin "R7A12.1"
				( objectStatus "@baseboard_fab2_lib.baseboard_fab2(sch_1):page218_i25:a" )
			)
			( pin "R7A12.2"
				( objectStatus "@baseboard_fab2_lib.baseboard_fab2(sch_1):page218_i25:b" )
			)
			( pin "C7B3.1"
				( objectStatus "@baseboard_fab2_lib.baseboard_fab2(sch_1):page218_i26:a" )
			)
			( pin "C7B3.2"
				( objectStatus "@baseboard_fab2_lib.baseboard_fab2(sch_1):page218_i26:b" )
			)
			( pin "C7A37.1"
				( objectStatus "@baseboard_fab2_lib.baseboard_fab2(sch_1):page218_i29:a" )
			)
			( pin "C7A37.2"
				( objectStatus "@baseboard_fab2_lib.baseboard_fab2(sch_1):page218_i29:b" )
			)
			( pin "C7A38.1"
				( objectStatus "@baseboard_fab2_lib.baseboard_fab2(sch_1):page218_i31:a" )
			)
			( pin "C7A38.2"
				( objectStatus "@baseboard_fab2_lib.baseboard_fab2(sch_1):page218_i31:b" )
			)
			( pin "R3M1.1"
				( objectStatus "@baseboard_fab2_lib.baseboard_fab2(sch_1):page218_i34:a" )
			)
			( pin "R3M1.2"
				( objectStatus "@baseboard_fab2_lib.baseboard_fab2(sch_1):page218_i34:b" )
			)
			( pin "R3M5.1"
				( objectStatus "@baseboard_fab2_lib.baseboard_fab2(sch_1):page218_i35:a" )
			)
			( pin "R3M5.2"
				( objectStatus "@baseboard_fab2_lib.baseboard_fab2(sch_1):page218_i35:b" )
			)
			( pin "R7A8.1"
				( objectStatus "@baseboard_fab2_lib.baseboard_fab2(sch_1):page218_i37:a" )
			)
			( pin "R7A8.2"
				( objectStatus "@baseboard_fab2_lib.baseboard_fab2(sch_1):page218_i37:b" )
			)
			( pin "C7A29.1"
				( objectStatus "@baseboard_fab2_lib.baseboard_fab2(sch_1):page218_i39:a" )
			)
			( pin "C7A29.2"
				( objectStatus "@baseboard_fab2_lib.baseboard_fab2(sch_1):page218_i39:b" )
			)
			( pin "R7A10.1"
				( objectStatus "@baseboard_fab2_lib.baseboard_fab2(sch_1):page218_i40:a" )
			)
			( pin "R7A10.2"
				( objectStatus "@baseboard_fab2_lib.baseboard_fab2(sch_1):page218_i40:b" )
			)
			( pin "R3L13.1"
				( objectStatus "@baseboard_fab2_lib.baseboard_fab2(sch_1):page218_i47:a" )
			)
			( pin "R3L13.2"
				( objectStatus "@baseboard_fab2_lib.baseboard_fab2(sch_1):page218_i47:b" )
			)
			( pin "R7A17.1"
				( objectStatus "@baseboard_fab2_lib.baseboard_fab2(sch_1):page218_i48:a" )
			)
			( pin "R7A17.2"
				( objectStatus "@baseboard_fab2_lib.baseboard_fab2(sch_1):page218_i48:b" )
			)
			( pin "R3L10.1"
				( objectStatus "@baseboard_fab2_lib.baseboard_fab2(sch_1):page218_i50:a" )
			)
			( pin "R3L10.2"
				( objectStatus "@baseboard_fab2_lib.baseboard_fab2(sch_1):page218_i50:b" )
			)
			( pin "R3L12.1"
				( objectStatus "@baseboard_fab2_lib.baseboard_fab2(sch_1):page218_i53:a" )
			)
			( pin "R3L12.2"
				( objectStatus "@baseboard_fab2_lib.baseboard_fab2(sch_1):page218_i53:b" )
			)
			( pin "R7A16.1"
				( objectStatus "@baseboard_fab2_lib.baseboard_fab2(sch_1):page218_i54:a" )
			)
			( pin "R7A16.2"
				( objectStatus "@baseboard_fab2_lib.baseboard_fab2(sch_1):page218_i54:b" )
			)
			( pin "C7A35.1"
				( objectStatus "@baseboard_fab2_lib.baseboard_fab2(sch_1):page218_i55:a" )
			)
			( pin "C7A35.2"
				( objectStatus "@baseboard_fab2_lib.baseboard_fab2(sch_1):page218_i55:b" )
			)
			( pin "R3L9.1"
				( objectStatus "@baseboard_fab2_lib.baseboard_fab2(sch_1):page218_i57:a" )
			)
			( pin "R3L9.2"
				( objectStatus "@baseboard_fab2_lib.baseboard_fab2(sch_1):page218_i57:b" )
			)
			( pin "R3M6.1"
				( objectStatus "@baseboard_fab2_lib.baseboard_fab2(sch_1):page218_i59:a" )
			)
			( pin "R3M6.2"
				( objectStatus "@baseboard_fab2_lib.baseboard_fab2(sch_1):page218_i59:b" )
			)
			( pin "R7A7.1"
				( objectStatus "@baseboard_fab2_lib.baseboard_fab2(sch_1):page218_i60:a" )
			)
			( pin "R7A7.2"
				( objectStatus "@baseboard_fab2_lib.baseboard_fab2(sch_1):page218_i60:b" )
			)
			( pin "C7A28.1"
				( objectStatus "@baseboard_fab2_lib.baseboard_fab2(sch_1):page218_i61:a" )
			)
			( pin "C7A28.2"
				( objectStatus "@baseboard_fab2_lib.baseboard_fab2(sch_1):page218_i61:b" )
			)
			( pin "EU7A5.21"
				( objectStatus "@baseboard_fab2_lib.baseboard_fab2(sch_1):page218_i75:airef1" )
			)
			( pin "EU7A5.23"
				( objectStatus "@baseboard_fab2_lib.baseboard_fab2(sch_1):page218_i75:airef2" )
			)
			( pin "EU7A5.25"
				( objectStatus "@baseboard_fab2_lib.baseboard_fab2(sch_1):page218_i75:airef3" )
			)
			( pin "EU7A5.22"
				( objectStatus "@baseboard_fab2_lib.baseboard_fab2(sch_1):page218_i75:aisen1" )
			)
			( pin "EU7A5.24"
				( objectStatus "@baseboard_fab2_lib.baseboard_fab2(sch_1):page218_i75:aisen2" )
			)
			( pin "EU7A5.26"
				( objectStatus "@baseboard_fab2_lib.baseboard_fab2(sch_1):page218_i75:aisen3" )
			)
			( pin "EU7A5.5"
				( objectStatus "@baseboard_fab2_lib.baseboard_fab2(sch_1):page218_i75:apwm1" )
			)
			( pin "EU7A5.4"
				( objectStatus "@baseboard_fab2_lib.baseboard_fab2(sch_1):page218_i75:apwm2" )
			)
			( pin "EU7A5.3"
				( objectStatus "@baseboard_fab2_lib.baseboard_fab2(sch_1):page218_i75:apwm3" )
			)
			( pin "EU7A5.35"
				( objectStatus "@baseboard_fab2_lib.baseboard_fab2(sch_1):page218_i75:atsen" )
			)
			( pin "EU7A5.20"
				( objectStatus "@baseboard_fab2_lib.baseboard_fab2(sch_1):page218_i75:avref" )
			)
			( pin "EU7A5.10"
				( objectStatus "@baseboard_fab2_lib.baseboard_fab2(sch_1):page218_i75:avren" )
			)
			( pin "EU7A5.9"
				( objectStatus "@baseboard_fab2_lib.baseboard_fab2(sch_1):page218_i75:avrrdy" )
			)
			( pin "EU7A5.19"
				( objectStatus "@baseboard_fab2_lib.baseboard_fab2(sch_1):page218_i75:avsen" )
			)
			( pin "EU7A5.31"
				( objectStatus "@baseboard_fab2_lib.baseboard_fab2(sch_1):page218_i75:biref1" )
			)
			( pin "EU7A5.32"
				( objectStatus "@baseboard_fab2_lib.baseboard_fab2(sch_1):page218_i75:bisen1" )
			)
			( pin "EU7A5.1"
				( objectStatus "@baseboard_fab2_lib.baseboard_fab2(sch_1):page218_i75:bpwm1" )
			)
			( pin "EU7A5.34"
				( objectStatus "@baseboard_fab2_lib.baseboard_fab2(sch_1):page218_i75:btsen" )
			)
			( pin "EU7A5.30"
				( objectStatus "@baseboard_fab2_lib.baseboard_fab2(sch_1):page218_i75:bvref" )
			)
			( pin "EU7A5.29"
				( objectStatus "@baseboard_fab2_lib.baseboard_fab2(sch_1):page218_i75:bvsen" )
			)
			( pin "EU7A5.2"
				( objectStatus "@baseboard_fab2_lib.baseboard_fab2(sch_1):page218_i75:dnc(0)" )
			)
			( pin "EU7A5.28"
				( objectStatus "@baseboard_fab2_lib.baseboard_fab2(sch_1):page218_i75:dnc(1)" )
			)
			( pin "EU7A5.27"
				( objectStatus "@baseboard_fab2_lib.baseboard_fab2(sch_1):page218_i75:gnd" )
			)
			( pin "EU7A5.38"
				( objectStatus "@baseboard_fab2_lib.baseboard_fab2(sch_1):page218_i75:iinsen" )
			)
			( pin "EU7A5.13"
				( objectStatus "@baseboard_fab2_lib.baseboard_fab2(sch_1):page218_i75:mp0" )
			)
			( pin "EU7A5.14"
				( objectStatus "@baseboard_fab2_lib.baseboard_fab2(sch_1):page218_i75:mp1" )
			)
			( pin "EU7A5.18"
				( objectStatus "@baseboard_fab2_lib.baseboard_fab2(sch_1):page218_i75:mp2" )
			)
			( pin "EU7A5.12"
				( objectStatus "@baseboard_fab2_lib.baseboard_fab2(sch_1):page218_i75:pinalrt_n" )
			)
			( pin "EU7A5.8"
				( objectStatus "@baseboard_fab2_lib.baseboard_fab2(sch_1):page218_i75:reset_n" )
			)
			( pin "EU7A5.7"
				( objectStatus "@baseboard_fab2_lib.baseboard_fab2(sch_1):page218_i75:scl" )
			)
			( pin "EU7A5.6"
				( objectStatus "@baseboard_fab2_lib.baseboard_fab2(sch_1):page218_i75:sda" )
			)
			( pin "EU7A5.41"
				( objectStatus "@baseboard_fab2_lib.baseboard_fab2(sch_1):page218_i75:thpad" )
			)
			( pin "EU7A5.17"
				( objectStatus "@baseboard_fab2_lib.baseboard_fab2(sch_1):page218_i75:valrt_n" )
			)
			( pin "EU7A5.15"
				( objectStatus "@baseboard_fab2_lib.baseboard_fab2(sch_1):page218_i75:vclk" )
			)
			( pin "EU7A5.40"
				( objectStatus "@baseboard_fab2_lib.baseboard_fab2(sch_1):page218_i75:vd12" )
			)
			( pin "EU7A5.39"
				( objectStatus "@baseboard_fab2_lib.baseboard_fab2(sch_1):page218_i75:vdd" )
			)
			( pin "EU7A5.16"
				( objectStatus "@baseboard_fab2_lib.baseboard_fab2(sch_1):page218_i75:vdio" )
			)
			( pin "EU7A5.37"
				( objectStatus "@baseboard_fab2_lib.baseboard_fab2(sch_1):page218_i75:vinsen" )
			)
			( pin "EU7A5.11"
				( objectStatus "@baseboard_fab2_lib.baseboard_fab2(sch_1):page218_i75:vrhot_n" )
			)
			( pin "EU7A5.36"
				( objectStatus "@baseboard_fab2_lib.baseboard_fab2(sch_1):page218_i75:xaddr1" )
			)
			( pin "EU7A5.33"
				( objectStatus "@baseboard_fab2_lib.baseboard_fab2(sch_1):page218_i75:xaddr2" )
			)
			( pin "C3L31.1"
				( objectStatus "@baseboard_fab2_lib.baseboard_fab2(sch_1):page218_i77:a" )
			)
			( pin "C3L31.2"
				( objectStatus "@baseboard_fab2_lib.baseboard_fab2(sch_1):page218_i77:b" )
			)
			( pin "C7A12.1"
				( objectStatus "@baseboard_fab2_lib.baseboard_fab2(sch_1):page219_i44:a" )
			)
			( pin "C7A12.2"
				( objectStatus "@baseboard_fab2_lib.baseboard_fab2(sch_1):page219_i44:b" )
			)
			( pin "C3L2.1"
				( objectStatus "@baseboard_fab2_lib.baseboard_fab2(sch_1):page219_i45:a" )
			)
			( pin "C3L2.2"
				( objectStatus "@baseboard_fab2_lib.baseboard_fab2(sch_1):page219_i45:b" )
			)
			( pin "C3L4.1"
				( objectStatus "@baseboard_fab2_lib.baseboard_fab2(sch_1):page219_i46:a" )
			)
			( pin "C3L4.2"
				( objectStatus "@baseboard_fab2_lib.baseboard_fab2(sch_1):page219_i46:b" )
			)
			( pin "C3L13.1"
				( objectStatus "@baseboard_fab2_lib.baseboard_fab2(sch_1):page219_i47:a" )
			)
			( pin "C3L13.2"
				( objectStatus "@baseboard_fab2_lib.baseboard_fab2(sch_1):page219_i47:b" )
			)
			( pin "C7A11.1"
				( objectStatus "@baseboard_fab2_lib.baseboard_fab2(sch_1):page219_i48:a" )
			)
			( pin "C7A11.2"
				( objectStatus "@baseboard_fab2_lib.baseboard_fab2(sch_1):page219_i48:b" )
			)
			( pin "C7A16.1"
				( objectStatus "@baseboard_fab2_lib.baseboard_fab2(sch_1):page219_i50:a" )
			)
			( pin "C7A16.2"
				( objectStatus "@baseboard_fab2_lib.baseboard_fab2(sch_1):page219_i50:b" )
			)
			( pin "C7A5.1"
				( objectStatus "@baseboard_fab2_lib.baseboard_fab2(sch_1):page219_i51:a" )
			)
			( pin "C7A5.2"
				( objectStatus "@baseboard_fab2_lib.baseboard_fab2(sch_1):page219_i51:b" )
			)
			( pin "R3L6.1"
				( objectStatus "@baseboard_fab2_lib.baseboard_fab2(sch_1):page219_i52:a" )
			)
			( pin "R3L6.2"
				( objectStatus "@baseboard_fab2_lib.baseboard_fab2(sch_1):page219_i52:b" )
			)
			( pin "C7A18.1"
				( objectStatus "@baseboard_fab2_lib.baseboard_fab2(sch_1):page219_i53:a" )
			)
			( pin "C7A18.2"
				( objectStatus "@baseboard_fab2_lib.baseboard_fab2(sch_1):page219_i53:b" )
			)
			( pin "C7A17.1"
				( objectStatus "@baseboard_fab2_lib.baseboard_fab2(sch_1):page219_i54:a" )
			)
			( pin "C7A17.2"
				( objectStatus "@baseboard_fab2_lib.baseboard_fab2(sch_1):page219_i54:b" )
			)
			( pin "L7A1.1"
				( objectStatus "@baseboard_fab2_lib.baseboard_fab2(sch_1):page219_i55:ina" )
			)
			( pin "L7A1.2"
				( objectStatus "@baseboard_fab2_lib.baseboard_fab2(sch_1):page219_i55:inb" )
			)
			( pin "L7A3.1"
				( objectStatus "@baseboard_fab2_lib.baseboard_fab2(sch_1):page219_i65:ina" )
			)
			( pin "L7A3.2"
				( objectStatus "@baseboard_fab2_lib.baseboard_fab2(sch_1):page219_i65:inb" )
			)
			( pin "C6A4.1"
				( objectStatus "@baseboard_fab2_lib.baseboard_fab2(sch_1):page219_i68:a" )
			)
			( pin "C6A4.2"
				( objectStatus "@baseboard_fab2_lib.baseboard_fab2(sch_1):page219_i68:b" )
			)
			( pin "C7A25.1"
				( objectStatus "@baseboard_fab2_lib.baseboard_fab2(sch_1):page219_i72:a" )
			)
			( pin "C7A25.2"
				( objectStatus "@baseboard_fab2_lib.baseboard_fab2(sch_1):page219_i72:b" )
			)
			( pin "C7A26.1"
				( objectStatus "@baseboard_fab2_lib.baseboard_fab2(sch_1):page219_i73:a" )
			)
			( pin "C7A26.2"
				( objectStatus "@baseboard_fab2_lib.baseboard_fab2(sch_1):page219_i73:b" )
			)
			( pin "C7A22.1"
				( objectStatus "@baseboard_fab2_lib.baseboard_fab2(sch_1):page219_i75:a" )
			)
			( pin "C7A22.2"
				( objectStatus "@baseboard_fab2_lib.baseboard_fab2(sch_1):page219_i75:b" )
			)
			( pin "R3L8.1"
				( objectStatus "@baseboard_fab2_lib.baseboard_fab2(sch_1):page219_i76:a" )
			)
			( pin "R3L8.2"
				( objectStatus "@baseboard_fab2_lib.baseboard_fab2(sch_1):page219_i76:b" )
			)
			( pin "C7A24.1"
				( objectStatus "@baseboard_fab2_lib.baseboard_fab2(sch_1):page219_i77:a" )
			)
			( pin "C7A24.2"
				( objectStatus "@baseboard_fab2_lib.baseboard_fab2(sch_1):page219_i77:b" )
			)
			( pin "C7A20.1"
				( objectStatus "@baseboard_fab2_lib.baseboard_fab2(sch_1):page219_i78:a" )
			)
			( pin "C7A20.2"
				( objectStatus "@baseboard_fab2_lib.baseboard_fab2(sch_1):page219_i78:b" )
			)
			( pin "C7A21.1"
				( objectStatus "@baseboard_fab2_lib.baseboard_fab2(sch_1):page219_i79:a" )
			)
			( pin "C7A21.2"
				( objectStatus "@baseboard_fab2_lib.baseboard_fab2(sch_1):page219_i79:b" )
			)
			( pin "C3L17.1"
				( objectStatus "@baseboard_fab2_lib.baseboard_fab2(sch_1):page219_i80:a" )
			)
			( pin "C3L17.2"
				( objectStatus "@baseboard_fab2_lib.baseboard_fab2(sch_1):page219_i80:b" )
			)
			( pin "C3L16.1"
				( objectStatus "@baseboard_fab2_lib.baseboard_fab2(sch_1):page219_i81:a" )
			)
			( pin "C3L16.2"
				( objectStatus "@baseboard_fab2_lib.baseboard_fab2(sch_1):page219_i81:b" )
			)
			( pin "C3L15.1"
				( objectStatus "@baseboard_fab2_lib.baseboard_fab2(sch_1):page219_i84:a" )
			)
			( pin "C3L15.2"
				( objectStatus "@baseboard_fab2_lib.baseboard_fab2(sch_1):page219_i84:b" )
			)
			( pin "C6A1.1"
				( objectStatus "@baseboard_fab2_lib.baseboard_fab2(sch_1):page219_i87:a" )
			)
			( pin "C6A1.2"
				( objectStatus "@baseboard_fab2_lib.baseboard_fab2(sch_1):page219_i87:b" )
			)
			( pin "EU7A1.33"
				( objectStatus "@baseboard_fab2_lib.baseboard_fab2(sch_1):page219_i106:boost" )
			)
			( pin "EU7A1.35"
				( objectStatus "@baseboard_fab2_lib.baseboard_fab2(sch_1):page219_i106:en" )
			)
			( pin "EU7A1.6"
				( objectStatus "@baseboard_fab2_lib.baseboard_fab2(sch_1):page219_i106:gl(0)" )
			)
			( pin "EU7A1.41"
				( objectStatus "@baseboard_fab2_lib.baseboard_fab2(sch_1):page219_i106:gl(1)" )
			)
			( pin "EU7A1.38"
				( objectStatus "@baseboard_fab2_lib.baseboard_fab2(sch_1):page219_i106:iout" )
			)
			( pin "EU7A1.2"
				( objectStatus "@baseboard_fab2_lib.baseboard_fab2(sch_1):page219_i106:lgnd" )
			)
			( pin "EU7A1.31"
				( objectStatus "@baseboard_fab2_lib.baseboard_fab2(sch_1):page219_i106:nc" )
			)
			( pin "EU7A1.37"
				( objectStatus "@baseboard_fab2_lib.baseboard_fab2(sch_1):page219_i106:ocset" )
			)
			( pin "EU7A1.5"
				( objectStatus "@baseboard_fab2_lib.baseboard_fab2(sch_1):page219_i106:pgnd(0)" )
			)
			( pin "EU7A1.7"
				( objectStatus "@baseboard_fab2_lib.baseboard_fab2(sch_1):page219_i106:pgnd(1)" )
			)
			( pin "EU7A1.40"
				( objectStatus "@baseboard_fab2_lib.baseboard_fab2(sch_1):page219_i106:pgnd(2)" )
			)
			( pin "EU7A1.32"
				( objectStatus "@baseboard_fab2_lib.baseboard_fab2(sch_1):page219_i106:phase" )
			)
			( pin "EU7A1.34"
				( objectStatus "@baseboard_fab2_lib.baseboard_fab2(sch_1):page219_i106:pwm" )
			)
			( pin "EU7A1.39"
				( objectStatus "@baseboard_fab2_lib.baseboard_fab2(sch_1):page219_i106:refin" )
			)
			( pin "EU7A1.10"
				( objectStatus "@baseboard_fab2_lib.baseboard_fab2(sch_1):page219_i106:sw" )
			)
			( pin "EU7A1.36"
				( objectStatus "@baseboard_fab2_lib.baseboard_fab2(sch_1):page219_i106:tout_flt" )
			)
			( pin "EU7A1.3"
				( objectStatus "@baseboard_fab2_lib.baseboard_fab2(sch_1):page219_i106:vcc" )
			)
			( pin "EU7A1.4"
				( objectStatus "@baseboard_fab2_lib.baseboard_fab2(sch_1):page219_i106:vdrv" )
			)
			( pin "EU7A1.25"
				( objectStatus "@baseboard_fab2_lib.baseboard_fab2(sch_1):page219_i106:vin(0)" )
			)
			( pin "EU7A1.30"
				( objectStatus "@baseboard_fab2_lib.baseboard_fab2(sch_1):page219_i106:vin(1)" )
			)
			( pin "EU7A1.1"
				( objectStatus "@baseboard_fab2_lib.baseboard_fab2(sch_1):page219_i106:vos" )
			)
			( pin "EU7A4.33"
				( objectStatus "@baseboard_fab2_lib.baseboard_fab2(sch_1):page219_i107:boost" )
			)
			( pin "EU7A4.35"
				( objectStatus "@baseboard_fab2_lib.baseboard_fab2(sch_1):page219_i107:en" )
			)
			( pin "EU7A4.6"
				( objectStatus "@baseboard_fab2_lib.baseboard_fab2(sch_1):page219_i107:gl(0)" )
			)
			( pin "EU7A4.41"
				( objectStatus "@baseboard_fab2_lib.baseboard_fab2(sch_1):page219_i107:gl(1)" )
			)
			( pin "EU7A4.38"
				( objectStatus "@baseboard_fab2_lib.baseboard_fab2(sch_1):page219_i107:iout" )
			)
			( pin "EU7A4.2"
				( objectStatus "@baseboard_fab2_lib.baseboard_fab2(sch_1):page219_i107:lgnd" )
			)
			( pin "EU7A4.31"
				( objectStatus "@baseboard_fab2_lib.baseboard_fab2(sch_1):page219_i107:nc" )
			)
			( pin "EU7A4.37"
				( objectStatus "@baseboard_fab2_lib.baseboard_fab2(sch_1):page219_i107:ocset" )
			)
			( pin "EU7A4.5"
				( objectStatus "@baseboard_fab2_lib.baseboard_fab2(sch_1):page219_i107:pgnd(0)" )
			)
			( pin "EU7A4.7"
				( objectStatus "@baseboard_fab2_lib.baseboard_fab2(sch_1):page219_i107:pgnd(1)" )
			)
			( pin "EU7A4.40"
				( objectStatus "@baseboard_fab2_lib.baseboard_fab2(sch_1):page219_i107:pgnd(2)" )
			)
			( pin "EU7A4.32"
				( objectStatus "@baseboard_fab2_lib.baseboard_fab2(sch_1):page219_i107:phase" )
			)
			( pin "EU7A4.34"
				( objectStatus "@baseboard_fab2_lib.baseboard_fab2(sch_1):page219_i107:pwm" )
			)
			( pin "EU7A4.39"
				( objectStatus "@baseboard_fab2_lib.baseboard_fab2(sch_1):page219_i107:refin" )
			)
			( pin "EU7A4.10"
				( objectStatus "@baseboard_fab2_lib.baseboard_fab2(sch_1):page219_i107:sw" )
			)
			( pin "EU7A4.36"
				( objectStatus "@baseboard_fab2_lib.baseboard_fab2(sch_1):page219_i107:tout_flt" )
			)
			( pin "EU7A4.3"
				( objectStatus "@baseboard_fab2_lib.baseboard_fab2(sch_1):page219_i107:vcc" )
			)
			( pin "EU7A4.4"
				( objectStatus "@baseboard_fab2_lib.baseboard_fab2(sch_1):page219_i107:vdrv" )
			)
			( pin "EU7A4.25"
				( objectStatus "@baseboard_fab2_lib.baseboard_fab2(sch_1):page219_i107:vin(0)" )
			)
			( pin "EU7A4.30"
				( objectStatus "@baseboard_fab2_lib.baseboard_fab2(sch_1):page219_i107:vin(1)" )
			)
			( pin "EU7A4.1"
				( objectStatus "@baseboard_fab2_lib.baseboard_fab2(sch_1):page219_i107:vos" )
			)
			( pin "R7A20.1"
				( objectStatus "@baseboard_fab2_lib.baseboard_fab2(sch_1):page219_i108:a" )
			)
			( pin "R7A20.2"
				( objectStatus "@baseboard_fab2_lib.baseboard_fab2(sch_1):page219_i108:b" )
			)
			( pin "R7A21.1"
				( objectStatus "@baseboard_fab2_lib.baseboard_fab2(sch_1):page219_i110:a" )
			)
			( pin "R7A21.2"
				( objectStatus "@baseboard_fab2_lib.baseboard_fab2(sch_1):page219_i110:b" )
			)
			( pin "R4L4.1"
				( objectStatus "@baseboard_fab2_lib.baseboard_fab2(sch_1):page220_i58:a" )
			)
			( pin "R4L4.2"
				( objectStatus "@baseboard_fab2_lib.baseboard_fab2(sch_1):page220_i58:b" )
			)
			( pin "R4L2.1"
				( objectStatus "@baseboard_fab2_lib.baseboard_fab2(sch_1):page220_i74:a" )
			)
			( pin "R4L2.2"
				( objectStatus "@baseboard_fab2_lib.baseboard_fab2(sch_1):page220_i74:b" )
			)
			( pin "C3L6.1"
				( objectStatus "@baseboard_fab2_lib.baseboard_fab2(sch_1):page220_i75:a" )
			)
			( pin "C3L6.2"
				( objectStatus "@baseboard_fab2_lib.baseboard_fab2(sch_1):page220_i75:b" )
			)
			( pin "C3L14.1"
				( objectStatus "@baseboard_fab2_lib.baseboard_fab2(sch_1):page220_i76:a" )
			)
			( pin "C3L14.2"
				( objectStatus "@baseboard_fab2_lib.baseboard_fab2(sch_1):page220_i76:b" )
			)
			( pin "C6A5.1"
				( objectStatus "@baseboard_fab2_lib.baseboard_fab2(sch_1):page220_i77:a" )
			)
			( pin "C6A5.2"
				( objectStatus "@baseboard_fab2_lib.baseboard_fab2(sch_1):page220_i77:b" )
			)
			( pin "C4L5.1"
				( objectStatus "@baseboard_fab2_lib.baseboard_fab2(sch_1):page220_i78:a" )
			)
			( pin "C4L5.2"
				( objectStatus "@baseboard_fab2_lib.baseboard_fab2(sch_1):page220_i78:b" )
			)
			( pin "C5M8.1"
				( objectStatus "@baseboard_fab2_lib.baseboard_fab2(sch_1):page220_i82:a" )
			)
			( pin "C5M8.2"
				( objectStatus "@baseboard_fab2_lib.baseboard_fab2(sch_1):page220_i82:b" )
			)
			( pin "C5L14.1"
				( objectStatus "@baseboard_fab2_lib.baseboard_fab2(sch_1):page220_i83:a" )
			)
			( pin "C5L14.2"
				( objectStatus "@baseboard_fab2_lib.baseboard_fab2(sch_1):page220_i83:b" )
			)
			( pin "C5M12.1"
				( objectStatus "@baseboard_fab2_lib.baseboard_fab2(sch_1):page220_i88:a" )
			)
			( pin "C5M12.2"
				( objectStatus "@baseboard_fab2_lib.baseboard_fab2(sch_1):page220_i88:b" )
			)
			( pin "C5L3.1"
				( objectStatus "@baseboard_fab2_lib.baseboard_fab2(sch_1):page220_i89:a" )
			)
			( pin "C5L3.2"
				( objectStatus "@baseboard_fab2_lib.baseboard_fab2(sch_1):page220_i89:b" )
			)
			( pin "C5L2.1"
				( objectStatus "@baseboard_fab2_lib.baseboard_fab2(sch_1):page220_i90:a" )
			)
			( pin "C5L2.2"
				( objectStatus "@baseboard_fab2_lib.baseboard_fab2(sch_1):page220_i90:b" )
			)
			( pin "C5L1.1"
				( objectStatus "@baseboard_fab2_lib.baseboard_fab2(sch_1):page220_i91:a" )
			)
			( pin "C5L1.2"
				( objectStatus "@baseboard_fab2_lib.baseboard_fab2(sch_1):page220_i91:b" )
			)
			( pin "C5A20.1"
				( objectStatus "@baseboard_fab2_lib.baseboard_fab2(sch_1):page220_i92:a" )
			)
			( pin "C5A20.2"
				( objectStatus "@baseboard_fab2_lib.baseboard_fab2(sch_1):page220_i92:b" )
			)
			( pin "C5A10.1"
				( objectStatus "@baseboard_fab2_lib.baseboard_fab2(sch_1):page220_i110:a" )
			)
			( pin "C5A10.2"
				( objectStatus "@baseboard_fab2_lib.baseboard_fab2(sch_1):page220_i110:b" )
			)
			( pin "L7A5.1"
				( objectStatus "@baseboard_fab2_lib.baseboard_fab2(sch_1):page220_i124:ina" )
			)
			( pin "L7A5.2"
				( objectStatus "@baseboard_fab2_lib.baseboard_fab2(sch_1):page220_i124:inb" )
			)
			( pin "C7A19.1"
				( objectStatus "@baseboard_fab2_lib.baseboard_fab2(sch_1):page220_i175:a" )
			)
			( pin "C7A19.2"
				( objectStatus "@baseboard_fab2_lib.baseboard_fab2(sch_1):page220_i175:b" )
			)
			( pin "C5P2.1"
				( objectStatus "@baseboard_fab2_lib.baseboard_fab2(sch_1):page220_i177:a" )
			)
			( pin "C5P2.2"
				( objectStatus "@baseboard_fab2_lib.baseboard_fab2(sch_1):page220_i177:b" )
			)
			( pin "C5P1.1"
				( objectStatus "@baseboard_fab2_lib.baseboard_fab2(sch_1):page220_i179:a" )
			)
			( pin "C5P1.2"
				( objectStatus "@baseboard_fab2_lib.baseboard_fab2(sch_1):page220_i179:b" )
			)
			( pin "C5D9.1"
				( objectStatus "@baseboard_fab2_lib.baseboard_fab2(sch_1):page220_i180:a" )
			)
			( pin "C5D9.2"
				( objectStatus "@baseboard_fab2_lib.baseboard_fab2(sch_1):page220_i180:b" )
			)
			( pin "C5D6.1"
				( objectStatus "@baseboard_fab2_lib.baseboard_fab2(sch_1):page220_i182:a" )
			)
			( pin "C5D6.2"
				( objectStatus "@baseboard_fab2_lib.baseboard_fab2(sch_1):page220_i182:b" )
			)
			( pin "C5D7.1"
				( objectStatus "@baseboard_fab2_lib.baseboard_fab2(sch_1):page220_i183:a" )
			)
			( pin "C5D7.2"
				( objectStatus "@baseboard_fab2_lib.baseboard_fab2(sch_1):page220_i183:b" )
			)
			( pin "C5D8.1"
				( objectStatus "@baseboard_fab2_lib.baseboard_fab2(sch_1):page220_i184:a" )
			)
			( pin "C5D8.2"
				( objectStatus "@baseboard_fab2_lib.baseboard_fab2(sch_1):page220_i184:b" )
			)
			( pin "C5L15.1"
				( objectStatus "@baseboard_fab2_lib.baseboard_fab2(sch_1):page220_i192:a" )
			)
			( pin "C5L15.2"
				( objectStatus "@baseboard_fab2_lib.baseboard_fab2(sch_1):page220_i192:b" )
			)
			( pin "C5A5.1"
				( objectStatus "@baseboard_fab2_lib.baseboard_fab2(sch_1):page220_i193:a" )
			)
			( pin "C5A5.2"
				( objectStatus "@baseboard_fab2_lib.baseboard_fab2(sch_1):page220_i193:b" )
			)
			( pin "C5B1.1"
				( objectStatus "@baseboard_fab2_lib.baseboard_fab2(sch_1):page220_i194:a" )
			)
			( pin "C5B1.2"
				( objectStatus "@baseboard_fab2_lib.baseboard_fab2(sch_1):page220_i194:b" )
			)
			( pin "C5M9.1"
				( objectStatus "@baseboard_fab2_lib.baseboard_fab2(sch_1):page220_i195:a" )
			)
			( pin "C5M9.2"
				( objectStatus "@baseboard_fab2_lib.baseboard_fab2(sch_1):page220_i195:b" )
			)
			( pin "C4M5.1"
				( objectStatus "@baseboard_fab2_lib.baseboard_fab2(sch_1):page220_i196:a" )
			)
			( pin "C4M5.2"
				( objectStatus "@baseboard_fab2_lib.baseboard_fab2(sch_1):page220_i196:b" )
			)
			( pin "C5B2.1"
				( objectStatus "@baseboard_fab2_lib.baseboard_fab2(sch_1):page220_i197:a" )
			)
			( pin "C5B2.2"
				( objectStatus "@baseboard_fab2_lib.baseboard_fab2(sch_1):page220_i197:b" )
			)
			( pin "C5M10.1"
				( objectStatus "@baseboard_fab2_lib.baseboard_fab2(sch_1):page220_i198:a" )
			)
			( pin "C5M10.2"
				( objectStatus "@baseboard_fab2_lib.baseboard_fab2(sch_1):page220_i198:b" )
			)
			( pin "C5M3.1"
				( objectStatus "@baseboard_fab2_lib.baseboard_fab2(sch_1):page220_i199:a" )
			)
			( pin "C5M3.2"
				( objectStatus "@baseboard_fab2_lib.baseboard_fab2(sch_1):page220_i199:b" )
			)
			( pin "C5M11.1"
				( objectStatus "@baseboard_fab2_lib.baseboard_fab2(sch_1):page220_i200:a" )
			)
			( pin "C5M11.2"
				( objectStatus "@baseboard_fab2_lib.baseboard_fab2(sch_1):page220_i200:b" )
			)
			( pin "C5A19.1"
				( objectStatus "@baseboard_fab2_lib.baseboard_fab2(sch_1):page220_i203:a" )
			)
			( pin "C5A19.2"
				( objectStatus "@baseboard_fab2_lib.baseboard_fab2(sch_1):page220_i203:b" )
			)
			( pin "C5A18.1"
				( objectStatus "@baseboard_fab2_lib.baseboard_fab2(sch_1):page220_i204:a" )
			)
			( pin "C5A18.2"
				( objectStatus "@baseboard_fab2_lib.baseboard_fab2(sch_1):page220_i204:b" )
			)
			( pin "C5A17.1"
				( objectStatus "@baseboard_fab2_lib.baseboard_fab2(sch_1):page220_i205:a" )
			)
			( pin "C5A17.2"
				( objectStatus "@baseboard_fab2_lib.baseboard_fab2(sch_1):page220_i205:b" )
			)
			( pin "C5A4.1"
				( objectStatus "@baseboard_fab2_lib.baseboard_fab2(sch_1):page220_i206:a" )
			)
			( pin "C5A4.2"
				( objectStatus "@baseboard_fab2_lib.baseboard_fab2(sch_1):page220_i206:b" )
			)
			( pin "C5A16.1"
				( objectStatus "@baseboard_fab2_lib.baseboard_fab2(sch_1):page220_i207:a" )
			)
			( pin "C5A16.2"
				( objectStatus "@baseboard_fab2_lib.baseboard_fab2(sch_1):page220_i207:b" )
			)
			( pin "C5A9.1"
				( objectStatus "@baseboard_fab2_lib.baseboard_fab2(sch_1):page220_i208:a" )
			)
			( pin "C5A9.2"
				( objectStatus "@baseboard_fab2_lib.baseboard_fab2(sch_1):page220_i208:b" )
			)
			( pin "C5A8.1"
				( objectStatus "@baseboard_fab2_lib.baseboard_fab2(sch_1):page220_i209:a" )
			)
			( pin "C5A8.2"
				( objectStatus "@baseboard_fab2_lib.baseboard_fab2(sch_1):page220_i209:b" )
			)
			( pin "C5A3.1"
				( objectStatus "@baseboard_fab2_lib.baseboard_fab2(sch_1):page220_i210:a" )
			)
			( pin "C5A3.2"
				( objectStatus "@baseboard_fab2_lib.baseboard_fab2(sch_1):page220_i210:b" )
			)
			( pin "C5A7.1"
				( objectStatus "@baseboard_fab2_lib.baseboard_fab2(sch_1):page220_i211:a" )
			)
			( pin "C5A7.2"
				( objectStatus "@baseboard_fab2_lib.baseboard_fab2(sch_1):page220_i211:b" )
			)
			( pin "C5A6.1"
				( objectStatus "@baseboard_fab2_lib.baseboard_fab2(sch_1):page220_i212:a" )
			)
			( pin "C5A6.2"
				( objectStatus "@baseboard_fab2_lib.baseboard_fab2(sch_1):page220_i212:b" )
			)
			( pin "C5A14.1"
				( objectStatus "@baseboard_fab2_lib.baseboard_fab2(sch_1):page220_i213:a" )
			)
			( pin "C5A14.2"
				( objectStatus "@baseboard_fab2_lib.baseboard_fab2(sch_1):page220_i213:b" )
			)
			( pin "C5A2.1"
				( objectStatus "@baseboard_fab2_lib.baseboard_fab2(sch_1):page220_i214:a" )
			)
			( pin "C5A2.2"
				( objectStatus "@baseboard_fab2_lib.baseboard_fab2(sch_1):page220_i214:b" )
			)
			( pin "C5A13.1"
				( objectStatus "@baseboard_fab2_lib.baseboard_fab2(sch_1):page220_i215:a" )
			)
			( pin "C5A13.2"
				( objectStatus "@baseboard_fab2_lib.baseboard_fab2(sch_1):page220_i215:b" )
			)
			( pin "C5A12.1"
				( objectStatus "@baseboard_fab2_lib.baseboard_fab2(sch_1):page220_i216:a" )
			)
			( pin "C5A12.2"
				( objectStatus "@baseboard_fab2_lib.baseboard_fab2(sch_1):page220_i216:b" )
			)
			( pin "C5A15.1"
				( objectStatus "@baseboard_fab2_lib.baseboard_fab2(sch_1):page220_i217:a" )
			)
			( pin "C5A15.2"
				( objectStatus "@baseboard_fab2_lib.baseboard_fab2(sch_1):page220_i217:b" )
			)
			( pin "C5A1.1"
				( objectStatus "@baseboard_fab2_lib.baseboard_fab2(sch_1):page220_i219:a" )
			)
			( pin "C5A1.2"
				( objectStatus "@baseboard_fab2_lib.baseboard_fab2(sch_1):page220_i219:b" )
			)
			( pin "C5A11.1"
				( objectStatus "@baseboard_fab2_lib.baseboard_fab2(sch_1):page220_i221:a" )
			)
			( pin "C5A11.2"
				( objectStatus "@baseboard_fab2_lib.baseboard_fab2(sch_1):page220_i221:b" )
			)
			( pin "C4M2.1"
				( objectStatus "@baseboard_fab2_lib.baseboard_fab2(sch_1):page220_i222:a" )
			)
			( pin "C4M2.2"
				( objectStatus "@baseboard_fab2_lib.baseboard_fab2(sch_1):page220_i222:b" )
			)
			( pin "C5M1.1"
				( objectStatus "@baseboard_fab2_lib.baseboard_fab2(sch_1):page220_i223:a" )
			)
			( pin "C5M1.2"
				( objectStatus "@baseboard_fab2_lib.baseboard_fab2(sch_1):page220_i223:b" )
			)
			( pin "C5M2.1"
				( objectStatus "@baseboard_fab2_lib.baseboard_fab2(sch_1):page220_i224:a" )
			)
			( pin "C5M2.2"
				( objectStatus "@baseboard_fab2_lib.baseboard_fab2(sch_1):page220_i224:b" )
			)
			( pin "C5M4.1"
				( objectStatus "@baseboard_fab2_lib.baseboard_fab2(sch_1):page220_i225:a" )
			)
			( pin "C5M4.2"
				( objectStatus "@baseboard_fab2_lib.baseboard_fab2(sch_1):page220_i225:b" )
			)
			( pin "C5M5.1"
				( objectStatus "@baseboard_fab2_lib.baseboard_fab2(sch_1):page220_i226:a" )
			)
			( pin "C5M5.2"
				( objectStatus "@baseboard_fab2_lib.baseboard_fab2(sch_1):page220_i226:b" )
			)
			( pin "C5M6.1"
				( objectStatus "@baseboard_fab2_lib.baseboard_fab2(sch_1):page220_i227:a" )
			)
			( pin "C5M6.2"
				( objectStatus "@baseboard_fab2_lib.baseboard_fab2(sch_1):page220_i227:b" )
			)
			( pin "C5M7.1"
				( objectStatus "@baseboard_fab2_lib.baseboard_fab2(sch_1):page220_i228:a" )
			)
			( pin "C5M7.2"
				( objectStatus "@baseboard_fab2_lib.baseboard_fab2(sch_1):page220_i228:b" )
			)
			( pin "C5L13.1"
				( objectStatus "@baseboard_fab2_lib.baseboard_fab2(sch_1):page220_i229:a" )
			)
			( pin "C5L13.2"
				( objectStatus "@baseboard_fab2_lib.baseboard_fab2(sch_1):page220_i229:b" )
			)
			( pin "C5L12.1"
				( objectStatus "@baseboard_fab2_lib.baseboard_fab2(sch_1):page220_i230:a" )
			)
			( pin "C5L12.2"
				( objectStatus "@baseboard_fab2_lib.baseboard_fab2(sch_1):page220_i230:b" )
			)
			( pin "C5L11.1"
				( objectStatus "@baseboard_fab2_lib.baseboard_fab2(sch_1):page220_i231:a" )
			)
			( pin "C5L11.2"
				( objectStatus "@baseboard_fab2_lib.baseboard_fab2(sch_1):page220_i231:b" )
			)
			( pin "C5L10.1"
				( objectStatus "@baseboard_fab2_lib.baseboard_fab2(sch_1):page220_i232:a" )
			)
			( pin "C5L10.2"
				( objectStatus "@baseboard_fab2_lib.baseboard_fab2(sch_1):page220_i232:b" )
			)
			( pin "C5L9.1"
				( objectStatus "@baseboard_fab2_lib.baseboard_fab2(sch_1):page220_i233:a" )
			)
			( pin "C5L9.2"
				( objectStatus "@baseboard_fab2_lib.baseboard_fab2(sch_1):page220_i233:b" )
			)
			( pin "C5L8.1"
				( objectStatus "@baseboard_fab2_lib.baseboard_fab2(sch_1):page220_i234:a" )
			)
			( pin "C5L8.2"
				( objectStatus "@baseboard_fab2_lib.baseboard_fab2(sch_1):page220_i234:b" )
			)
			( pin "C5L7.1"
				( objectStatus "@baseboard_fab2_lib.baseboard_fab2(sch_1):page220_i236:a" )
			)
			( pin "C5L7.2"
				( objectStatus "@baseboard_fab2_lib.baseboard_fab2(sch_1):page220_i236:b" )
			)
			( pin "C5L6.1"
				( objectStatus "@baseboard_fab2_lib.baseboard_fab2(sch_1):page220_i237:a" )
			)
			( pin "C5L6.2"
				( objectStatus "@baseboard_fab2_lib.baseboard_fab2(sch_1):page220_i237:b" )
			)
			( pin "SH4L2.1"
				( objectStatus "@baseboard_fab2_lib.baseboard_fab2(sch_1):page220_i239:a" )
			)
			( pin "SH4L2.2"
				( objectStatus "@baseboard_fab2_lib.baseboard_fab2(sch_1):page220_i239:b" )
			)
			( pin "SH4L1.1"
				( objectStatus "@baseboard_fab2_lib.baseboard_fab2(sch_1):page220_i240:a" )
			)
			( pin "SH4L1.2"
				( objectStatus "@baseboard_fab2_lib.baseboard_fab2(sch_1):page220_i240:b" )
			)
			( pin "EU4G3.3"
				( objectStatus "@baseboard_fab2_lib.baseboard_fab2(sch_1):page221_i1:agnd" )
			)
			( pin "EU4G3.2"
				( objectStatus "@baseboard_fab2_lib.baseboard_fab2(sch_1):page221_i1:bias" )
			)
			( pin "EU4G3.7"
				( objectStatus "@baseboard_fab2_lib.baseboard_fab2(sch_1):page221_i1:en" )
			)
			( pin "EU4G3.5"
				( objectStatus "@baseboard_fab2_lib.baseboard_fab2(sch_1):page221_i1:pg" )
			)
			( pin "EU4G3.8"
				( objectStatus "@baseboard_fab2_lib.baseboard_fab2(sch_1):page221_i1:pgnd" )
			)
			( pin "EU4G3.6"
				( objectStatus "@baseboard_fab2_lib.baseboard_fab2(sch_1):page221_i1:sns" )
			)
			( pin "EU4G3.11"
				( objectStatus "@baseboard_fab2_lib.baseboard_fab2(sch_1):page221_i1:thpad" )
			)
			( pin "EU4G3.4"
				( objectStatus "@baseboard_fab2_lib.baseboard_fab2(sch_1):page221_i1:vddq" )
			)
			( pin "EU4G3.10"
				( objectStatus "@baseboard_fab2_lib.baseboard_fab2(sch_1):page221_i1:vin" )
			)
			( pin "EU4G3.1"
				( objectStatus "@baseboard_fab2_lib.baseboard_fab2(sch_1):page221_i1:vref" )
			)
			( pin "EU4G3.9"
				( objectStatus "@baseboard_fab2_lib.baseboard_fab2(sch_1):page221_i1:vtt" )
			)
			( pin "C4G14.1"
				( objectStatus "@baseboard_fab2_lib.baseboard_fab2(sch_1):page221_i15:a" )
			)
			( pin "C4G14.2"
				( objectStatus "@baseboard_fab2_lib.baseboard_fab2(sch_1):page221_i15:b" )
			)
			( pin "C4G24.1"
				( objectStatus "@baseboard_fab2_lib.baseboard_fab2(sch_1):page221_i20:a" )
			)
			( pin "C4G24.2"
				( objectStatus "@baseboard_fab2_lib.baseboard_fab2(sch_1):page221_i20:b" )
			)
			( pin "C6U16.1"
				( objectStatus "@baseboard_fab2_lib.baseboard_fab2(sch_1):page221_i22:a" )
			)
			( pin "C6U16.2"
				( objectStatus "@baseboard_fab2_lib.baseboard_fab2(sch_1):page221_i22:b" )
			)
			( pin "C4G15.1"
				( objectStatus "@baseboard_fab2_lib.baseboard_fab2(sch_1):page221_i24:a" )
			)
			( pin "C4G15.2"
				( objectStatus "@baseboard_fab2_lib.baseboard_fab2(sch_1):page221_i24:b" )
			)
			( pin "C6U15.1"
				( objectStatus "@baseboard_fab2_lib.baseboard_fab2(sch_1):page221_i26:a" )
			)
			( pin "C6U15.2"
				( objectStatus "@baseboard_fab2_lib.baseboard_fab2(sch_1):page221_i26:b" )
			)
			( pin "R6U4.1"
				( objectStatus "@baseboard_fab2_lib.baseboard_fab2(sch_1):page221_i28:a" )
			)
			( pin "R6U4.2"
				( objectStatus "@baseboard_fab2_lib.baseboard_fab2(sch_1):page221_i28:b" )
			)
			( pin "R6U5.1"
				( objectStatus "@baseboard_fab2_lib.baseboard_fab2(sch_1):page221_i32:a" )
			)
			( pin "R6U5.2"
				( objectStatus "@baseboard_fab2_lib.baseboard_fab2(sch_1):page221_i32:b" )
			)
			( pin "C4G16.1"
				( objectStatus "@baseboard_fab2_lib.baseboard_fab2(sch_1):page221_i34:a" )
			)
			( pin "C4G16.2"
				( objectStatus "@baseboard_fab2_lib.baseboard_fab2(sch_1):page221_i34:b" )
			)
			( pin "R6U15.1"
				( objectStatus "@baseboard_fab2_lib.baseboard_fab2(sch_1):page221_i37:a" )
			)
			( pin "R6U15.2"
				( objectStatus "@baseboard_fab2_lib.baseboard_fab2(sch_1):page221_i37:b" )
			)
			( pin "R4G23.1"
				( objectStatus "@baseboard_fab2_lib.baseboard_fab2(sch_1):page221_i38:a" )
			)
			( pin "R4G23.2"
				( objectStatus "@baseboard_fab2_lib.baseboard_fab2(sch_1):page221_i38:b" )
			)
			( pin "C4G23.1"
				( objectStatus "@baseboard_fab2_lib.baseboard_fab2(sch_1):page221_i39:a" )
			)
			( pin "C4G23.2"
				( objectStatus "@baseboard_fab2_lib.baseboard_fab2(sch_1):page221_i39:b" )
			)
			( pin "R4G18.1"
				( objectStatus "@baseboard_fab2_lib.baseboard_fab2(sch_1):page221_i45:a" )
			)
			( pin "R4G18.2"
				( objectStatus "@baseboard_fab2_lib.baseboard_fab2(sch_1):page221_i45:b" )
			)
			( pin "C6U12.1"
				( objectStatus "@baseboard_fab2_lib.baseboard_fab2(sch_1):page221_i49:a" )
			)
			( pin "C6U12.2"
				( objectStatus "@baseboard_fab2_lib.baseboard_fab2(sch_1):page221_i49:b" )
			)
			( pin "C5U12.1"
				( objectStatus "@baseboard_fab2_lib.baseboard_fab2(sch_1):page221_i50:a" )
			)
			( pin "C5U12.2"
				( objectStatus "@baseboard_fab2_lib.baseboard_fab2(sch_1):page221_i50:b" )
			)
			( pin "C5T3.1"
				( objectStatus "@baseboard_fab2_lib.baseboard_fab2(sch_1):page221_i51:a" )
			)
			( pin "C5T3.2"
				( objectStatus "@baseboard_fab2_lib.baseboard_fab2(sch_1):page221_i51:b" )
			)
			( pin "C5U16.1"
				( objectStatus "@baseboard_fab2_lib.baseboard_fab2(sch_1):page221_i52:a" )
			)
			( pin "C5U16.2"
				( objectStatus "@baseboard_fab2_lib.baseboard_fab2(sch_1):page221_i52:b" )
			)
			( pin "R4G19.1"
				( objectStatus "@baseboard_fab2_lib.baseboard_fab2(sch_1):page221_i54:a" )
			)
			( pin "R4G19.2"
				( objectStatus "@baseboard_fab2_lib.baseboard_fab2(sch_1):page221_i54:b" )
			)
			( pin "R6U16.1"
				( objectStatus "@baseboard_fab2_lib.baseboard_fab2(sch_1):page221_i55:a" )
			)
			( pin "R6U16.2"
				( objectStatus "@baseboard_fab2_lib.baseboard_fab2(sch_1):page221_i55:b" )
			)
			( pin "SH5U1.1"
				( objectStatus "@baseboard_fab2_lib.baseboard_fab2(sch_1):page221_i56:a" )
			)
			( pin "SH5U1.2"
				( objectStatus "@baseboard_fab2_lib.baseboard_fab2(sch_1):page221_i56:b" )
			)
			( pin "C4A12.1"
				( objectStatus "@baseboard_fab2_lib.baseboard_fab2(sch_1):page222_i12:a" )
			)
			( pin "C4A12.2"
				( objectStatus "@baseboard_fab2_lib.baseboard_fab2(sch_1):page222_i12:b" )
			)
			( pin "C4A1.1"
				( objectStatus "@baseboard_fab2_lib.baseboard_fab2(sch_1):page222_i16:a" )
			)
			( pin "C4A1.2"
				( objectStatus "@baseboard_fab2_lib.baseboard_fab2(sch_1):page222_i16:b" )
			)
			( pin "R6L9.1"
				( objectStatus "@baseboard_fab2_lib.baseboard_fab2(sch_1):page222_i19:a" )
			)
			( pin "R6L9.2"
				( objectStatus "@baseboard_fab2_lib.baseboard_fab2(sch_1):page222_i19:b" )
			)
			( pin "C4A9.1"
				( objectStatus "@baseboard_fab2_lib.baseboard_fab2(sch_1):page222_i21:a" )
			)
			( pin "C4A9.2"
				( objectStatus "@baseboard_fab2_lib.baseboard_fab2(sch_1):page222_i21:b" )
			)
			( pin "C6L3.1"
				( objectStatus "@baseboard_fab2_lib.baseboard_fab2(sch_1):page222_i24:a" )
			)
			( pin "C6L3.2"
				( objectStatus "@baseboard_fab2_lib.baseboard_fab2(sch_1):page222_i24:b" )
			)
			( pin "C6L4.1"
				( objectStatus "@baseboard_fab2_lib.baseboard_fab2(sch_1):page222_i26:a" )
			)
			( pin "C6L4.2"
				( objectStatus "@baseboard_fab2_lib.baseboard_fab2(sch_1):page222_i26:b" )
			)
			( pin "C4A10.1"
				( objectStatus "@baseboard_fab2_lib.baseboard_fab2(sch_1):page222_i28:a" )
			)
			( pin "C4A10.2"
				( objectStatus "@baseboard_fab2_lib.baseboard_fab2(sch_1):page222_i28:b" )
			)
			( pin "R6L11.1"
				( objectStatus "@baseboard_fab2_lib.baseboard_fab2(sch_1):page222_i30:a" )
			)
			( pin "R6L11.2"
				( objectStatus "@baseboard_fab2_lib.baseboard_fab2(sch_1):page222_i30:b" )
			)
			( pin "EU4A1.3"
				( objectStatus "@baseboard_fab2_lib.baseboard_fab2(sch_1):page222_i31:agnd" )
			)
			( pin "EU4A1.2"
				( objectStatus "@baseboard_fab2_lib.baseboard_fab2(sch_1):page222_i31:bias" )
			)
			( pin "EU4A1.7"
				( objectStatus "@baseboard_fab2_lib.baseboard_fab2(sch_1):page222_i31:en" )
			)
			( pin "EU4A1.5"
				( objectStatus "@baseboard_fab2_lib.baseboard_fab2(sch_1):page222_i31:pg" )
			)
			( pin "EU4A1.8"
				( objectStatus "@baseboard_fab2_lib.baseboard_fab2(sch_1):page222_i31:pgnd" )
			)
			( pin "EU4A1.6"
				( objectStatus "@baseboard_fab2_lib.baseboard_fab2(sch_1):page222_i31:sns" )
			)
			( pin "EU4A1.11"
				( objectStatus "@baseboard_fab2_lib.baseboard_fab2(sch_1):page222_i31:thpad" )
			)
			( pin "EU4A1.4"
				( objectStatus "@baseboard_fab2_lib.baseboard_fab2(sch_1):page222_i31:vddq" )
			)
			( pin "EU4A1.10"
				( objectStatus "@baseboard_fab2_lib.baseboard_fab2(sch_1):page222_i31:vin" )
			)
			( pin "EU4A1.1"
				( objectStatus "@baseboard_fab2_lib.baseboard_fab2(sch_1):page222_i31:vref" )
			)
			( pin "EU4A1.9"
				( objectStatus "@baseboard_fab2_lib.baseboard_fab2(sch_1):page222_i31:vtt" )
			)
			( pin "R6L10.1"
				( objectStatus "@baseboard_fab2_lib.baseboard_fab2(sch_1):page222_i34:a" )
			)
			( pin "R6L10.2"
				( objectStatus "@baseboard_fab2_lib.baseboard_fab2(sch_1):page222_i34:b" )
			)
			( pin "R6L4.1"
				( objectStatus "@baseboard_fab2_lib.baseboard_fab2(sch_1):page222_i37:a" )
			)
			( pin "R6L4.2"
				( objectStatus "@baseboard_fab2_lib.baseboard_fab2(sch_1):page222_i37:b" )
			)
			( pin "R4A2.1"
				( objectStatus "@baseboard_fab2_lib.baseboard_fab2(sch_1):page222_i38:a" )
			)
			( pin "R4A2.2"
				( objectStatus "@baseboard_fab2_lib.baseboard_fab2(sch_1):page222_i38:b" )
			)
			( pin "C4A2.1"
				( objectStatus "@baseboard_fab2_lib.baseboard_fab2(sch_1):page222_i40:a" )
			)
			( pin "C4A2.2"
				( objectStatus "@baseboard_fab2_lib.baseboard_fab2(sch_1):page222_i40:b" )
			)
			( pin "C4A11.1"
				( objectStatus "@baseboard_fab2_lib.baseboard_fab2(sch_1):page222_i46:a" )
			)
			( pin "C4A11.2"
				( objectStatus "@baseboard_fab2_lib.baseboard_fab2(sch_1):page222_i46:b" )
			)
			( pin "C5L4.1"
				( objectStatus "@baseboard_fab2_lib.baseboard_fab2(sch_1):page222_i47:a" )
			)
			( pin "C5L4.2"
				( objectStatus "@baseboard_fab2_lib.baseboard_fab2(sch_1):page222_i47:b" )
			)
			( pin "C5M13.1"
				( objectStatus "@baseboard_fab2_lib.baseboard_fab2(sch_1):page222_i48:a" )
			)
			( pin "C5M13.2"
				( objectStatus "@baseboard_fab2_lib.baseboard_fab2(sch_1):page222_i48:b" )
			)
			( pin "C5L5.1"
				( objectStatus "@baseboard_fab2_lib.baseboard_fab2(sch_1):page222_i49:a" )
			)
			( pin "C5L5.2"
				( objectStatus "@baseboard_fab2_lib.baseboard_fab2(sch_1):page222_i49:b" )
			)
			( pin "R4A6.1"
				( objectStatus "@baseboard_fab2_lib.baseboard_fab2(sch_1):page222_i51:a" )
			)
			( pin "R4A6.2"
				( objectStatus "@baseboard_fab2_lib.baseboard_fab2(sch_1):page222_i51:b" )
			)
			( pin "R4A1.1"
				( objectStatus "@baseboard_fab2_lib.baseboard_fab2(sch_1):page222_i52:a" )
			)
			( pin "R4A1.2"
				( objectStatus "@baseboard_fab2_lib.baseboard_fab2(sch_1):page222_i52:b" )
			)
			( pin "SH5L1.1"
				( objectStatus "@baseboard_fab2_lib.baseboard_fab2(sch_1):page222_i53:a" )
			)
			( pin "SH5L1.2"
				( objectStatus "@baseboard_fab2_lib.baseboard_fab2(sch_1):page222_i53:b" )
			)
			( pin "R9U3.1"
				( objectStatus "@baseboard_fab2_lib.baseboard_fab2(sch_1):page223_i8:a" )
			)
			( pin "R9U3.2"
				( objectStatus "@baseboard_fab2_lib.baseboard_fab2(sch_1):page223_i8:b" )
			)
			( pin "R1G6.1"
				( objectStatus "@baseboard_fab2_lib.baseboard_fab2(sch_1):page223_i13:a" )
			)
			( pin "R1G6.2"
				( objectStatus "@baseboard_fab2_lib.baseboard_fab2(sch_1):page223_i13:b" )
			)
			( pin "R1G12.1"
				( objectStatus "@baseboard_fab2_lib.baseboard_fab2(sch_1):page223_i14:a" )
			)
			( pin "R1G12.2"
				( objectStatus "@baseboard_fab2_lib.baseboard_fab2(sch_1):page223_i14:b" )
			)
			( pin "R1G9.1"
				( objectStatus "@baseboard_fab2_lib.baseboard_fab2(sch_1):page223_i16:a" )
			)
			( pin "R1G9.2"
				( objectStatus "@baseboard_fab2_lib.baseboard_fab2(sch_1):page223_i16:b" )
			)
			( pin "R1G16.1"
				( objectStatus "@baseboard_fab2_lib.baseboard_fab2(sch_1):page223_i17:a" )
			)
			( pin "R1G16.2"
				( objectStatus "@baseboard_fab2_lib.baseboard_fab2(sch_1):page223_i17:b" )
			)
			( pin "R1G19.1"
				( objectStatus "@baseboard_fab2_lib.baseboard_fab2(sch_1):page223_i21:a" )
			)
			( pin "R1G19.2"
				( objectStatus "@baseboard_fab2_lib.baseboard_fab2(sch_1):page223_i21:b" )
			)
			( pin "R1G21.1"
				( objectStatus "@baseboard_fab2_lib.baseboard_fab2(sch_1):page223_i22:a" )
			)
			( pin "R1G21.2"
				( objectStatus "@baseboard_fab2_lib.baseboard_fab2(sch_1):page223_i22:b" )
			)
			( pin "R1G10.1"
				( objectStatus "@baseboard_fab2_lib.baseboard_fab2(sch_1):page223_i23:a" )
			)
			( pin "R1G10.2"
				( objectStatus "@baseboard_fab2_lib.baseboard_fab2(sch_1):page223_i23:b" )
			)
			( pin "C1G27.1"
				( objectStatus "@baseboard_fab2_lib.baseboard_fab2(sch_1):page223_i25:a" )
			)
			( pin "C1G27.2"
				( objectStatus "@baseboard_fab2_lib.baseboard_fab2(sch_1):page223_i25:b" )
			)
			( pin "C1G25.1"
				( objectStatus "@baseboard_fab2_lib.baseboard_fab2(sch_1):page223_i27:a" )
			)
			( pin "C1G25.2"
				( objectStatus "@baseboard_fab2_lib.baseboard_fab2(sch_1):page223_i27:b" )
			)
			( pin "R9U10.1"
				( objectStatus "@baseboard_fab2_lib.baseboard_fab2(sch_1):page223_i30:a" )
			)
			( pin "R9U10.2"
				( objectStatus "@baseboard_fab2_lib.baseboard_fab2(sch_1):page223_i30:b" )
			)
			( pin "R1G5.1"
				( objectStatus "@baseboard_fab2_lib.baseboard_fab2(sch_1):page223_i32:a" )
			)
			( pin "R1G5.2"
				( objectStatus "@baseboard_fab2_lib.baseboard_fab2(sch_1):page223_i32:b" )
			)
			( pin "C1G24.1"
				( objectStatus "@baseboard_fab2_lib.baseboard_fab2(sch_1):page223_i36:a" )
			)
			( pin "C1G24.2"
				( objectStatus "@baseboard_fab2_lib.baseboard_fab2(sch_1):page223_i36:b" )
			)
			( pin "C1G16.1"
				( objectStatus "@baseboard_fab2_lib.baseboard_fab2(sch_1):page223_i39:a" )
			)
			( pin "C1G16.2"
				( objectStatus "@baseboard_fab2_lib.baseboard_fab2(sch_1):page223_i39:b" )
			)
			( pin "C1G23.1"
				( objectStatus "@baseboard_fab2_lib.baseboard_fab2(sch_1):page223_i41:a" )
			)
			( pin "C1G23.2"
				( objectStatus "@baseboard_fab2_lib.baseboard_fab2(sch_1):page223_i41:b" )
			)
			( pin "C1G22.1"
				( objectStatus "@baseboard_fab2_lib.baseboard_fab2(sch_1):page223_i44:a" )
			)
			( pin "C1G22.2"
				( objectStatus "@baseboard_fab2_lib.baseboard_fab2(sch_1):page223_i44:b" )
			)
			( pin "R9U4.1"
				( objectStatus "@baseboard_fab2_lib.baseboard_fab2(sch_1):page223_i50:a" )
			)
			( pin "R9U4.2"
				( objectStatus "@baseboard_fab2_lib.baseboard_fab2(sch_1):page223_i50:b" )
			)
			( pin "R1G7.1"
				( objectStatus "@baseboard_fab2_lib.baseboard_fab2(sch_1):page223_i53:a" )
			)
			( pin "R1G7.2"
				( objectStatus "@baseboard_fab2_lib.baseboard_fab2(sch_1):page223_i53:b" )
			)
			( pin "R9U11.1"
				( objectStatus "@baseboard_fab2_lib.baseboard_fab2(sch_1):page223_i57:a" )
			)
			( pin "R9U11.2"
				( objectStatus "@baseboard_fab2_lib.baseboard_fab2(sch_1):page223_i57:b" )
			)
			( pin "R1G24.1"
				( objectStatus "@baseboard_fab2_lib.baseboard_fab2(sch_1):page223_i58:a" )
			)
			( pin "R1G24.2"
				( objectStatus "@baseboard_fab2_lib.baseboard_fab2(sch_1):page223_i58:b" )
			)
			( pin "C1G26.1"
				( objectStatus "@baseboard_fab2_lib.baseboard_fab2(sch_1):page223_i59:a" )
			)
			( pin "C1G26.2"
				( objectStatus "@baseboard_fab2_lib.baseboard_fab2(sch_1):page223_i59:b" )
			)
			( pin "R1G23.1"
				( objectStatus "@baseboard_fab2_lib.baseboard_fab2(sch_1):page223_i77:a" )
			)
			( pin "R1G23.2"
				( objectStatus "@baseboard_fab2_lib.baseboard_fab2(sch_1):page223_i77:b" )
			)
			( pin "R1G22.1"
				( objectStatus "@baseboard_fab2_lib.baseboard_fab2(sch_1):page223_i78:a" )
			)
			( pin "R1G22.2"
				( objectStatus "@baseboard_fab2_lib.baseboard_fab2(sch_1):page223_i78:b" )
			)
			( pin "R1G11.1"
				( objectStatus "@baseboard_fab2_lib.baseboard_fab2(sch_1):page223_i79:a" )
			)
			( pin "R1G11.2"
				( objectStatus "@baseboard_fab2_lib.baseboard_fab2(sch_1):page223_i79:b" )
			)
			( pin "C1G21.1"
				( objectStatus "@baseboard_fab2_lib.baseboard_fab2(sch_1):page223_i80:a" )
			)
			( pin "C1G21.2"
				( objectStatus "@baseboard_fab2_lib.baseboard_fab2(sch_1):page223_i80:b" )
			)
			( pin "R1G8.1"
				( objectStatus "@baseboard_fab2_lib.baseboard_fab2(sch_1):page223_i82:a" )
			)
			( pin "R1G8.2"
				( objectStatus "@baseboard_fab2_lib.baseboard_fab2(sch_1):page223_i82:b" )
			)
			( pin "R9U7.1"
				( objectStatus "@baseboard_fab2_lib.baseboard_fab2(sch_1):page223_i84:a" )
			)
			( pin "R9U7.2"
				( objectStatus "@baseboard_fab2_lib.baseboard_fab2(sch_1):page223_i84:b" )
			)
			( pin "R9U8.1"
				( objectStatus "@baseboard_fab2_lib.baseboard_fab2(sch_1):page223_i85:a" )
			)
			( pin "R9U8.2"
				( objectStatus "@baseboard_fab2_lib.baseboard_fab2(sch_1):page223_i85:b" )
			)
			( pin "R1G28.1"
				( objectStatus "@baseboard_fab2_lib.baseboard_fab2(sch_1):page223_i87:a" )
			)
			( pin "R1G28.2"
				( objectStatus "@baseboard_fab2_lib.baseboard_fab2(sch_1):page223_i87:b" )
			)
			( pin "R1G27.1"
				( objectStatus "@baseboard_fab2_lib.baseboard_fab2(sch_1):page223_i88:a" )
			)
			( pin "R1G27.2"
				( objectStatus "@baseboard_fab2_lib.baseboard_fab2(sch_1):page223_i88:b" )
			)
			( pin "EU1G2.21"
				( objectStatus "@baseboard_fab2_lib.baseboard_fab2(sch_1):page223_i90:airef1" )
			)
			( pin "EU1G2.23"
				( objectStatus "@baseboard_fab2_lib.baseboard_fab2(sch_1):page223_i90:airef2" )
			)
			( pin "EU1G2.25"
				( objectStatus "@baseboard_fab2_lib.baseboard_fab2(sch_1):page223_i90:airef3" )
			)
			( pin "EU1G2.22"
				( objectStatus "@baseboard_fab2_lib.baseboard_fab2(sch_1):page223_i90:aisen1" )
			)
			( pin "EU1G2.24"
				( objectStatus "@baseboard_fab2_lib.baseboard_fab2(sch_1):page223_i90:aisen2" )
			)
			( pin "EU1G2.26"
				( objectStatus "@baseboard_fab2_lib.baseboard_fab2(sch_1):page223_i90:aisen3" )
			)
			( pin "EU1G2.5"
				( objectStatus "@baseboard_fab2_lib.baseboard_fab2(sch_1):page223_i90:apwm1" )
			)
			( pin "EU1G2.4"
				( objectStatus "@baseboard_fab2_lib.baseboard_fab2(sch_1):page223_i90:apwm2" )
			)
			( pin "EU1G2.3"
				( objectStatus "@baseboard_fab2_lib.baseboard_fab2(sch_1):page223_i90:apwm3" )
			)
			( pin "EU1G2.35"
				( objectStatus "@baseboard_fab2_lib.baseboard_fab2(sch_1):page223_i90:atsen" )
			)
			( pin "EU1G2.20"
				( objectStatus "@baseboard_fab2_lib.baseboard_fab2(sch_1):page223_i90:avref" )
			)
			( pin "EU1G2.10"
				( objectStatus "@baseboard_fab2_lib.baseboard_fab2(sch_1):page223_i90:avren" )
			)
			( pin "EU1G2.9"
				( objectStatus "@baseboard_fab2_lib.baseboard_fab2(sch_1):page223_i90:avrrdy" )
			)
			( pin "EU1G2.19"
				( objectStatus "@baseboard_fab2_lib.baseboard_fab2(sch_1):page223_i90:avsen" )
			)
			( pin "EU1G2.31"
				( objectStatus "@baseboard_fab2_lib.baseboard_fab2(sch_1):page223_i90:biref1" )
			)
			( pin "EU1G2.32"
				( objectStatus "@baseboard_fab2_lib.baseboard_fab2(sch_1):page223_i90:bisen1" )
			)
			( pin "EU1G2.1"
				( objectStatus "@baseboard_fab2_lib.baseboard_fab2(sch_1):page223_i90:bpwm1" )
			)
			( pin "EU1G2.34"
				( objectStatus "@baseboard_fab2_lib.baseboard_fab2(sch_1):page223_i90:btsen" )
			)
			( pin "EU1G2.30"
				( objectStatus "@baseboard_fab2_lib.baseboard_fab2(sch_1):page223_i90:bvref" )
			)
			( pin "EU1G2.29"
				( objectStatus "@baseboard_fab2_lib.baseboard_fab2(sch_1):page223_i90:bvsen" )
			)
			( pin "EU1G2.2"
				( objectStatus "@baseboard_fab2_lib.baseboard_fab2(sch_1):page223_i90:dnc(0)" )
			)
			( pin "EU1G2.28"
				( objectStatus "@baseboard_fab2_lib.baseboard_fab2(sch_1):page223_i90:dnc(1)" )
			)
			( pin "EU1G2.27"
				( objectStatus "@baseboard_fab2_lib.baseboard_fab2(sch_1):page223_i90:gnd" )
			)
			( pin "EU1G2.38"
				( objectStatus "@baseboard_fab2_lib.baseboard_fab2(sch_1):page223_i90:iinsen" )
			)
			( pin "EU1G2.13"
				( objectStatus "@baseboard_fab2_lib.baseboard_fab2(sch_1):page223_i90:mp0" )
			)
			( pin "EU1G2.14"
				( objectStatus "@baseboard_fab2_lib.baseboard_fab2(sch_1):page223_i90:mp1" )
			)
			( pin "EU1G2.18"
				( objectStatus "@baseboard_fab2_lib.baseboard_fab2(sch_1):page223_i90:mp2" )
			)
			( pin "EU1G2.12"
				( objectStatus "@baseboard_fab2_lib.baseboard_fab2(sch_1):page223_i90:pinalrt_n" )
			)
			( pin "EU1G2.8"
				( objectStatus "@baseboard_fab2_lib.baseboard_fab2(sch_1):page223_i90:reset_n" )
			)
			( pin "EU1G2.7"
				( objectStatus "@baseboard_fab2_lib.baseboard_fab2(sch_1):page223_i90:scl" )
			)
			( pin "EU1G2.6"
				( objectStatus "@baseboard_fab2_lib.baseboard_fab2(sch_1):page223_i90:sda" )
			)
			( pin "EU1G2.41"
				( objectStatus "@baseboard_fab2_lib.baseboard_fab2(sch_1):page223_i90:thpad" )
			)
			( pin "EU1G2.17"
				( objectStatus "@baseboard_fab2_lib.baseboard_fab2(sch_1):page223_i90:valrt_n" )
			)
			( pin "EU1G2.15"
				( objectStatus "@baseboard_fab2_lib.baseboard_fab2(sch_1):page223_i90:vclk" )
			)
			( pin "EU1G2.40"
				( objectStatus "@baseboard_fab2_lib.baseboard_fab2(sch_1):page223_i90:vd12" )
			)
			( pin "EU1G2.39"
				( objectStatus "@baseboard_fab2_lib.baseboard_fab2(sch_1):page223_i90:vdd" )
			)
			( pin "EU1G2.16"
				( objectStatus "@baseboard_fab2_lib.baseboard_fab2(sch_1):page223_i90:vdio" )
			)
			( pin "EU1G2.37"
				( objectStatus "@baseboard_fab2_lib.baseboard_fab2(sch_1):page223_i90:vinsen" )
			)
			( pin "EU1G2.11"
				( objectStatus "@baseboard_fab2_lib.baseboard_fab2(sch_1):page223_i90:vrhot_n" )
			)
			( pin "EU1G2.36"
				( objectStatus "@baseboard_fab2_lib.baseboard_fab2(sch_1):page223_i90:xaddr1" )
			)
			( pin "EU1G2.33"
				( objectStatus "@baseboard_fab2_lib.baseboard_fab2(sch_1):page223_i90:xaddr2" )
			)
			( pin "C9U12.1"
				( objectStatus "@baseboard_fab2_lib.baseboard_fab2(sch_1):page223_i92:a" )
			)
			( pin "C9U12.2"
				( objectStatus "@baseboard_fab2_lib.baseboard_fab2(sch_1):page223_i92:b" )
			)
			( pin "C1G17.1"
				( objectStatus "@baseboard_fab2_lib.baseboard_fab2(sch_1):page224_i6:a" )
			)
			( pin "C1G17.2"
				( objectStatus "@baseboard_fab2_lib.baseboard_fab2(sch_1):page224_i6:b" )
			)
			( pin "C1G11.1"
				( objectStatus "@baseboard_fab2_lib.baseboard_fab2(sch_1):page224_i44:a" )
			)
			( pin "C1G11.2"
				( objectStatus "@baseboard_fab2_lib.baseboard_fab2(sch_1):page224_i44:b" )
			)
			( pin "C9U6.1"
				( objectStatus "@baseboard_fab2_lib.baseboard_fab2(sch_1):page224_i45:a" )
			)
			( pin "C9U6.2"
				( objectStatus "@baseboard_fab2_lib.baseboard_fab2(sch_1):page224_i45:b" )
			)
			( pin "C9U4.1"
				( objectStatus "@baseboard_fab2_lib.baseboard_fab2(sch_1):page224_i46:a" )
			)
			( pin "C9U4.2"
				( objectStatus "@baseboard_fab2_lib.baseboard_fab2(sch_1):page224_i46:b" )
			)
			( pin "C9T4.1"
				( objectStatus "@baseboard_fab2_lib.baseboard_fab2(sch_1):page224_i47:a" )
			)
			( pin "C9T4.2"
				( objectStatus "@baseboard_fab2_lib.baseboard_fab2(sch_1):page224_i47:b" )
			)
			( pin "C1F27.1"
				( objectStatus "@baseboard_fab2_lib.baseboard_fab2(sch_1):page224_i48:a" )
			)
			( pin "C1F27.2"
				( objectStatus "@baseboard_fab2_lib.baseboard_fab2(sch_1):page224_i48:b" )
			)
			( pin "C1G6.1"
				( objectStatus "@baseboard_fab2_lib.baseboard_fab2(sch_1):page224_i50:a" )
			)
			( pin "C1G6.2"
				( objectStatus "@baseboard_fab2_lib.baseboard_fab2(sch_1):page224_i50:b" )
			)
			( pin "C1G14.1"
				( objectStatus "@baseboard_fab2_lib.baseboard_fab2(sch_1):page224_i51:a" )
			)
			( pin "C1G14.2"
				( objectStatus "@baseboard_fab2_lib.baseboard_fab2(sch_1):page224_i51:b" )
			)
			( pin "R9U1.1"
				( objectStatus "@baseboard_fab2_lib.baseboard_fab2(sch_1):page224_i52:a" )
			)
			( pin "R9U1.2"
				( objectStatus "@baseboard_fab2_lib.baseboard_fab2(sch_1):page224_i52:b" )
			)
			( pin "C1G4.1"
				( objectStatus "@baseboard_fab2_lib.baseboard_fab2(sch_1):page224_i53:a" )
			)
			( pin "C1G4.2"
				( objectStatus "@baseboard_fab2_lib.baseboard_fab2(sch_1):page224_i53:b" )
			)
			( pin "C1G5.1"
				( objectStatus "@baseboard_fab2_lib.baseboard_fab2(sch_1):page224_i54:a" )
			)
			( pin "C1G5.2"
				( objectStatus "@baseboard_fab2_lib.baseboard_fab2(sch_1):page224_i54:b" )
			)
			( pin "L1G1.1"
				( objectStatus "@baseboard_fab2_lib.baseboard_fab2(sch_1):page224_i55:ina" )
			)
			( pin "L1G1.2"
				( objectStatus "@baseboard_fab2_lib.baseboard_fab2(sch_1):page224_i55:inb" )
			)
			( pin "L1F2.1"
				( objectStatus "@baseboard_fab2_lib.baseboard_fab2(sch_1):page224_i65:ina" )
			)
			( pin "L1F2.2"
				( objectStatus "@baseboard_fab2_lib.baseboard_fab2(sch_1):page224_i65:inb" )
			)
			( pin "C1G20.1"
				( objectStatus "@baseboard_fab2_lib.baseboard_fab2(sch_1):page224_i68:a" )
			)
			( pin "C1G20.2"
				( objectStatus "@baseboard_fab2_lib.baseboard_fab2(sch_1):page224_i68:b" )
			)
			( pin "C1G29.1"
				( objectStatus "@baseboard_fab2_lib.baseboard_fab2(sch_1):page224_i72:a" )
			)
			( pin "C1G29.2"
				( objectStatus "@baseboard_fab2_lib.baseboard_fab2(sch_1):page224_i72:b" )
			)
			( pin "C1F21.1"
				( objectStatus "@baseboard_fab2_lib.baseboard_fab2(sch_1):page224_i73:a" )
			)
			( pin "C1F21.2"
				( objectStatus "@baseboard_fab2_lib.baseboard_fab2(sch_1):page224_i73:b" )
			)
			( pin "C1F26.1"
				( objectStatus "@baseboard_fab2_lib.baseboard_fab2(sch_1):page224_i75:a" )
			)
			( pin "C1F26.2"
				( objectStatus "@baseboard_fab2_lib.baseboard_fab2(sch_1):page224_i75:b" )
			)
			( pin "R9U12.1"
				( objectStatus "@baseboard_fab2_lib.baseboard_fab2(sch_1):page224_i76:a" )
			)
			( pin "R9U12.2"
				( objectStatus "@baseboard_fab2_lib.baseboard_fab2(sch_1):page224_i76:b" )
			)
			( pin "C1G28.1"
				( objectStatus "@baseboard_fab2_lib.baseboard_fab2(sch_1):page224_i77:a" )
			)
			( pin "C1G28.2"
				( objectStatus "@baseboard_fab2_lib.baseboard_fab2(sch_1):page224_i77:b" )
			)
			( pin "C1F28.1"
				( objectStatus "@baseboard_fab2_lib.baseboard_fab2(sch_1):page224_i78:a" )
			)
			( pin "C1F28.2"
				( objectStatus "@baseboard_fab2_lib.baseboard_fab2(sch_1):page224_i78:b" )
			)
			( pin "C1G13.1"
				( objectStatus "@baseboard_fab2_lib.baseboard_fab2(sch_1):page224_i79:a" )
			)
			( pin "C1G13.2"
				( objectStatus "@baseboard_fab2_lib.baseboard_fab2(sch_1):page224_i79:b" )
			)
			( pin "C9U3.1"
				( objectStatus "@baseboard_fab2_lib.baseboard_fab2(sch_1):page224_i80:a" )
			)
			( pin "C9U3.2"
				( objectStatus "@baseboard_fab2_lib.baseboard_fab2(sch_1):page224_i80:b" )
			)
			( pin "C9T6.1"
				( objectStatus "@baseboard_fab2_lib.baseboard_fab2(sch_1):page224_i81:a" )
			)
			( pin "C9T6.2"
				( objectStatus "@baseboard_fab2_lib.baseboard_fab2(sch_1):page224_i81:b" )
			)
			( pin "C9T9.1"
				( objectStatus "@baseboard_fab2_lib.baseboard_fab2(sch_1):page224_i84:a" )
			)
			( pin "C9T9.2"
				( objectStatus "@baseboard_fab2_lib.baseboard_fab2(sch_1):page224_i84:b" )
			)
			( pin "EU1G1.33"
				( objectStatus "@baseboard_fab2_lib.baseboard_fab2(sch_1):page224_i110:boost" )
			)
			( pin "EU1G1.35"
				( objectStatus "@baseboard_fab2_lib.baseboard_fab2(sch_1):page224_i110:en" )
			)
			( pin "EU1G1.6"
				( objectStatus "@baseboard_fab2_lib.baseboard_fab2(sch_1):page224_i110:gl(0)" )
			)
			( pin "EU1G1.41"
				( objectStatus "@baseboard_fab2_lib.baseboard_fab2(sch_1):page224_i110:gl(1)" )
			)
			( pin "EU1G1.38"
				( objectStatus "@baseboard_fab2_lib.baseboard_fab2(sch_1):page224_i110:iout" )
			)
			( pin "EU1G1.2"
				( objectStatus "@baseboard_fab2_lib.baseboard_fab2(sch_1):page224_i110:lgnd" )
			)
			( pin "EU1G1.31"
				( objectStatus "@baseboard_fab2_lib.baseboard_fab2(sch_1):page224_i110:nc" )
			)
			( pin "EU1G1.37"
				( objectStatus "@baseboard_fab2_lib.baseboard_fab2(sch_1):page224_i110:ocset" )
			)
			( pin "EU1G1.5"
				( objectStatus "@baseboard_fab2_lib.baseboard_fab2(sch_1):page224_i110:pgnd(0)" )
			)
			( pin "EU1G1.7"
				( objectStatus "@baseboard_fab2_lib.baseboard_fab2(sch_1):page224_i110:pgnd(1)" )
			)
			( pin "EU1G1.40"
				( objectStatus "@baseboard_fab2_lib.baseboard_fab2(sch_1):page224_i110:pgnd(2)" )
			)
			( pin "EU1G1.32"
				( objectStatus "@baseboard_fab2_lib.baseboard_fab2(sch_1):page224_i110:phase" )
			)
			( pin "EU1G1.34"
				( objectStatus "@baseboard_fab2_lib.baseboard_fab2(sch_1):page224_i110:pwm" )
			)
			( pin "EU1G1.39"
				( objectStatus "@baseboard_fab2_lib.baseboard_fab2(sch_1):page224_i110:refin" )
			)
			( pin "EU1G1.10"
				( objectStatus "@baseboard_fab2_lib.baseboard_fab2(sch_1):page224_i110:sw" )
			)
			( pin "EU1G1.36"
				( objectStatus "@baseboard_fab2_lib.baseboard_fab2(sch_1):page224_i110:tout_flt" )
			)
			( pin "EU1G1.3"
				( objectStatus "@baseboard_fab2_lib.baseboard_fab2(sch_1):page224_i110:vcc" )
			)
			( pin "EU1G1.4"
				( objectStatus "@baseboard_fab2_lib.baseboard_fab2(sch_1):page224_i110:vdrv" )
			)
			( pin "EU1G1.25"
				( objectStatus "@baseboard_fab2_lib.baseboard_fab2(sch_1):page224_i110:vin(0)" )
			)
			( pin "EU1G1.30"
				( objectStatus "@baseboard_fab2_lib.baseboard_fab2(sch_1):page224_i110:vin(1)" )
			)
			( pin "EU1G1.1"
				( objectStatus "@baseboard_fab2_lib.baseboard_fab2(sch_1):page224_i110:vos" )
			)
			( pin "EU1F1.33"
				( objectStatus "@baseboard_fab2_lib.baseboard_fab2(sch_1):page224_i111:boost" )
			)
			( pin "EU1F1.35"
				( objectStatus "@baseboard_fab2_lib.baseboard_fab2(sch_1):page224_i111:en" )
			)
			( pin "EU1F1.6"
				( objectStatus "@baseboard_fab2_lib.baseboard_fab2(sch_1):page224_i111:gl(0)" )
			)
			( pin "EU1F1.41"
				( objectStatus "@baseboard_fab2_lib.baseboard_fab2(sch_1):page224_i111:gl(1)" )
			)
			( pin "EU1F1.38"
				( objectStatus "@baseboard_fab2_lib.baseboard_fab2(sch_1):page224_i111:iout" )
			)
			( pin "EU1F1.2"
				( objectStatus "@baseboard_fab2_lib.baseboard_fab2(sch_1):page224_i111:lgnd" )
			)
			( pin "EU1F1.31"
				( objectStatus "@baseboard_fab2_lib.baseboard_fab2(sch_1):page224_i111:nc" )
			)
			( pin "EU1F1.37"
				( objectStatus "@baseboard_fab2_lib.baseboard_fab2(sch_1):page224_i111:ocset" )
			)
			( pin "EU1F1.5"
				( objectStatus "@baseboard_fab2_lib.baseboard_fab2(sch_1):page224_i111:pgnd(0)" )
			)
			( pin "EU1F1.7"
				( objectStatus "@baseboard_fab2_lib.baseboard_fab2(sch_1):page224_i111:pgnd(1)" )
			)
			( pin "EU1F1.40"
				( objectStatus "@baseboard_fab2_lib.baseboard_fab2(sch_1):page224_i111:pgnd(2)" )
			)
			( pin "EU1F1.32"
				( objectStatus "@baseboard_fab2_lib.baseboard_fab2(sch_1):page224_i111:phase" )
			)
			( pin "EU1F1.34"
				( objectStatus "@baseboard_fab2_lib.baseboard_fab2(sch_1):page224_i111:pwm" )
			)
			( pin "EU1F1.39"
				( objectStatus "@baseboard_fab2_lib.baseboard_fab2(sch_1):page224_i111:refin" )
			)
			( pin "EU1F1.10"
				( objectStatus "@baseboard_fab2_lib.baseboard_fab2(sch_1):page224_i111:sw" )
			)
			( pin "EU1F1.36"
				( objectStatus "@baseboard_fab2_lib.baseboard_fab2(sch_1):page224_i111:tout_flt" )
			)
			( pin "EU1F1.3"
				( objectStatus "@baseboard_fab2_lib.baseboard_fab2(sch_1):page224_i111:vcc" )
			)
			( pin "EU1F1.4"
				( objectStatus "@baseboard_fab2_lib.baseboard_fab2(sch_1):page224_i111:vdrv" )
			)
			( pin "EU1F1.25"
				( objectStatus "@baseboard_fab2_lib.baseboard_fab2(sch_1):page224_i111:vin(0)" )
			)
			( pin "EU1F1.30"
				( objectStatus "@baseboard_fab2_lib.baseboard_fab2(sch_1):page224_i111:vin(1)" )
			)
			( pin "EU1F1.1"
				( objectStatus "@baseboard_fab2_lib.baseboard_fab2(sch_1):page224_i111:vos" )
			)
			( pin "R1G26.1"
				( objectStatus "@baseboard_fab2_lib.baseboard_fab2(sch_1):page224_i112:a" )
			)
			( pin "R1G26.2"
				( objectStatus "@baseboard_fab2_lib.baseboard_fab2(sch_1):page224_i112:b" )
			)
			( pin "R1G25.1"
				( objectStatus "@baseboard_fab2_lib.baseboard_fab2(sch_1):page224_i114:a" )
			)
			( pin "R1G25.2"
				( objectStatus "@baseboard_fab2_lib.baseboard_fab2(sch_1):page224_i114:b" )
			)
			( pin "R1G20.1"
				( objectStatus "@baseboard_fab2_lib.baseboard_fab2(sch_1):page225_i58:a" )
			)
			( pin "R1G20.2"
				( objectStatus "@baseboard_fab2_lib.baseboard_fab2(sch_1):page225_i58:b" )
			)
			( pin "R7U2.1"
				( objectStatus "@baseboard_fab2_lib.baseboard_fab2(sch_1):page225_i74:a" )
			)
			( pin "R7U2.2"
				( objectStatus "@baseboard_fab2_lib.baseboard_fab2(sch_1):page225_i74:b" )
			)
			( pin "C9T5.1"
				( objectStatus "@baseboard_fab2_lib.baseboard_fab2(sch_1):page225_i75:a" )
			)
			( pin "C9T5.2"
				( objectStatus "@baseboard_fab2_lib.baseboard_fab2(sch_1):page225_i75:b" )
			)
			( pin "C9U2.1"
				( objectStatus "@baseboard_fab2_lib.baseboard_fab2(sch_1):page225_i76:a" )
			)
			( pin "C9U2.2"
				( objectStatus "@baseboard_fab2_lib.baseboard_fab2(sch_1):page225_i76:b" )
			)
			( pin "C9U9.1"
				( objectStatus "@baseboard_fab2_lib.baseboard_fab2(sch_1):page225_i77:a" )
			)
			( pin "C9U9.2"
				( objectStatus "@baseboard_fab2_lib.baseboard_fab2(sch_1):page225_i77:b" )
			)
			( pin "C9U5.1"
				( objectStatus "@baseboard_fab2_lib.baseboard_fab2(sch_1):page225_i78:a" )
			)
			( pin "C9U5.2"
				( objectStatus "@baseboard_fab2_lib.baseboard_fab2(sch_1):page225_i78:b" )
			)
			( pin "C8U1.1"
				( objectStatus "@baseboard_fab2_lib.baseboard_fab2(sch_1):page225_i82:a" )
			)
			( pin "C8U1.2"
				( objectStatus "@baseboard_fab2_lib.baseboard_fab2(sch_1):page225_i82:b" )
			)
			( pin "C8U8.1"
				( objectStatus "@baseboard_fab2_lib.baseboard_fab2(sch_1):page225_i83:a" )
			)
			( pin "C8U8.2"
				( objectStatus "@baseboard_fab2_lib.baseboard_fab2(sch_1):page225_i83:b" )
			)
			( pin "C8U12.1"
				( objectStatus "@baseboard_fab2_lib.baseboard_fab2(sch_1):page225_i88:a" )
			)
			( pin "C8U12.2"
				( objectStatus "@baseboard_fab2_lib.baseboard_fab2(sch_1):page225_i88:b" )
			)
			( pin "C8U11.1"
				( objectStatus "@baseboard_fab2_lib.baseboard_fab2(sch_1):page225_i89:a" )
			)
			( pin "C8U11.2"
				( objectStatus "@baseboard_fab2_lib.baseboard_fab2(sch_1):page225_i89:b" )
			)
			( pin "C7T1.1"
				( objectStatus "@baseboard_fab2_lib.baseboard_fab2(sch_1):page225_i90:a" )
			)
			( pin "C7T1.2"
				( objectStatus "@baseboard_fab2_lib.baseboard_fab2(sch_1):page225_i90:b" )
			)
			( pin "C7U7.1"
				( objectStatus "@baseboard_fab2_lib.baseboard_fab2(sch_1):page225_i91:a" )
			)
			( pin "C7U7.2"
				( objectStatus "@baseboard_fab2_lib.baseboard_fab2(sch_1):page225_i91:b" )
			)
			( pin "C2G7.1"
				( objectStatus "@baseboard_fab2_lib.baseboard_fab2(sch_1):page225_i92:a" )
			)
			( pin "C2G7.2"
				( objectStatus "@baseboard_fab2_lib.baseboard_fab2(sch_1):page225_i92:b" )
			)
			( pin "C2G16.1"
				( objectStatus "@baseboard_fab2_lib.baseboard_fab2(sch_1):page225_i110:a" )
			)
			( pin "C2G16.2"
				( objectStatus "@baseboard_fab2_lib.baseboard_fab2(sch_1):page225_i110:b" )
			)
			( pin "L1F1.1"
				( objectStatus "@baseboard_fab2_lib.baseboard_fab2(sch_1):page225_i124:ina" )
			)
			( pin "L1F1.2"
				( objectStatus "@baseboard_fab2_lib.baseboard_fab2(sch_1):page225_i124:inb" )
			)
			( pin "C8P31.1"
				( objectStatus "@baseboard_fab2_lib.baseboard_fab2(sch_1):page225_i178:a" )
			)
			( pin "C8P31.2"
				( objectStatus "@baseboard_fab2_lib.baseboard_fab2(sch_1):page225_i178:b" )
			)
			( pin "C2D43.1"
				( objectStatus "@baseboard_fab2_lib.baseboard_fab2(sch_1):page225_i179:a" )
			)
			( pin "C2D43.2"
				( objectStatus "@baseboard_fab2_lib.baseboard_fab2(sch_1):page225_i179:b" )
			)
			( pin "C2D41.1"
				( objectStatus "@baseboard_fab2_lib.baseboard_fab2(sch_1):page225_i180:a" )
			)
			( pin "C2D41.2"
				( objectStatus "@baseboard_fab2_lib.baseboard_fab2(sch_1):page225_i180:b" )
			)
			( pin "C2D44.1"
				( objectStatus "@baseboard_fab2_lib.baseboard_fab2(sch_1):page225_i181:a" )
			)
			( pin "C2D44.2"
				( objectStatus "@baseboard_fab2_lib.baseboard_fab2(sch_1):page225_i181:b" )
			)
			( pin "C2D42.1"
				( objectStatus "@baseboard_fab2_lib.baseboard_fab2(sch_1):page225_i183:a" )
			)
			( pin "C2D42.2"
				( objectStatus "@baseboard_fab2_lib.baseboard_fab2(sch_1):page225_i183:b" )
			)
			( pin "C8P30.1"
				( objectStatus "@baseboard_fab2_lib.baseboard_fab2(sch_1):page225_i184:a" )
			)
			( pin "C8P30.2"
				( objectStatus "@baseboard_fab2_lib.baseboard_fab2(sch_1):page225_i184:b" )
			)
			( pin "C1G15.1"
				( objectStatus "@baseboard_fab2_lib.baseboard_fab2(sch_1):page225_i192:a" )
			)
			( pin "C1G15.2"
				( objectStatus "@baseboard_fab2_lib.baseboard_fab2(sch_1):page225_i192:b" )
			)
			( pin "C1G12.1"
				( objectStatus "@baseboard_fab2_lib.baseboard_fab2(sch_1):page225_i193:a" )
			)
			( pin "C1G12.2"
				( objectStatus "@baseboard_fab2_lib.baseboard_fab2(sch_1):page225_i193:b" )
			)
			( pin "C1G2.1"
				( objectStatus "@baseboard_fab2_lib.baseboard_fab2(sch_1):page225_i194:a" )
			)
			( pin "C1G2.2"
				( objectStatus "@baseboard_fab2_lib.baseboard_fab2(sch_1):page225_i194:b" )
			)
			( pin "C1G7.1"
				( objectStatus "@baseboard_fab2_lib.baseboard_fab2(sch_1):page225_i195:a" )
			)
			( pin "C1G7.2"
				( objectStatus "@baseboard_fab2_lib.baseboard_fab2(sch_1):page225_i195:b" )
			)
			( pin "C8T4.1"
				( objectStatus "@baseboard_fab2_lib.baseboard_fab2(sch_1):page225_i196:a" )
			)
			( pin "C8T4.2"
				( objectStatus "@baseboard_fab2_lib.baseboard_fab2(sch_1):page225_i196:b" )
			)
			( pin "C2G8.1"
				( objectStatus "@baseboard_fab2_lib.baseboard_fab2(sch_1):page225_i197:a" )
			)
			( pin "C2G8.2"
				( objectStatus "@baseboard_fab2_lib.baseboard_fab2(sch_1):page225_i197:b" )
			)
			( pin "C8T2.1"
				( objectStatus "@baseboard_fab2_lib.baseboard_fab2(sch_1):page225_i198:a" )
			)
			( pin "C8T2.2"
				( objectStatus "@baseboard_fab2_lib.baseboard_fab2(sch_1):page225_i198:b" )
			)
			( pin "C8U13.1"
				( objectStatus "@baseboard_fab2_lib.baseboard_fab2(sch_1):page225_i199:a" )
			)
			( pin "C8U13.2"
				( objectStatus "@baseboard_fab2_lib.baseboard_fab2(sch_1):page225_i199:b" )
			)
			( pin "C2G15.1"
				( objectStatus "@baseboard_fab2_lib.baseboard_fab2(sch_1):page225_i200:a" )
			)
			( pin "C2G15.2"
				( objectStatus "@baseboard_fab2_lib.baseboard_fab2(sch_1):page225_i200:b" )
			)
			( pin "C2F1.1"
				( objectStatus "@baseboard_fab2_lib.baseboard_fab2(sch_1):page225_i201:a" )
			)
			( pin "C2F1.2"
				( objectStatus "@baseboard_fab2_lib.baseboard_fab2(sch_1):page225_i201:b" )
			)
			( pin "C8T1.1"
				( objectStatus "@baseboard_fab2_lib.baseboard_fab2(sch_1):page225_i202:a" )
			)
			( pin "C8T1.2"
				( objectStatus "@baseboard_fab2_lib.baseboard_fab2(sch_1):page225_i202:b" )
			)
			( pin "C8U9.1"
				( objectStatus "@baseboard_fab2_lib.baseboard_fab2(sch_1):page225_i203:a" )
			)
			( pin "C8U9.2"
				( objectStatus "@baseboard_fab2_lib.baseboard_fab2(sch_1):page225_i203:b" )
			)
			( pin "C8T11.1"
				( objectStatus "@baseboard_fab2_lib.baseboard_fab2(sch_1):page225_i204:a" )
			)
			( pin "C8T11.2"
				( objectStatus "@baseboard_fab2_lib.baseboard_fab2(sch_1):page225_i204:b" )
			)
			( pin "C3G6.1"
				( objectStatus "@baseboard_fab2_lib.baseboard_fab2(sch_1):page225_i207:a" )
			)
			( pin "C3G6.2"
				( objectStatus "@baseboard_fab2_lib.baseboard_fab2(sch_1):page225_i207:b" )
			)
			( pin "C3G5.1"
				( objectStatus "@baseboard_fab2_lib.baseboard_fab2(sch_1):page225_i208:a" )
			)
			( pin "C3G5.2"
				( objectStatus "@baseboard_fab2_lib.baseboard_fab2(sch_1):page225_i208:b" )
			)
			( pin "C2G14.1"
				( objectStatus "@baseboard_fab2_lib.baseboard_fab2(sch_1):page225_i209:a" )
			)
			( pin "C2G14.2"
				( objectStatus "@baseboard_fab2_lib.baseboard_fab2(sch_1):page225_i209:b" )
			)
			( pin "C2G13.1"
				( objectStatus "@baseboard_fab2_lib.baseboard_fab2(sch_1):page225_i210:a" )
			)
			( pin "C2G13.2"
				( objectStatus "@baseboard_fab2_lib.baseboard_fab2(sch_1):page225_i210:b" )
			)
			( pin "C3G2.1"
				( objectStatus "@baseboard_fab2_lib.baseboard_fab2(sch_1):page225_i211:a" )
			)
			( pin "C3G2.2"
				( objectStatus "@baseboard_fab2_lib.baseboard_fab2(sch_1):page225_i211:b" )
			)
			( pin "C3G1.1"
				( objectStatus "@baseboard_fab2_lib.baseboard_fab2(sch_1):page225_i212:a" )
			)
			( pin "C3G1.2"
				( objectStatus "@baseboard_fab2_lib.baseboard_fab2(sch_1):page225_i212:b" )
			)
			( pin "C2G6.1"
				( objectStatus "@baseboard_fab2_lib.baseboard_fab2(sch_1):page225_i213:a" )
			)
			( pin "C2G6.2"
				( objectStatus "@baseboard_fab2_lib.baseboard_fab2(sch_1):page225_i213:b" )
			)
			( pin "C2G5.1"
				( objectStatus "@baseboard_fab2_lib.baseboard_fab2(sch_1):page225_i214:a" )
			)
			( pin "C2G5.2"
				( objectStatus "@baseboard_fab2_lib.baseboard_fab2(sch_1):page225_i214:b" )
			)
			( pin "C2G4.1"
				( objectStatus "@baseboard_fab2_lib.baseboard_fab2(sch_1):page225_i215:a" )
			)
			( pin "C2G4.2"
				( objectStatus "@baseboard_fab2_lib.baseboard_fab2(sch_1):page225_i215:b" )
			)
			( pin "C2G3.1"
				( objectStatus "@baseboard_fab2_lib.baseboard_fab2(sch_1):page225_i216:a" )
			)
			( pin "C2G3.2"
				( objectStatus "@baseboard_fab2_lib.baseboard_fab2(sch_1):page225_i216:b" )
			)
			( pin "C2G2.1"
				( objectStatus "@baseboard_fab2_lib.baseboard_fab2(sch_1):page225_i217:a" )
			)
			( pin "C2G2.2"
				( objectStatus "@baseboard_fab2_lib.baseboard_fab2(sch_1):page225_i217:b" )
			)
			( pin "C2G9.1"
				( objectStatus "@baseboard_fab2_lib.baseboard_fab2(sch_1):page225_i218:a" )
			)
			( pin "C2G9.2"
				( objectStatus "@baseboard_fab2_lib.baseboard_fab2(sch_1):page225_i218:b" )
			)
			( pin "C2G1.1"
				( objectStatus "@baseboard_fab2_lib.baseboard_fab2(sch_1):page225_i219:a" )
			)
			( pin "C2G1.2"
				( objectStatus "@baseboard_fab2_lib.baseboard_fab2(sch_1):page225_i219:b" )
			)
			( pin "C2G12.1"
				( objectStatus "@baseboard_fab2_lib.baseboard_fab2(sch_1):page225_i220:a" )
			)
			( pin "C2G12.2"
				( objectStatus "@baseboard_fab2_lib.baseboard_fab2(sch_1):page225_i220:b" )
			)
			( pin "C2G11.1"
				( objectStatus "@baseboard_fab2_lib.baseboard_fab2(sch_1):page225_i221:a" )
			)
			( pin "C2G11.2"
				( objectStatus "@baseboard_fab2_lib.baseboard_fab2(sch_1):page225_i221:b" )
			)
			( pin "C2G10.1"
				( objectStatus "@baseboard_fab2_lib.baseboard_fab2(sch_1):page225_i223:a" )
			)
			( pin "C2G10.2"
				( objectStatus "@baseboard_fab2_lib.baseboard_fab2(sch_1):page225_i223:b" )
			)
			( pin "C8U4.1"
				( objectStatus "@baseboard_fab2_lib.baseboard_fab2(sch_1):page225_i225:a" )
			)
			( pin "C8U4.2"
				( objectStatus "@baseboard_fab2_lib.baseboard_fab2(sch_1):page225_i225:b" )
			)
			( pin "C8T10.1"
				( objectStatus "@baseboard_fab2_lib.baseboard_fab2(sch_1):page225_i226:a" )
			)
			( pin "C8T10.2"
				( objectStatus "@baseboard_fab2_lib.baseboard_fab2(sch_1):page225_i226:b" )
			)
			( pin "C8T9.1"
				( objectStatus "@baseboard_fab2_lib.baseboard_fab2(sch_1):page225_i227:a" )
			)
			( pin "C8T9.2"
				( objectStatus "@baseboard_fab2_lib.baseboard_fab2(sch_1):page225_i227:b" )
			)
			( pin "C8U5.1"
				( objectStatus "@baseboard_fab2_lib.baseboard_fab2(sch_1):page225_i228:a" )
			)
			( pin "C8U5.2"
				( objectStatus "@baseboard_fab2_lib.baseboard_fab2(sch_1):page225_i228:b" )
			)
			( pin "C8T8.1"
				( objectStatus "@baseboard_fab2_lib.baseboard_fab2(sch_1):page225_i229:a" )
			)
			( pin "C8T8.2"
				( objectStatus "@baseboard_fab2_lib.baseboard_fab2(sch_1):page225_i229:b" )
			)
			( pin "C8T7.1"
				( objectStatus "@baseboard_fab2_lib.baseboard_fab2(sch_1):page225_i230:a" )
			)
			( pin "C8T7.2"
				( objectStatus "@baseboard_fab2_lib.baseboard_fab2(sch_1):page225_i230:b" )
			)
			( pin "C8T6.1"
				( objectStatus "@baseboard_fab2_lib.baseboard_fab2(sch_1):page225_i231:a" )
			)
			( pin "C8T6.2"
				( objectStatus "@baseboard_fab2_lib.baseboard_fab2(sch_1):page225_i231:b" )
			)
			( pin "C8U6.1"
				( objectStatus "@baseboard_fab2_lib.baseboard_fab2(sch_1):page225_i232:a" )
			)
			( pin "C8U6.2"
				( objectStatus "@baseboard_fab2_lib.baseboard_fab2(sch_1):page225_i232:b" )
			)
			( pin "C8T5.1"
				( objectStatus "@baseboard_fab2_lib.baseboard_fab2(sch_1):page225_i233:a" )
			)
			( pin "C8T5.2"
				( objectStatus "@baseboard_fab2_lib.baseboard_fab2(sch_1):page225_i233:b" )
			)
			( pin "C7T5.1"
				( objectStatus "@baseboard_fab2_lib.baseboard_fab2(sch_1):page225_i234:a" )
			)
			( pin "C7T5.2"
				( objectStatus "@baseboard_fab2_lib.baseboard_fab2(sch_1):page225_i234:b" )
			)
			( pin "C7T4.1"
				( objectStatus "@baseboard_fab2_lib.baseboard_fab2(sch_1):page225_i235:a" )
			)
			( pin "C7T4.2"
				( objectStatus "@baseboard_fab2_lib.baseboard_fab2(sch_1):page225_i235:b" )
			)
			( pin "C8U3.1"
				( objectStatus "@baseboard_fab2_lib.baseboard_fab2(sch_1):page225_i236:a" )
			)
			( pin "C8U3.2"
				( objectStatus "@baseboard_fab2_lib.baseboard_fab2(sch_1):page225_i236:b" )
			)
			( pin "C7U1.1"
				( objectStatus "@baseboard_fab2_lib.baseboard_fab2(sch_1):page225_i237:a" )
			)
			( pin "C7U1.2"
				( objectStatus "@baseboard_fab2_lib.baseboard_fab2(sch_1):page225_i237:b" )
			)
			( pin "C7U2.1"
				( objectStatus "@baseboard_fab2_lib.baseboard_fab2(sch_1):page225_i238:a" )
			)
			( pin "C7U2.2"
				( objectStatus "@baseboard_fab2_lib.baseboard_fab2(sch_1):page225_i238:b" )
			)
			( pin "C8U2.1"
				( objectStatus "@baseboard_fab2_lib.baseboard_fab2(sch_1):page225_i239:a" )
			)
			( pin "C8U2.2"
				( objectStatus "@baseboard_fab2_lib.baseboard_fab2(sch_1):page225_i239:b" )
			)
			( pin "C8U7.1"
				( objectStatus "@baseboard_fab2_lib.baseboard_fab2(sch_1):page225_i241:a" )
			)
			( pin "C8U7.2"
				( objectStatus "@baseboard_fab2_lib.baseboard_fab2(sch_1):page225_i241:b" )
			)
			( pin "SH7U1.1"
				( objectStatus "@baseboard_fab2_lib.baseboard_fab2(sch_1):page225_i243:a" )
			)
			( pin "SH7U1.2"
				( objectStatus "@baseboard_fab2_lib.baseboard_fab2(sch_1):page225_i243:b" )
			)
			( pin "SH7U2.1"
				( objectStatus "@baseboard_fab2_lib.baseboard_fab2(sch_1):page225_i244:a" )
			)
			( pin "SH7U2.2"
				( objectStatus "@baseboard_fab2_lib.baseboard_fab2(sch_1):page225_i244:b" )
			)
			( pin "R9M7.1"
				( objectStatus "@baseboard_fab2_lib.baseboard_fab2(sch_1):page226_i8:a" )
			)
			( pin "R9M7.2"
				( objectStatus "@baseboard_fab2_lib.baseboard_fab2(sch_1):page226_i8:b" )
			)
			( pin "R1B13.1"
				( objectStatus "@baseboard_fab2_lib.baseboard_fab2(sch_1):page226_i13:a" )
			)
			( pin "R1B13.2"
				( objectStatus "@baseboard_fab2_lib.baseboard_fab2(sch_1):page226_i13:b" )
			)
			( pin "R1B5.1"
				( objectStatus "@baseboard_fab2_lib.baseboard_fab2(sch_1):page226_i14:a" )
			)
			( pin "R1B5.2"
				( objectStatus "@baseboard_fab2_lib.baseboard_fab2(sch_1):page226_i14:b" )
			)
			( pin "R1B11.1"
				( objectStatus "@baseboard_fab2_lib.baseboard_fab2(sch_1):page226_i16:a" )
			)
			( pin "R1B11.2"
				( objectStatus "@baseboard_fab2_lib.baseboard_fab2(sch_1):page226_i16:b" )
			)
			( pin "R1B2.1"
				( objectStatus "@baseboard_fab2_lib.baseboard_fab2(sch_1):page226_i17:a" )
			)
			( pin "R1B2.2"
				( objectStatus "@baseboard_fab2_lib.baseboard_fab2(sch_1):page226_i17:b" )
			)
			( pin "R1B6.1"
				( objectStatus "@baseboard_fab2_lib.baseboard_fab2(sch_1):page226_i21:a" )
			)
			( pin "R1B6.2"
				( objectStatus "@baseboard_fab2_lib.baseboard_fab2(sch_1):page226_i21:b" )
			)
			( pin "R1B7.1"
				( objectStatus "@baseboard_fab2_lib.baseboard_fab2(sch_1):page226_i22:a" )
			)
			( pin "R1B7.2"
				( objectStatus "@baseboard_fab2_lib.baseboard_fab2(sch_1):page226_i22:b" )
			)
			( pin "R1B10.1"
				( objectStatus "@baseboard_fab2_lib.baseboard_fab2(sch_1):page226_i23:a" )
			)
			( pin "R1B10.2"
				( objectStatus "@baseboard_fab2_lib.baseboard_fab2(sch_1):page226_i23:b" )
			)
			( pin "C1B6.1"
				( objectStatus "@baseboard_fab2_lib.baseboard_fab2(sch_1):page226_i25:a" )
			)
			( pin "C1B6.2"
				( objectStatus "@baseboard_fab2_lib.baseboard_fab2(sch_1):page226_i25:b" )
			)
			( pin "C1B5.1"
				( objectStatus "@baseboard_fab2_lib.baseboard_fab2(sch_1):page226_i27:a" )
			)
			( pin "C1B5.2"
				( objectStatus "@baseboard_fab2_lib.baseboard_fab2(sch_1):page226_i27:b" )
			)
			( pin "R9M3.1"
				( objectStatus "@baseboard_fab2_lib.baseboard_fab2(sch_1):page226_i30:a" )
			)
			( pin "R9M3.2"
				( objectStatus "@baseboard_fab2_lib.baseboard_fab2(sch_1):page226_i30:b" )
			)
			( pin "R1B16.1"
				( objectStatus "@baseboard_fab2_lib.baseboard_fab2(sch_1):page226_i32:a" )
			)
			( pin "R1B16.2"
				( objectStatus "@baseboard_fab2_lib.baseboard_fab2(sch_1):page226_i32:b" )
			)
			( pin "C1B11.1"
				( objectStatus "@baseboard_fab2_lib.baseboard_fab2(sch_1):page226_i36:a" )
			)
			( pin "C1B11.2"
				( objectStatus "@baseboard_fab2_lib.baseboard_fab2(sch_1):page226_i36:b" )
			)
			( pin "C1B12.1"
				( objectStatus "@baseboard_fab2_lib.baseboard_fab2(sch_1):page226_i39:a" )
			)
			( pin "C1B12.2"
				( objectStatus "@baseboard_fab2_lib.baseboard_fab2(sch_1):page226_i39:b" )
			)
			( pin "C1B3.1"
				( objectStatus "@baseboard_fab2_lib.baseboard_fab2(sch_1):page226_i41:a" )
			)
			( pin "C1B3.2"
				( objectStatus "@baseboard_fab2_lib.baseboard_fab2(sch_1):page226_i41:b" )
			)
			( pin "C1B2.1"
				( objectStatus "@baseboard_fab2_lib.baseboard_fab2(sch_1):page226_i44:a" )
			)
			( pin "C1B2.2"
				( objectStatus "@baseboard_fab2_lib.baseboard_fab2(sch_1):page226_i44:b" )
			)
			( pin "R9M6.1"
				( objectStatus "@baseboard_fab2_lib.baseboard_fab2(sch_1):page226_i50:a" )
			)
			( pin "R9M6.2"
				( objectStatus "@baseboard_fab2_lib.baseboard_fab2(sch_1):page226_i50:b" )
			)
			( pin "R1B8.1"
				( objectStatus "@baseboard_fab2_lib.baseboard_fab2(sch_1):page226_i53:a" )
			)
			( pin "R1B8.2"
				( objectStatus "@baseboard_fab2_lib.baseboard_fab2(sch_1):page226_i53:b" )
			)
			( pin "R9M8.1"
				( objectStatus "@baseboard_fab2_lib.baseboard_fab2(sch_1):page226_i57:a" )
			)
			( pin "R9M8.2"
				( objectStatus "@baseboard_fab2_lib.baseboard_fab2(sch_1):page226_i57:b" )
			)
			( pin "R1B9.1"
				( objectStatus "@baseboard_fab2_lib.baseboard_fab2(sch_1):page226_i58:a" )
			)
			( pin "R1B9.2"
				( objectStatus "@baseboard_fab2_lib.baseboard_fab2(sch_1):page226_i58:b" )
			)
			( pin "C1B8.1"
				( objectStatus "@baseboard_fab2_lib.baseboard_fab2(sch_1):page226_i59:a" )
			)
			( pin "C1B8.2"
				( objectStatus "@baseboard_fab2_lib.baseboard_fab2(sch_1):page226_i59:b" )
			)
			( pin "R1B15.1"
				( objectStatus "@baseboard_fab2_lib.baseboard_fab2(sch_1):page226_i77:a" )
			)
			( pin "R1B15.2"
				( objectStatus "@baseboard_fab2_lib.baseboard_fab2(sch_1):page226_i77:b" )
			)
			( pin "R1B12.1"
				( objectStatus "@baseboard_fab2_lib.baseboard_fab2(sch_1):page226_i78:a" )
			)
			( pin "R1B12.2"
				( objectStatus "@baseboard_fab2_lib.baseboard_fab2(sch_1):page226_i78:b" )
			)
			( pin "R1B1.1"
				( objectStatus "@baseboard_fab2_lib.baseboard_fab2(sch_1):page226_i79:a" )
			)
			( pin "R1B1.2"
				( objectStatus "@baseboard_fab2_lib.baseboard_fab2(sch_1):page226_i79:b" )
			)
			( pin "C1B4.1"
				( objectStatus "@baseboard_fab2_lib.baseboard_fab2(sch_1):page226_i80:a" )
			)
			( pin "C1B4.2"
				( objectStatus "@baseboard_fab2_lib.baseboard_fab2(sch_1):page226_i80:b" )
			)
			( pin "R1B4.1"
				( objectStatus "@baseboard_fab2_lib.baseboard_fab2(sch_1):page226_i82:a" )
			)
			( pin "R1B4.2"
				( objectStatus "@baseboard_fab2_lib.baseboard_fab2(sch_1):page226_i82:b" )
			)
			( pin "R9M9.1"
				( objectStatus "@baseboard_fab2_lib.baseboard_fab2(sch_1):page226_i84:a" )
			)
			( pin "R9M9.2"
				( objectStatus "@baseboard_fab2_lib.baseboard_fab2(sch_1):page226_i84:b" )
			)
			( pin "R9M5.1"
				( objectStatus "@baseboard_fab2_lib.baseboard_fab2(sch_1):page226_i85:a" )
			)
			( pin "R9M5.2"
				( objectStatus "@baseboard_fab2_lib.baseboard_fab2(sch_1):page226_i85:b" )
			)
			( pin "R9M11.1"
				( objectStatus "@baseboard_fab2_lib.baseboard_fab2(sch_1):page226_i87:a" )
			)
			( pin "R9M11.2"
				( objectStatus "@baseboard_fab2_lib.baseboard_fab2(sch_1):page226_i87:b" )
			)
			( pin "R9M10.1"
				( objectStatus "@baseboard_fab2_lib.baseboard_fab2(sch_1):page226_i88:a" )
			)
			( pin "R9M10.2"
				( objectStatus "@baseboard_fab2_lib.baseboard_fab2(sch_1):page226_i88:b" )
			)
			( pin "EU1B1.21"
				( objectStatus "@baseboard_fab2_lib.baseboard_fab2(sch_1):page226_i90:airef1" )
			)
			( pin "EU1B1.23"
				( objectStatus "@baseboard_fab2_lib.baseboard_fab2(sch_1):page226_i90:airef2" )
			)
			( pin "EU1B1.25"
				( objectStatus "@baseboard_fab2_lib.baseboard_fab2(sch_1):page226_i90:airef3" )
			)
			( pin "EU1B1.22"
				( objectStatus "@baseboard_fab2_lib.baseboard_fab2(sch_1):page226_i90:aisen1" )
			)
			( pin "EU1B1.24"
				( objectStatus "@baseboard_fab2_lib.baseboard_fab2(sch_1):page226_i90:aisen2" )
			)
			( pin "EU1B1.26"
				( objectStatus "@baseboard_fab2_lib.baseboard_fab2(sch_1):page226_i90:aisen3" )
			)
			( pin "EU1B1.5"
				( objectStatus "@baseboard_fab2_lib.baseboard_fab2(sch_1):page226_i90:apwm1" )
			)
			( pin "EU1B1.4"
				( objectStatus "@baseboard_fab2_lib.baseboard_fab2(sch_1):page226_i90:apwm2" )
			)
			( pin "EU1B1.3"
				( objectStatus "@baseboard_fab2_lib.baseboard_fab2(sch_1):page226_i90:apwm3" )
			)
			( pin "EU1B1.35"
				( objectStatus "@baseboard_fab2_lib.baseboard_fab2(sch_1):page226_i90:atsen" )
			)
			( pin "EU1B1.20"
				( objectStatus "@baseboard_fab2_lib.baseboard_fab2(sch_1):page226_i90:avref" )
			)
			( pin "EU1B1.10"
				( objectStatus "@baseboard_fab2_lib.baseboard_fab2(sch_1):page226_i90:avren" )
			)
			( pin "EU1B1.9"
				( objectStatus "@baseboard_fab2_lib.baseboard_fab2(sch_1):page226_i90:avrrdy" )
			)
			( pin "EU1B1.19"
				( objectStatus "@baseboard_fab2_lib.baseboard_fab2(sch_1):page226_i90:avsen" )
			)
			( pin "EU1B1.31"
				( objectStatus "@baseboard_fab2_lib.baseboard_fab2(sch_1):page226_i90:biref1" )
			)
			( pin "EU1B1.32"
				( objectStatus "@baseboard_fab2_lib.baseboard_fab2(sch_1):page226_i90:bisen1" )
			)
			( pin "EU1B1.1"
				( objectStatus "@baseboard_fab2_lib.baseboard_fab2(sch_1):page226_i90:bpwm1" )
			)
			( pin "EU1B1.34"
				( objectStatus "@baseboard_fab2_lib.baseboard_fab2(sch_1):page226_i90:btsen" )
			)
			( pin "EU1B1.30"
				( objectStatus "@baseboard_fab2_lib.baseboard_fab2(sch_1):page226_i90:bvref" )
			)
			( pin "EU1B1.29"
				( objectStatus "@baseboard_fab2_lib.baseboard_fab2(sch_1):page226_i90:bvsen" )
			)
			( pin "EU1B1.2"
				( objectStatus "@baseboard_fab2_lib.baseboard_fab2(sch_1):page226_i90:dnc(0)" )
			)
			( pin "EU1B1.28"
				( objectStatus "@baseboard_fab2_lib.baseboard_fab2(sch_1):page226_i90:dnc(1)" )
			)
			( pin "EU1B1.27"
				( objectStatus "@baseboard_fab2_lib.baseboard_fab2(sch_1):page226_i90:gnd" )
			)
			( pin "EU1B1.38"
				( objectStatus "@baseboard_fab2_lib.baseboard_fab2(sch_1):page226_i90:iinsen" )
			)
			( pin "EU1B1.13"
				( objectStatus "@baseboard_fab2_lib.baseboard_fab2(sch_1):page226_i90:mp0" )
			)
			( pin "EU1B1.14"
				( objectStatus "@baseboard_fab2_lib.baseboard_fab2(sch_1):page226_i90:mp1" )
			)
			( pin "EU1B1.18"
				( objectStatus "@baseboard_fab2_lib.baseboard_fab2(sch_1):page226_i90:mp2" )
			)
			( pin "EU1B1.12"
				( objectStatus "@baseboard_fab2_lib.baseboard_fab2(sch_1):page226_i90:pinalrt_n" )
			)
			( pin "EU1B1.8"
				( objectStatus "@baseboard_fab2_lib.baseboard_fab2(sch_1):page226_i90:reset_n" )
			)
			( pin "EU1B1.7"
				( objectStatus "@baseboard_fab2_lib.baseboard_fab2(sch_1):page226_i90:scl" )
			)
			( pin "EU1B1.6"
				( objectStatus "@baseboard_fab2_lib.baseboard_fab2(sch_1):page226_i90:sda" )
			)
			( pin "EU1B1.41"
				( objectStatus "@baseboard_fab2_lib.baseboard_fab2(sch_1):page226_i90:thpad" )
			)
			( pin "EU1B1.17"
				( objectStatus "@baseboard_fab2_lib.baseboard_fab2(sch_1):page226_i90:valrt_n" )
			)
			( pin "EU1B1.15"
				( objectStatus "@baseboard_fab2_lib.baseboard_fab2(sch_1):page226_i90:vclk" )
			)
			( pin "EU1B1.40"
				( objectStatus "@baseboard_fab2_lib.baseboard_fab2(sch_1):page226_i90:vd12" )
			)
			( pin "EU1B1.39"
				( objectStatus "@baseboard_fab2_lib.baseboard_fab2(sch_1):page226_i90:vdd" )
			)
			( pin "EU1B1.16"
				( objectStatus "@baseboard_fab2_lib.baseboard_fab2(sch_1):page226_i90:vdio" )
			)
			( pin "EU1B1.37"
				( objectStatus "@baseboard_fab2_lib.baseboard_fab2(sch_1):page226_i90:vinsen" )
			)
			( pin "EU1B1.11"
				( objectStatus "@baseboard_fab2_lib.baseboard_fab2(sch_1):page226_i90:vrhot_n" )
			)
			( pin "EU1B1.36"
				( objectStatus "@baseboard_fab2_lib.baseboard_fab2(sch_1):page226_i90:xaddr1" )
			)
			( pin "EU1B1.33"
				( objectStatus "@baseboard_fab2_lib.baseboard_fab2(sch_1):page226_i90:xaddr2" )
			)
			( pin "C9M11.1"
				( objectStatus "@baseboard_fab2_lib.baseboard_fab2(sch_1):page226_i92:a" )
			)
			( pin "C9M11.2"
				( objectStatus "@baseboard_fab2_lib.baseboard_fab2(sch_1):page226_i92:b" )
			)
			( pin "C1A12.1"
				( objectStatus "@baseboard_fab2_lib.baseboard_fab2(sch_1):page227_i6:a" )
			)
			( pin "C1A12.2"
				( objectStatus "@baseboard_fab2_lib.baseboard_fab2(sch_1):page227_i6:b" )
			)
			( pin "C1A18.1"
				( objectStatus "@baseboard_fab2_lib.baseboard_fab2(sch_1):page227_i44:a" )
			)
			( pin "C1A18.2"
				( objectStatus "@baseboard_fab2_lib.baseboard_fab2(sch_1):page227_i44:b" )
			)
			( pin "C9L11.1"
				( objectStatus "@baseboard_fab2_lib.baseboard_fab2(sch_1):page227_i45:a" )
			)
			( pin "C9L11.2"
				( objectStatus "@baseboard_fab2_lib.baseboard_fab2(sch_1):page227_i45:b" )
			)
			( pin "C9L10.1"
				( objectStatus "@baseboard_fab2_lib.baseboard_fab2(sch_1):page227_i46:a" )
			)
			( pin "C9L10.2"
				( objectStatus "@baseboard_fab2_lib.baseboard_fab2(sch_1):page227_i46:b" )
			)
			( pin "C9L6.1"
				( objectStatus "@baseboard_fab2_lib.baseboard_fab2(sch_1):page227_i47:a" )
			)
			( pin "C9L6.2"
				( objectStatus "@baseboard_fab2_lib.baseboard_fab2(sch_1):page227_i47:b" )
			)
			( pin "C1A19.1"
				( objectStatus "@baseboard_fab2_lib.baseboard_fab2(sch_1):page227_i48:a" )
			)
			( pin "C1A19.2"
				( objectStatus "@baseboard_fab2_lib.baseboard_fab2(sch_1):page227_i48:b" )
			)
			( pin "C1B20.1"
				( objectStatus "@baseboard_fab2_lib.baseboard_fab2(sch_1):page227_i50:a" )
			)
			( pin "C1B20.2"
				( objectStatus "@baseboard_fab2_lib.baseboard_fab2(sch_1):page227_i50:b" )
			)
			( pin "C1A10.1"
				( objectStatus "@baseboard_fab2_lib.baseboard_fab2(sch_1):page227_i51:a" )
			)
			( pin "C1A10.2"
				( objectStatus "@baseboard_fab2_lib.baseboard_fab2(sch_1):page227_i51:b" )
			)
			( pin "R9L9.1"
				( objectStatus "@baseboard_fab2_lib.baseboard_fab2(sch_1):page227_i52:a" )
			)
			( pin "R9L9.2"
				( objectStatus "@baseboard_fab2_lib.baseboard_fab2(sch_1):page227_i52:b" )
			)
			( pin "C1A2.1"
				( objectStatus "@baseboard_fab2_lib.baseboard_fab2(sch_1):page227_i53:a" )
			)
			( pin "C1A2.2"
				( objectStatus "@baseboard_fab2_lib.baseboard_fab2(sch_1):page227_i53:b" )
			)
			( pin "C1B21.1"
				( objectStatus "@baseboard_fab2_lib.baseboard_fab2(sch_1):page227_i54:a" )
			)
			( pin "C1B21.2"
				( objectStatus "@baseboard_fab2_lib.baseboard_fab2(sch_1):page227_i54:b" )
			)
			( pin "L1A2.1"
				( objectStatus "@baseboard_fab2_lib.baseboard_fab2(sch_1):page227_i55:ina" )
			)
			( pin "L1A2.2"
				( objectStatus "@baseboard_fab2_lib.baseboard_fab2(sch_1):page227_i55:inb" )
			)
			( pin "L1A1.1"
				( objectStatus "@baseboard_fab2_lib.baseboard_fab2(sch_1):page227_i65:ina" )
			)
			( pin "L1A1.2"
				( objectStatus "@baseboard_fab2_lib.baseboard_fab2(sch_1):page227_i65:inb" )
			)
			( pin "C1A1.1"
				( objectStatus "@baseboard_fab2_lib.baseboard_fab2(sch_1):page227_i68:a" )
			)
			( pin "C1A1.2"
				( objectStatus "@baseboard_fab2_lib.baseboard_fab2(sch_1):page227_i68:b" )
			)
			( pin "C1A13.1"
				( objectStatus "@baseboard_fab2_lib.baseboard_fab2(sch_1):page227_i72:a" )
			)
			( pin "C1A13.2"
				( objectStatus "@baseboard_fab2_lib.baseboard_fab2(sch_1):page227_i72:b" )
			)
			( pin "C1A11.1"
				( objectStatus "@baseboard_fab2_lib.baseboard_fab2(sch_1):page227_i73:a" )
			)
			( pin "C1A11.2"
				( objectStatus "@baseboard_fab2_lib.baseboard_fab2(sch_1):page227_i73:b" )
			)
			( pin "C1A8.1"
				( objectStatus "@baseboard_fab2_lib.baseboard_fab2(sch_1):page227_i75:a" )
			)
			( pin "C1A8.2"
				( objectStatus "@baseboard_fab2_lib.baseboard_fab2(sch_1):page227_i75:b" )
			)
			( pin "R9L4.1"
				( objectStatus "@baseboard_fab2_lib.baseboard_fab2(sch_1):page227_i76:a" )
			)
			( pin "R9L4.2"
				( objectStatus "@baseboard_fab2_lib.baseboard_fab2(sch_1):page227_i76:b" )
			)
			( pin "C1A6.1"
				( objectStatus "@baseboard_fab2_lib.baseboard_fab2(sch_1):page227_i77:a" )
			)
			( pin "C1A6.2"
				( objectStatus "@baseboard_fab2_lib.baseboard_fab2(sch_1):page227_i77:b" )
			)
			( pin "C1A20.1"
				( objectStatus "@baseboard_fab2_lib.baseboard_fab2(sch_1):page227_i78:a" )
			)
			( pin "C1A20.2"
				( objectStatus "@baseboard_fab2_lib.baseboard_fab2(sch_1):page227_i78:b" )
			)
			( pin "C1A9.1"
				( objectStatus "@baseboard_fab2_lib.baseboard_fab2(sch_1):page227_i79:a" )
			)
			( pin "C1A9.2"
				( objectStatus "@baseboard_fab2_lib.baseboard_fab2(sch_1):page227_i79:b" )
			)
			( pin "C9L5.1"
				( objectStatus "@baseboard_fab2_lib.baseboard_fab2(sch_1):page227_i80:a" )
			)
			( pin "C9L5.2"
				( objectStatus "@baseboard_fab2_lib.baseboard_fab2(sch_1):page227_i80:b" )
			)
			( pin "C9L13.1"
				( objectStatus "@baseboard_fab2_lib.baseboard_fab2(sch_1):page227_i81:a" )
			)
			( pin "C9L13.2"
				( objectStatus "@baseboard_fab2_lib.baseboard_fab2(sch_1):page227_i81:b" )
			)
			( pin "C9L14.1"
				( objectStatus "@baseboard_fab2_lib.baseboard_fab2(sch_1):page227_i84:a" )
			)
			( pin "C9L14.2"
				( objectStatus "@baseboard_fab2_lib.baseboard_fab2(sch_1):page227_i84:b" )
			)
			( pin "EU1A2.33"
				( objectStatus "@baseboard_fab2_lib.baseboard_fab2(sch_1):page227_i101:boost" )
			)
			( pin "EU1A2.35"
				( objectStatus "@baseboard_fab2_lib.baseboard_fab2(sch_1):page227_i101:en" )
			)
			( pin "EU1A2.6"
				( objectStatus "@baseboard_fab2_lib.baseboard_fab2(sch_1):page227_i101:gl(0)" )
			)
			( pin "EU1A2.41"
				( objectStatus "@baseboard_fab2_lib.baseboard_fab2(sch_1):page227_i101:gl(1)" )
			)
			( pin "EU1A2.38"
				( objectStatus "@baseboard_fab2_lib.baseboard_fab2(sch_1):page227_i101:iout" )
			)
			( pin "EU1A2.2"
				( objectStatus "@baseboard_fab2_lib.baseboard_fab2(sch_1):page227_i101:lgnd" )
			)
			( pin "EU1A2.31"
				( objectStatus "@baseboard_fab2_lib.baseboard_fab2(sch_1):page227_i101:nc" )
			)
			( pin "EU1A2.37"
				( objectStatus "@baseboard_fab2_lib.baseboard_fab2(sch_1):page227_i101:ocset" )
			)
			( pin "EU1A2.5"
				( objectStatus "@baseboard_fab2_lib.baseboard_fab2(sch_1):page227_i101:pgnd(0)" )
			)
			( pin "EU1A2.7"
				( objectStatus "@baseboard_fab2_lib.baseboard_fab2(sch_1):page227_i101:pgnd(1)" )
			)
			( pin "EU1A2.40"
				( objectStatus "@baseboard_fab2_lib.baseboard_fab2(sch_1):page227_i101:pgnd(2)" )
			)
			( pin "EU1A2.32"
				( objectStatus "@baseboard_fab2_lib.baseboard_fab2(sch_1):page227_i101:phase" )
			)
			( pin "EU1A2.34"
				( objectStatus "@baseboard_fab2_lib.baseboard_fab2(sch_1):page227_i101:pwm" )
			)
			( pin "EU1A2.39"
				( objectStatus "@baseboard_fab2_lib.baseboard_fab2(sch_1):page227_i101:refin" )
			)
			( pin "EU1A2.10"
				( objectStatus "@baseboard_fab2_lib.baseboard_fab2(sch_1):page227_i101:sw" )
			)
			( pin "EU1A2.36"
				( objectStatus "@baseboard_fab2_lib.baseboard_fab2(sch_1):page227_i101:tout_flt" )
			)
			( pin "EU1A2.3"
				( objectStatus "@baseboard_fab2_lib.baseboard_fab2(sch_1):page227_i101:vcc" )
			)
			( pin "EU1A2.4"
				( objectStatus "@baseboard_fab2_lib.baseboard_fab2(sch_1):page227_i101:vdrv" )
			)
			( pin "EU1A2.25"
				( objectStatus "@baseboard_fab2_lib.baseboard_fab2(sch_1):page227_i101:vin(0)" )
			)
			( pin "EU1A2.30"
				( objectStatus "@baseboard_fab2_lib.baseboard_fab2(sch_1):page227_i101:vin(1)" )
			)
			( pin "EU1A2.1"
				( objectStatus "@baseboard_fab2_lib.baseboard_fab2(sch_1):page227_i101:vos" )
			)
			( pin "EU1A1.33"
				( objectStatus "@baseboard_fab2_lib.baseboard_fab2(sch_1):page227_i102:boost" )
			)
			( pin "EU1A1.35"
				( objectStatus "@baseboard_fab2_lib.baseboard_fab2(sch_1):page227_i102:en" )
			)
			( pin "EU1A1.6"
				( objectStatus "@baseboard_fab2_lib.baseboard_fab2(sch_1):page227_i102:gl(0)" )
			)
			( pin "EU1A1.41"
				( objectStatus "@baseboard_fab2_lib.baseboard_fab2(sch_1):page227_i102:gl(1)" )
			)
			( pin "EU1A1.38"
				( objectStatus "@baseboard_fab2_lib.baseboard_fab2(sch_1):page227_i102:iout" )
			)
			( pin "EU1A1.2"
				( objectStatus "@baseboard_fab2_lib.baseboard_fab2(sch_1):page227_i102:lgnd" )
			)
			( pin "EU1A1.31"
				( objectStatus "@baseboard_fab2_lib.baseboard_fab2(sch_1):page227_i102:nc" )
			)
			( pin "EU1A1.37"
				( objectStatus "@baseboard_fab2_lib.baseboard_fab2(sch_1):page227_i102:ocset" )
			)
			( pin "EU1A1.5"
				( objectStatus "@baseboard_fab2_lib.baseboard_fab2(sch_1):page227_i102:pgnd(0)" )
			)
			( pin "EU1A1.7"
				( objectStatus "@baseboard_fab2_lib.baseboard_fab2(sch_1):page227_i102:pgnd(1)" )
			)
			( pin "EU1A1.40"
				( objectStatus "@baseboard_fab2_lib.baseboard_fab2(sch_1):page227_i102:pgnd(2)" )
			)
			( pin "EU1A1.32"
				( objectStatus "@baseboard_fab2_lib.baseboard_fab2(sch_1):page227_i102:phase" )
			)
			( pin "EU1A1.34"
				( objectStatus "@baseboard_fab2_lib.baseboard_fab2(sch_1):page227_i102:pwm" )
			)
			( pin "EU1A1.39"
				( objectStatus "@baseboard_fab2_lib.baseboard_fab2(sch_1):page227_i102:refin" )
			)
			( pin "EU1A1.10"
				( objectStatus "@baseboard_fab2_lib.baseboard_fab2(sch_1):page227_i102:sw" )
			)
			( pin "EU1A1.36"
				( objectStatus "@baseboard_fab2_lib.baseboard_fab2(sch_1):page227_i102:tout_flt" )
			)
			( pin "EU1A1.3"
				( objectStatus "@baseboard_fab2_lib.baseboard_fab2(sch_1):page227_i102:vcc" )
			)
			( pin "EU1A1.4"
				( objectStatus "@baseboard_fab2_lib.baseboard_fab2(sch_1):page227_i102:vdrv" )
			)
			( pin "EU1A1.25"
				( objectStatus "@baseboard_fab2_lib.baseboard_fab2(sch_1):page227_i102:vin(0)" )
			)
			( pin "EU1A1.30"
				( objectStatus "@baseboard_fab2_lib.baseboard_fab2(sch_1):page227_i102:vin(1)" )
			)
			( pin "EU1A1.1"
				( objectStatus "@baseboard_fab2_lib.baseboard_fab2(sch_1):page227_i102:vos" )
			)
			( pin "R1A3.1"
				( objectStatus "@baseboard_fab2_lib.baseboard_fab2(sch_1):page227_i103:a" )
			)
			( pin "R1A3.2"
				( objectStatus "@baseboard_fab2_lib.baseboard_fab2(sch_1):page227_i103:b" )
			)
			( pin "R1A2.1"
				( objectStatus "@baseboard_fab2_lib.baseboard_fab2(sch_1):page227_i105:a" )
			)
			( pin "R1A2.2"
				( objectStatus "@baseboard_fab2_lib.baseboard_fab2(sch_1):page227_i105:b" )
			)
			( pin "R1A1.1"
				( objectStatus "@baseboard_fab2_lib.baseboard_fab2(sch_1):page228_i58:a" )
			)
			( pin "R1A1.2"
				( objectStatus "@baseboard_fab2_lib.baseboard_fab2(sch_1):page228_i58:b" )
			)
			( pin "R7L2.1"
				( objectStatus "@baseboard_fab2_lib.baseboard_fab2(sch_1):page228_i74:a" )
			)
			( pin "R7L2.2"
				( objectStatus "@baseboard_fab2_lib.baseboard_fab2(sch_1):page228_i74:b" )
			)
			( pin "C9L9.1"
				( objectStatus "@baseboard_fab2_lib.baseboard_fab2(sch_1):page228_i75:a" )
			)
			( pin "C9L9.2"
				( objectStatus "@baseboard_fab2_lib.baseboard_fab2(sch_1):page228_i75:b" )
			)
			( pin "C9L12.1"
				( objectStatus "@baseboard_fab2_lib.baseboard_fab2(sch_1):page228_i76:a" )
			)
			( pin "C9L12.2"
				( objectStatus "@baseboard_fab2_lib.baseboard_fab2(sch_1):page228_i76:b" )
			)
			( pin "C9L4.1"
				( objectStatus "@baseboard_fab2_lib.baseboard_fab2(sch_1):page228_i77:a" )
			)
			( pin "C9L4.2"
				( objectStatus "@baseboard_fab2_lib.baseboard_fab2(sch_1):page228_i77:b" )
			)
			( pin "C9L2.1"
				( objectStatus "@baseboard_fab2_lib.baseboard_fab2(sch_1):page228_i78:a" )
			)
			( pin "C9L2.2"
				( objectStatus "@baseboard_fab2_lib.baseboard_fab2(sch_1):page228_i78:b" )
			)
			( pin "C2A8.1"
				( objectStatus "@baseboard_fab2_lib.baseboard_fab2(sch_1):page228_i82:a" )
			)
			( pin "C2A8.2"
				( objectStatus "@baseboard_fab2_lib.baseboard_fab2(sch_1):page228_i82:b" )
			)
			( pin "C8L2.1"
				( objectStatus "@baseboard_fab2_lib.baseboard_fab2(sch_1):page228_i83:a" )
			)
			( pin "C8L2.2"
				( objectStatus "@baseboard_fab2_lib.baseboard_fab2(sch_1):page228_i83:b" )
			)
			( pin "C8L11.1"
				( objectStatus "@baseboard_fab2_lib.baseboard_fab2(sch_1):page228_i88:a" )
			)
			( pin "C8L11.2"
				( objectStatus "@baseboard_fab2_lib.baseboard_fab2(sch_1):page228_i88:b" )
			)
			( pin "C2A16.1"
				( objectStatus "@baseboard_fab2_lib.baseboard_fab2(sch_1):page228_i89:a" )
			)
			( pin "C2A16.2"
				( objectStatus "@baseboard_fab2_lib.baseboard_fab2(sch_1):page228_i89:b" )
			)
			( pin "C8M7.1"
				( objectStatus "@baseboard_fab2_lib.baseboard_fab2(sch_1):page228_i90:a" )
			)
			( pin "C8M7.2"
				( objectStatus "@baseboard_fab2_lib.baseboard_fab2(sch_1):page228_i90:b" )
			)
			( pin "C8M11.1"
				( objectStatus "@baseboard_fab2_lib.baseboard_fab2(sch_1):page228_i91:a" )
			)
			( pin "C8M11.2"
				( objectStatus "@baseboard_fab2_lib.baseboard_fab2(sch_1):page228_i91:b" )
			)
			( pin "C7L1.1"
				( objectStatus "@baseboard_fab2_lib.baseboard_fab2(sch_1):page228_i92:a" )
			)
			( pin "C7L1.2"
				( objectStatus "@baseboard_fab2_lib.baseboard_fab2(sch_1):page228_i92:b" )
			)
			( pin "C8L1.1"
				( objectStatus "@baseboard_fab2_lib.baseboard_fab2(sch_1):page228_i110:a" )
			)
			( pin "C8L1.2"
				( objectStatus "@baseboard_fab2_lib.baseboard_fab2(sch_1):page228_i110:b" )
			)
			( pin "L1B1.1"
				( objectStatus "@baseboard_fab2_lib.baseboard_fab2(sch_1):page228_i124:ina" )
			)
			( pin "L1B1.2"
				( objectStatus "@baseboard_fab2_lib.baseboard_fab2(sch_1):page228_i124:inb" )
			)
			( pin "C1B10.1"
				( objectStatus "@baseboard_fab2_lib.baseboard_fab2(sch_1):page228_i175:a" )
			)
			( pin "C1B10.2"
				( objectStatus "@baseboard_fab2_lib.baseboard_fab2(sch_1):page228_i175:b" )
			)
			( pin "C8P2.1"
				( objectStatus "@baseboard_fab2_lib.baseboard_fab2(sch_1):page228_i183:a" )
			)
			( pin "C8P2.2"
				( objectStatus "@baseboard_fab2_lib.baseboard_fab2(sch_1):page228_i183:b" )
			)
			( pin "C8P1.1"
				( objectStatus "@baseboard_fab2_lib.baseboard_fab2(sch_1):page228_i185:a" )
			)
			( pin "C8P1.2"
				( objectStatus "@baseboard_fab2_lib.baseboard_fab2(sch_1):page228_i185:b" )
			)
			( pin "C2D7.1"
				( objectStatus "@baseboard_fab2_lib.baseboard_fab2(sch_1):page228_i186:a" )
			)
			( pin "C2D7.2"
				( objectStatus "@baseboard_fab2_lib.baseboard_fab2(sch_1):page228_i186:b" )
			)
			( pin "C2D4.1"
				( objectStatus "@baseboard_fab2_lib.baseboard_fab2(sch_1):page228_i187:a" )
			)
			( pin "C2D4.2"
				( objectStatus "@baseboard_fab2_lib.baseboard_fab2(sch_1):page228_i187:b" )
			)
			( pin "C2D5.1"
				( objectStatus "@baseboard_fab2_lib.baseboard_fab2(sch_1):page228_i188:a" )
			)
			( pin "C2D5.2"
				( objectStatus "@baseboard_fab2_lib.baseboard_fab2(sch_1):page228_i188:b" )
			)
			( pin "C2D6.1"
				( objectStatus "@baseboard_fab2_lib.baseboard_fab2(sch_1):page228_i190:a" )
			)
			( pin "C2D6.2"
				( objectStatus "@baseboard_fab2_lib.baseboard_fab2(sch_1):page228_i190:b" )
			)
			( pin "C8M8.1"
				( objectStatus "@baseboard_fab2_lib.baseboard_fab2(sch_1):page228_i198:a" )
			)
			( pin "C8M8.2"
				( objectStatus "@baseboard_fab2_lib.baseboard_fab2(sch_1):page228_i198:b" )
			)
			( pin "C2A5.1"
				( objectStatus "@baseboard_fab2_lib.baseboard_fab2(sch_1):page228_i199:a" )
			)
			( pin "C2A5.2"
				( objectStatus "@baseboard_fab2_lib.baseboard_fab2(sch_1):page228_i199:b" )
			)
			( pin "C2B1.1"
				( objectStatus "@baseboard_fab2_lib.baseboard_fab2(sch_1):page228_i200:a" )
			)
			( pin "C2B1.2"
				( objectStatus "@baseboard_fab2_lib.baseboard_fab2(sch_1):page228_i200:b" )
			)
			( pin "C8L12.1"
				( objectStatus "@baseboard_fab2_lib.baseboard_fab2(sch_1):page228_i201:a" )
			)
			( pin "C8L12.2"
				( objectStatus "@baseboard_fab2_lib.baseboard_fab2(sch_1):page228_i201:b" )
			)
			( pin "C7M5.1"
				( objectStatus "@baseboard_fab2_lib.baseboard_fab2(sch_1):page228_i202:a" )
			)
			( pin "C7M5.2"
				( objectStatus "@baseboard_fab2_lib.baseboard_fab2(sch_1):page228_i202:b" )
			)
			( pin "C8M10.1"
				( objectStatus "@baseboard_fab2_lib.baseboard_fab2(sch_1):page228_i203:a" )
			)
			( pin "C8M10.2"
				( objectStatus "@baseboard_fab2_lib.baseboard_fab2(sch_1):page228_i203:b" )
			)
			( pin "C2B2.1"
				( objectStatus "@baseboard_fab2_lib.baseboard_fab2(sch_1):page228_i204:a" )
			)
			( pin "C2B2.2"
				( objectStatus "@baseboard_fab2_lib.baseboard_fab2(sch_1):page228_i204:b" )
			)
			( pin "C8M9.1"
				( objectStatus "@baseboard_fab2_lib.baseboard_fab2(sch_1):page228_i205:a" )
			)
			( pin "C8M9.2"
				( objectStatus "@baseboard_fab2_lib.baseboard_fab2(sch_1):page228_i205:b" )
			)
			( pin "C8M2.1"
				( objectStatus "@baseboard_fab2_lib.baseboard_fab2(sch_1):page228_i206:a" )
			)
			( pin "C8M2.2"
				( objectStatus "@baseboard_fab2_lib.baseboard_fab2(sch_1):page228_i206:b" )
			)
			( pin "C2A2.1"
				( objectStatus "@baseboard_fab2_lib.baseboard_fab2(sch_1):page228_i209:a" )
			)
			( pin "C2A2.2"
				( objectStatus "@baseboard_fab2_lib.baseboard_fab2(sch_1):page228_i209:b" )
			)
			( pin "C2A1.1"
				( objectStatus "@baseboard_fab2_lib.baseboard_fab2(sch_1):page228_i210:a" )
			)
			( pin "C2A1.2"
				( objectStatus "@baseboard_fab2_lib.baseboard_fab2(sch_1):page228_i210:b" )
			)
			( pin "C2A12.1"
				( objectStatus "@baseboard_fab2_lib.baseboard_fab2(sch_1):page228_i211:a" )
			)
			( pin "C2A12.2"
				( objectStatus "@baseboard_fab2_lib.baseboard_fab2(sch_1):page228_i211:b" )
			)
			( pin "C2A13.1"
				( objectStatus "@baseboard_fab2_lib.baseboard_fab2(sch_1):page228_i212:a" )
			)
			( pin "C2A13.2"
				( objectStatus "@baseboard_fab2_lib.baseboard_fab2(sch_1):page228_i212:b" )
			)
			( pin "C2A11.1"
				( objectStatus "@baseboard_fab2_lib.baseboard_fab2(sch_1):page228_i213:a" )
			)
			( pin "C2A11.2"
				( objectStatus "@baseboard_fab2_lib.baseboard_fab2(sch_1):page228_i213:b" )
			)
			( pin "C2A10.1"
				( objectStatus "@baseboard_fab2_lib.baseboard_fab2(sch_1):page228_i214:a" )
			)
			( pin "C2A10.2"
				( objectStatus "@baseboard_fab2_lib.baseboard_fab2(sch_1):page228_i214:b" )
			)
			( pin "C2A9.1"
				( objectStatus "@baseboard_fab2_lib.baseboard_fab2(sch_1):page228_i215:a" )
			)
			( pin "C2A9.2"
				( objectStatus "@baseboard_fab2_lib.baseboard_fab2(sch_1):page228_i215:b" )
			)
			( pin "C3A2.1"
				( objectStatus "@baseboard_fab2_lib.baseboard_fab2(sch_1):page228_i216:a" )
			)
			( pin "C3A2.2"
				( objectStatus "@baseboard_fab2_lib.baseboard_fab2(sch_1):page228_i216:b" )
			)
			( pin "C3A1.1"
				( objectStatus "@baseboard_fab2_lib.baseboard_fab2(sch_1):page228_i217:a" )
			)
			( pin "C3A1.2"
				( objectStatus "@baseboard_fab2_lib.baseboard_fab2(sch_1):page228_i217:b" )
			)
			( pin "C2A7.1"
				( objectStatus "@baseboard_fab2_lib.baseboard_fab2(sch_1):page228_i218:a" )
			)
			( pin "C2A7.2"
				( objectStatus "@baseboard_fab2_lib.baseboard_fab2(sch_1):page228_i218:b" )
			)
			( pin "C2A6.1"
				( objectStatus "@baseboard_fab2_lib.baseboard_fab2(sch_1):page228_i219:a" )
			)
			( pin "C2A6.2"
				( objectStatus "@baseboard_fab2_lib.baseboard_fab2(sch_1):page228_i219:b" )
			)
			( pin "C2A14.1"
				( objectStatus "@baseboard_fab2_lib.baseboard_fab2(sch_1):page228_i220:a" )
			)
			( pin "C2A14.2"
				( objectStatus "@baseboard_fab2_lib.baseboard_fab2(sch_1):page228_i220:b" )
			)
			( pin "C2A15.1"
				( objectStatus "@baseboard_fab2_lib.baseboard_fab2(sch_1):page228_i221:a" )
			)
			( pin "C2A15.2"
				( objectStatus "@baseboard_fab2_lib.baseboard_fab2(sch_1):page228_i221:b" )
			)
			( pin "C3A5.1"
				( objectStatus "@baseboard_fab2_lib.baseboard_fab2(sch_1):page228_i222:a" )
			)
			( pin "C3A5.2"
				( objectStatus "@baseboard_fab2_lib.baseboard_fab2(sch_1):page228_i222:b" )
			)
			( pin "C3A6.1"
				( objectStatus "@baseboard_fab2_lib.baseboard_fab2(sch_1):page228_i223:a" )
			)
			( pin "C3A6.2"
				( objectStatus "@baseboard_fab2_lib.baseboard_fab2(sch_1):page228_i223:b" )
			)
			( pin "C7L5.1"
				( objectStatus "@baseboard_fab2_lib.baseboard_fab2(sch_1):page228_i225:a" )
			)
			( pin "C7L5.2"
				( objectStatus "@baseboard_fab2_lib.baseboard_fab2(sch_1):page228_i225:b" )
			)
			( pin "C8M3.1"
				( objectStatus "@baseboard_fab2_lib.baseboard_fab2(sch_1):page228_i227:a" )
			)
			( pin "C8M3.2"
				( objectStatus "@baseboard_fab2_lib.baseboard_fab2(sch_1):page228_i227:b" )
			)
			( pin "C8M5.1"
				( objectStatus "@baseboard_fab2_lib.baseboard_fab2(sch_1):page228_i228:a" )
			)
			( pin "C8M5.2"
				( objectStatus "@baseboard_fab2_lib.baseboard_fab2(sch_1):page228_i228:b" )
			)
			( pin "C8L10.1"
				( objectStatus "@baseboard_fab2_lib.baseboard_fab2(sch_1):page228_i229:a" )
			)
			( pin "C8L10.2"
				( objectStatus "@baseboard_fab2_lib.baseboard_fab2(sch_1):page228_i229:b" )
			)
			( pin "C2A3.1"
				( objectStatus "@baseboard_fab2_lib.baseboard_fab2(sch_1):page228_i230:a" )
			)
			( pin "C2A3.2"
				( objectStatus "@baseboard_fab2_lib.baseboard_fab2(sch_1):page228_i230:b" )
			)
			( pin "C7M1.1"
				( objectStatus "@baseboard_fab2_lib.baseboard_fab2(sch_1):page228_i231:a" )
			)
			( pin "C7M1.2"
				( objectStatus "@baseboard_fab2_lib.baseboard_fab2(sch_1):page228_i231:b" )
			)
			( pin "C7M2.1"
				( objectStatus "@baseboard_fab2_lib.baseboard_fab2(sch_1):page228_i232:a" )
			)
			( pin "C7M2.2"
				( objectStatus "@baseboard_fab2_lib.baseboard_fab2(sch_1):page228_i232:b" )
			)
			( pin "C8M4.1"
				( objectStatus "@baseboard_fab2_lib.baseboard_fab2(sch_1):page228_i233:a" )
			)
			( pin "C8M4.2"
				( objectStatus "@baseboard_fab2_lib.baseboard_fab2(sch_1):page228_i233:b" )
			)
			( pin "C2A4.1"
				( objectStatus "@baseboard_fab2_lib.baseboard_fab2(sch_1):page228_i234:a" )
			)
			( pin "C2A4.2"
				( objectStatus "@baseboard_fab2_lib.baseboard_fab2(sch_1):page228_i234:b" )
			)
			( pin "C8M6.1"
				( objectStatus "@baseboard_fab2_lib.baseboard_fab2(sch_1):page228_i235:a" )
			)
			( pin "C8M6.2"
				( objectStatus "@baseboard_fab2_lib.baseboard_fab2(sch_1):page228_i235:b" )
			)
			( pin "C8L9.1"
				( objectStatus "@baseboard_fab2_lib.baseboard_fab2(sch_1):page228_i236:a" )
			)
			( pin "C8L9.2"
				( objectStatus "@baseboard_fab2_lib.baseboard_fab2(sch_1):page228_i236:b" )
			)
			( pin "C8L8.1"
				( objectStatus "@baseboard_fab2_lib.baseboard_fab2(sch_1):page228_i237:a" )
			)
			( pin "C8L8.2"
				( objectStatus "@baseboard_fab2_lib.baseboard_fab2(sch_1):page228_i237:b" )
			)
			( pin "C7L4.1"
				( objectStatus "@baseboard_fab2_lib.baseboard_fab2(sch_1):page228_i238:a" )
			)
			( pin "C7L4.2"
				( objectStatus "@baseboard_fab2_lib.baseboard_fab2(sch_1):page228_i238:b" )
			)
			( pin "C8L7.1"
				( objectStatus "@baseboard_fab2_lib.baseboard_fab2(sch_1):page228_i239:a" )
			)
			( pin "C8L7.2"
				( objectStatus "@baseboard_fab2_lib.baseboard_fab2(sch_1):page228_i239:b" )
			)
			( pin "C8L6.1"
				( objectStatus "@baseboard_fab2_lib.baseboard_fab2(sch_1):page228_i240:a" )
			)
			( pin "C8L6.2"
				( objectStatus "@baseboard_fab2_lib.baseboard_fab2(sch_1):page228_i240:b" )
			)
			( pin "C8L5.1"
				( objectStatus "@baseboard_fab2_lib.baseboard_fab2(sch_1):page228_i241:a" )
			)
			( pin "C8L5.2"
				( objectStatus "@baseboard_fab2_lib.baseboard_fab2(sch_1):page228_i241:b" )
			)
			( pin "C8M1.1"
				( objectStatus "@baseboard_fab2_lib.baseboard_fab2(sch_1):page228_i243:a" )
			)
			( pin "C8M1.2"
				( objectStatus "@baseboard_fab2_lib.baseboard_fab2(sch_1):page228_i243:b" )
			)
			( pin "SH7L2.1"
				( objectStatus "@baseboard_fab2_lib.baseboard_fab2(sch_1):page228_i245:a" )
			)
			( pin "SH7L2.2"
				( objectStatus "@baseboard_fab2_lib.baseboard_fab2(sch_1):page228_i245:b" )
			)
			( pin "SH7L1.1"
				( objectStatus "@baseboard_fab2_lib.baseboard_fab2(sch_1):page228_i246:a" )
			)
			( pin "SH7L1.2"
				( objectStatus "@baseboard_fab2_lib.baseboard_fab2(sch_1):page228_i246:b" )
			)
			( pin "R4G17.1"
				( objectStatus "@baseboard_fab2_lib.baseboard_fab2(sch_1):page229_i14:a" )
			)
			( pin "R4G17.2"
				( objectStatus "@baseboard_fab2_lib.baseboard_fab2(sch_1):page229_i14:b" )
			)
			( pin "C4G13.1"
				( objectStatus "@baseboard_fab2_lib.baseboard_fab2(sch_1):page229_i15:a" )
			)
			( pin "C4G13.2"
				( objectStatus "@baseboard_fab2_lib.baseboard_fab2(sch_1):page229_i15:b" )
			)
			( pin "C4G20.1"
				( objectStatus "@baseboard_fab2_lib.baseboard_fab2(sch_1):page229_i17:a" )
			)
			( pin "C4G20.2"
				( objectStatus "@baseboard_fab2_lib.baseboard_fab2(sch_1):page229_i17:b" )
			)
			( pin "C4G21.1"
				( objectStatus "@baseboard_fab2_lib.baseboard_fab2(sch_1):page229_i21:a" )
			)
			( pin "C4G21.2"
				( objectStatus "@baseboard_fab2_lib.baseboard_fab2(sch_1):page229_i21:b" )
			)
			( pin "EU4G2.3"
				( objectStatus "@baseboard_fab2_lib.baseboard_fab2(sch_1):page229_i24:agnd" )
			)
			( pin "EU4G2.2"
				( objectStatus "@baseboard_fab2_lib.baseboard_fab2(sch_1):page229_i24:bias" )
			)
			( pin "EU4G2.7"
				( objectStatus "@baseboard_fab2_lib.baseboard_fab2(sch_1):page229_i24:en" )
			)
			( pin "EU4G2.5"
				( objectStatus "@baseboard_fab2_lib.baseboard_fab2(sch_1):page229_i24:pg" )
			)
			( pin "EU4G2.8"
				( objectStatus "@baseboard_fab2_lib.baseboard_fab2(sch_1):page229_i24:pgnd" )
			)
			( pin "EU4G2.6"
				( objectStatus "@baseboard_fab2_lib.baseboard_fab2(sch_1):page229_i24:sns" )
			)
			( pin "EU4G2.11"
				( objectStatus "@baseboard_fab2_lib.baseboard_fab2(sch_1):page229_i24:thpad" )
			)
			( pin "EU4G2.4"
				( objectStatus "@baseboard_fab2_lib.baseboard_fab2(sch_1):page229_i24:vddq" )
			)
			( pin "EU4G2.10"
				( objectStatus "@baseboard_fab2_lib.baseboard_fab2(sch_1):page229_i24:vin" )
			)
			( pin "EU4G2.1"
				( objectStatus "@baseboard_fab2_lib.baseboard_fab2(sch_1):page229_i24:vref" )
			)
			( pin "EU4G2.9"
				( objectStatus "@baseboard_fab2_lib.baseboard_fab2(sch_1):page229_i24:vtt" )
			)
			( pin "C6U14.1"
				( objectStatus "@baseboard_fab2_lib.baseboard_fab2(sch_1):page229_i25:a" )
			)
			( pin "C6U14.2"
				( objectStatus "@baseboard_fab2_lib.baseboard_fab2(sch_1):page229_i25:b" )
			)
			( pin "C4G18.1"
				( objectStatus "@baseboard_fab2_lib.baseboard_fab2(sch_1):page229_i27:a" )
			)
			( pin "C4G18.2"
				( objectStatus "@baseboard_fab2_lib.baseboard_fab2(sch_1):page229_i27:b" )
			)
			( pin "C6U13.1"
				( objectStatus "@baseboard_fab2_lib.baseboard_fab2(sch_1):page229_i29:a" )
			)
			( pin "C6U13.2"
				( objectStatus "@baseboard_fab2_lib.baseboard_fab2(sch_1):page229_i29:b" )
			)
			( pin "R6U7.1"
				( objectStatus "@baseboard_fab2_lib.baseboard_fab2(sch_1):page229_i32:a" )
			)
			( pin "R6U7.2"
				( objectStatus "@baseboard_fab2_lib.baseboard_fab2(sch_1):page229_i32:b" )
			)
			( pin "R6U3.1"
				( objectStatus "@baseboard_fab2_lib.baseboard_fab2(sch_1):page229_i34:a" )
			)
			( pin "R6U3.2"
				( objectStatus "@baseboard_fab2_lib.baseboard_fab2(sch_1):page229_i34:b" )
			)
			( pin "R4G16.1"
				( objectStatus "@baseboard_fab2_lib.baseboard_fab2(sch_1):page229_i35:a" )
			)
			( pin "R4G16.2"
				( objectStatus "@baseboard_fab2_lib.baseboard_fab2(sch_1):page229_i35:b" )
			)
			( pin "C4G12.1"
				( objectStatus "@baseboard_fab2_lib.baseboard_fab2(sch_1):page229_i36:a" )
			)
			( pin "C4G12.2"
				( objectStatus "@baseboard_fab2_lib.baseboard_fab2(sch_1):page229_i36:b" )
			)
			( pin "R6U6.1"
				( objectStatus "@baseboard_fab2_lib.baseboard_fab2(sch_1):page229_i39:a" )
			)
			( pin "R6U6.2"
				( objectStatus "@baseboard_fab2_lib.baseboard_fab2(sch_1):page229_i39:b" )
			)
			( pin "C6U11.1"
				( objectStatus "@baseboard_fab2_lib.baseboard_fab2(sch_1):page229_i46:a" )
			)
			( pin "C6U11.2"
				( objectStatus "@baseboard_fab2_lib.baseboard_fab2(sch_1):page229_i46:b" )
			)
			( pin "C2F2.1"
				( objectStatus "@baseboard_fab2_lib.baseboard_fab2(sch_1):page229_i47:a" )
			)
			( pin "C2F2.2"
				( objectStatus "@baseboard_fab2_lib.baseboard_fab2(sch_1):page229_i47:b" )
			)
			( pin "C8T3.1"
				( objectStatus "@baseboard_fab2_lib.baseboard_fab2(sch_1):page229_i48:a" )
			)
			( pin "C8T3.2"
				( objectStatus "@baseboard_fab2_lib.baseboard_fab2(sch_1):page229_i48:b" )
			)
			( pin "C8U10.1"
				( objectStatus "@baseboard_fab2_lib.baseboard_fab2(sch_1):page229_i49:a" )
			)
			( pin "C8U10.2"
				( objectStatus "@baseboard_fab2_lib.baseboard_fab2(sch_1):page229_i49:b" )
			)
			( pin "R4G15.1"
				( objectStatus "@baseboard_fab2_lib.baseboard_fab2(sch_1):page229_i51:a" )
			)
			( pin "R4G15.2"
				( objectStatus "@baseboard_fab2_lib.baseboard_fab2(sch_1):page229_i51:b" )
			)
			( pin "R6U8.1"
				( objectStatus "@baseboard_fab2_lib.baseboard_fab2(sch_1):page229_i52:a" )
			)
			( pin "R6U8.2"
				( objectStatus "@baseboard_fab2_lib.baseboard_fab2(sch_1):page229_i52:b" )
			)
			( pin "SH8U1.1"
				( objectStatus "@baseboard_fab2_lib.baseboard_fab2(sch_1):page229_i53:a" )
			)
			( pin "SH8U1.2"
				( objectStatus "@baseboard_fab2_lib.baseboard_fab2(sch_1):page229_i53:b" )
			)
			( pin "C4A3.1"
				( objectStatus "@baseboard_fab2_lib.baseboard_fab2(sch_1):page230_i16:a" )
			)
			( pin "C4A3.2"
				( objectStatus "@baseboard_fab2_lib.baseboard_fab2(sch_1):page230_i16:b" )
			)
			( pin "R4A5.1"
				( objectStatus "@baseboard_fab2_lib.baseboard_fab2(sch_1):page230_i17:a" )
			)
			( pin "R4A5.2"
				( objectStatus "@baseboard_fab2_lib.baseboard_fab2(sch_1):page230_i17:b" )
			)
			( pin "C4A13.1"
				( objectStatus "@baseboard_fab2_lib.baseboard_fab2(sch_1):page230_i18:a" )
			)
			( pin "C4A13.2"
				( objectStatus "@baseboard_fab2_lib.baseboard_fab2(sch_1):page230_i18:b" )
			)
			( pin "C4A14.1"
				( objectStatus "@baseboard_fab2_lib.baseboard_fab2(sch_1):page230_i21:a" )
			)
			( pin "C4A14.2"
				( objectStatus "@baseboard_fab2_lib.baseboard_fab2(sch_1):page230_i21:b" )
			)
			( pin "C4A15.1"
				( objectStatus "@baseboard_fab2_lib.baseboard_fab2(sch_1):page230_i25:a" )
			)
			( pin "C4A15.2"
				( objectStatus "@baseboard_fab2_lib.baseboard_fab2(sch_1):page230_i25:b" )
			)
			( pin "C6L5.1"
				( objectStatus "@baseboard_fab2_lib.baseboard_fab2(sch_1):page230_i26:a" )
			)
			( pin "C6L5.2"
				( objectStatus "@baseboard_fab2_lib.baseboard_fab2(sch_1):page230_i26:b" )
			)
			( pin "C4A8.1"
				( objectStatus "@baseboard_fab2_lib.baseboard_fab2(sch_1):page230_i28:a" )
			)
			( pin "C4A8.2"
				( objectStatus "@baseboard_fab2_lib.baseboard_fab2(sch_1):page230_i28:b" )
			)
			( pin "R6L8.1"
				( objectStatus "@baseboard_fab2_lib.baseboard_fab2(sch_1):page230_i30:a" )
			)
			( pin "R6L8.2"
				( objectStatus "@baseboard_fab2_lib.baseboard_fab2(sch_1):page230_i30:b" )
			)
			( pin "EU4A2.3"
				( objectStatus "@baseboard_fab2_lib.baseboard_fab2(sch_1):page230_i31:agnd" )
			)
			( pin "EU4A2.2"
				( objectStatus "@baseboard_fab2_lib.baseboard_fab2(sch_1):page230_i31:bias" )
			)
			( pin "EU4A2.7"
				( objectStatus "@baseboard_fab2_lib.baseboard_fab2(sch_1):page230_i31:en" )
			)
			( pin "EU4A2.5"
				( objectStatus "@baseboard_fab2_lib.baseboard_fab2(sch_1):page230_i31:pg" )
			)
			( pin "EU4A2.8"
				( objectStatus "@baseboard_fab2_lib.baseboard_fab2(sch_1):page230_i31:pgnd" )
			)
			( pin "EU4A2.6"
				( objectStatus "@baseboard_fab2_lib.baseboard_fab2(sch_1):page230_i31:sns" )
			)
			( pin "EU4A2.11"
				( objectStatus "@baseboard_fab2_lib.baseboard_fab2(sch_1):page230_i31:thpad" )
			)
			( pin "EU4A2.4"
				( objectStatus "@baseboard_fab2_lib.baseboard_fab2(sch_1):page230_i31:vddq" )
			)
			( pin "EU4A2.10"
				( objectStatus "@baseboard_fab2_lib.baseboard_fab2(sch_1):page230_i31:vin" )
			)
			( pin "EU4A2.1"
				( objectStatus "@baseboard_fab2_lib.baseboard_fab2(sch_1):page230_i31:vref" )
			)
			( pin "EU4A2.9"
				( objectStatus "@baseboard_fab2_lib.baseboard_fab2(sch_1):page230_i31:vtt" )
			)
			( pin "R6L6.1"
				( objectStatus "@baseboard_fab2_lib.baseboard_fab2(sch_1):page230_i34:a" )
			)
			( pin "R6L6.2"
				( objectStatus "@baseboard_fab2_lib.baseboard_fab2(sch_1):page230_i34:b" )
			)
			( pin "R6L5.1"
				( objectStatus "@baseboard_fab2_lib.baseboard_fab2(sch_1):page230_i37:a" )
			)
			( pin "R6L5.2"
				( objectStatus "@baseboard_fab2_lib.baseboard_fab2(sch_1):page230_i37:b" )
			)
			( pin "R4A3.1"
				( objectStatus "@baseboard_fab2_lib.baseboard_fab2(sch_1):page230_i38:a" )
			)
			( pin "R4A3.2"
				( objectStatus "@baseboard_fab2_lib.baseboard_fab2(sch_1):page230_i38:b" )
			)
			( pin "C4A6.1"
				( objectStatus "@baseboard_fab2_lib.baseboard_fab2(sch_1):page230_i39:a" )
			)
			( pin "C4A6.2"
				( objectStatus "@baseboard_fab2_lib.baseboard_fab2(sch_1):page230_i39:b" )
			)
			( pin "C4A7.1"
				( objectStatus "@baseboard_fab2_lib.baseboard_fab2(sch_1):page230_i46:a" )
			)
			( pin "C4A7.2"
				( objectStatus "@baseboard_fab2_lib.baseboard_fab2(sch_1):page230_i46:b" )
			)
			( pin "C8M12.1"
				( objectStatus "@baseboard_fab2_lib.baseboard_fab2(sch_1):page230_i47:a" )
			)
			( pin "C8M12.2"
				( objectStatus "@baseboard_fab2_lib.baseboard_fab2(sch_1):page230_i47:b" )
			)
			( pin "C8L3.1"
				( objectStatus "@baseboard_fab2_lib.baseboard_fab2(sch_1):page230_i48:a" )
			)
			( pin "C8L3.2"
				( objectStatus "@baseboard_fab2_lib.baseboard_fab2(sch_1):page230_i48:b" )
			)
			( pin "C8L4.1"
				( objectStatus "@baseboard_fab2_lib.baseboard_fab2(sch_1):page230_i49:a" )
			)
			( pin "C8L4.2"
				( objectStatus "@baseboard_fab2_lib.baseboard_fab2(sch_1):page230_i49:b" )
			)
			( pin "R4A4.1"
				( objectStatus "@baseboard_fab2_lib.baseboard_fab2(sch_1):page230_i51:a" )
			)
			( pin "R4A4.2"
				( objectStatus "@baseboard_fab2_lib.baseboard_fab2(sch_1):page230_i51:b" )
			)
			( pin "R6L7.1"
				( objectStatus "@baseboard_fab2_lib.baseboard_fab2(sch_1):page230_i52:a" )
			)
			( pin "R6L7.2"
				( objectStatus "@baseboard_fab2_lib.baseboard_fab2(sch_1):page230_i52:b" )
			)
			( pin "SH8L1.1"
				( objectStatus "@baseboard_fab2_lib.baseboard_fab2(sch_1):page230_i53:a" )
			)
			( pin "SH8L1.2"
				( objectStatus "@baseboard_fab2_lib.baseboard_fab2(sch_1):page230_i53:b" )
			)
			( pin "C6F6.1"
				( objectStatus "@baseboard_fab2_lib.baseboard_fab2(sch_1):page231_i122:a" )
			)
			( pin "C6F6.2"
				( objectStatus "@baseboard_fab2_lib.baseboard_fab2(sch_1):page231_i122:b" )
			)
			( pin "C4T6.1"
				( objectStatus "@baseboard_fab2_lib.baseboard_fab2(sch_1):page231_i124:a" )
			)
			( pin "C4T6.2"
				( objectStatus "@baseboard_fab2_lib.baseboard_fab2(sch_1):page231_i124:b" )
			)
			( pin "C4T5.1"
				( objectStatus "@baseboard_fab2_lib.baseboard_fab2(sch_1):page231_i125:a" )
			)
			( pin "C4T5.2"
				( objectStatus "@baseboard_fab2_lib.baseboard_fab2(sch_1):page231_i125:b" )
			)
			( pin "C6G1.1"
				( objectStatus "@baseboard_fab2_lib.baseboard_fab2(sch_1):page231_i126:a" )
			)
			( pin "C6G1.2"
				( objectStatus "@baseboard_fab2_lib.baseboard_fab2(sch_1):page231_i126:b" )
			)
			( pin "C6G2.1"
				( objectStatus "@baseboard_fab2_lib.baseboard_fab2(sch_1):page231_i128:a" )
			)
			( pin "C6G2.2"
				( objectStatus "@baseboard_fab2_lib.baseboard_fab2(sch_1):page231_i128:b" )
			)
			( pin "C4U2.1"
				( objectStatus "@baseboard_fab2_lib.baseboard_fab2(sch_1):page231_i129:a" )
			)
			( pin "C4U2.2"
				( objectStatus "@baseboard_fab2_lib.baseboard_fab2(sch_1):page231_i129:b" )
			)
			( pin "C4U1.1"
				( objectStatus "@baseboard_fab2_lib.baseboard_fab2(sch_1):page231_i130:a" )
			)
			( pin "C4U1.2"
				( objectStatus "@baseboard_fab2_lib.baseboard_fab2(sch_1):page231_i130:b" )
			)
			( pin "C6G4.1"
				( objectStatus "@baseboard_fab2_lib.baseboard_fab2(sch_1):page231_i131:a" )
			)
			( pin "C6G4.2"
				( objectStatus "@baseboard_fab2_lib.baseboard_fab2(sch_1):page231_i131:b" )
			)
			( pin "R7F15.1"
				( objectStatus "@baseboard_fab2_lib.baseboard_fab2(sch_1):page231_i134:a" )
			)
			( pin "R7F15.2"
				( objectStatus "@baseboard_fab2_lib.baseboard_fab2(sch_1):page231_i134:b" )
			)
			( pin "R7F14.1"
				( objectStatus "@baseboard_fab2_lib.baseboard_fab2(sch_1):page231_i136:a" )
			)
			( pin "R7F14.2"
				( objectStatus "@baseboard_fab2_lib.baseboard_fab2(sch_1):page231_i136:b" )
			)
			( pin "C7F8.1"
				( objectStatus "@baseboard_fab2_lib.baseboard_fab2(sch_1):page231_i140:a" )
			)
			( pin "C7F8.2"
				( objectStatus "@baseboard_fab2_lib.baseboard_fab2(sch_1):page231_i140:b" )
			)
			( pin "C7F11.1"
				( objectStatus "@baseboard_fab2_lib.baseboard_fab2(sch_1):page231_i142:a" )
			)
			( pin "C7F11.2"
				( objectStatus "@baseboard_fab2_lib.baseboard_fab2(sch_1):page231_i142:b" )
			)
			( pin "R7F19.1"
				( objectStatus "@baseboard_fab2_lib.baseboard_fab2(sch_1):page231_i143:a" )
			)
			( pin "R7F19.2"
				( objectStatus "@baseboard_fab2_lib.baseboard_fab2(sch_1):page231_i143:b" )
			)
			( pin "C6G5.1"
				( objectStatus "@baseboard_fab2_lib.baseboard_fab2(sch_1):page231_i145:a" )
			)
			( pin "C6G5.2"
				( objectStatus "@baseboard_fab2_lib.baseboard_fab2(sch_1):page231_i145:b" )
			)
			( pin "C4U4.1"
				( objectStatus "@baseboard_fab2_lib.baseboard_fab2(sch_1):page231_i146:a" )
			)
			( pin "C4U4.2"
				( objectStatus "@baseboard_fab2_lib.baseboard_fab2(sch_1):page231_i146:b" )
			)
			( pin "C4U3.1"
				( objectStatus "@baseboard_fab2_lib.baseboard_fab2(sch_1):page231_i148:a" )
			)
			( pin "C4U3.2"
				( objectStatus "@baseboard_fab2_lib.baseboard_fab2(sch_1):page231_i148:b" )
			)
			( pin "C6F5.1"
				( objectStatus "@baseboard_fab2_lib.baseboard_fab2(sch_1):page231_i149:a" )
			)
			( pin "C6F5.2"
				( objectStatus "@baseboard_fab2_lib.baseboard_fab2(sch_1):page231_i149:b" )
			)
			( pin "C7F7.1"
				( objectStatus "@baseboard_fab2_lib.baseboard_fab2(sch_1):page231_i151:a" )
			)
			( pin "C7F7.2"
				( objectStatus "@baseboard_fab2_lib.baseboard_fab2(sch_1):page231_i151:b" )
			)
			( pin "R7F8.1"
				( objectStatus "@baseboard_fab2_lib.baseboard_fab2(sch_1):page231_i154:a" )
			)
			( pin "R7F8.2"
				( objectStatus "@baseboard_fab2_lib.baseboard_fab2(sch_1):page231_i154:b" )
			)
			( pin "C7F4.1"
				( objectStatus "@baseboard_fab2_lib.baseboard_fab2(sch_1):page231_i159:a" )
			)
			( pin "C7F4.2"
				( objectStatus "@baseboard_fab2_lib.baseboard_fab2(sch_1):page231_i159:b" )
			)
			( pin "C3T10.1"
				( objectStatus "@baseboard_fab2_lib.baseboard_fab2(sch_1):page231_i161:a" )
			)
			( pin "C3T10.2"
				( objectStatus "@baseboard_fab2_lib.baseboard_fab2(sch_1):page231_i161:b" )
			)
			( pin "FB7F1.1"
				( objectStatus "@baseboard_fab2_lib.baseboard_fab2(sch_1):page231_i162:a" )
			)
			( pin "FB7F1.2"
				( objectStatus "@baseboard_fab2_lib.baseboard_fab2(sch_1):page231_i162:b" )
			)
			( pin "R7F11.1"
				( objectStatus "@baseboard_fab2_lib.baseboard_fab2(sch_1):page231_i166:a" )
			)
			( pin "R7F11.2"
				( objectStatus "@baseboard_fab2_lib.baseboard_fab2(sch_1):page231_i166:b" )
			)
			( pin "R7F13.1"
				( objectStatus "@baseboard_fab2_lib.baseboard_fab2(sch_1):page231_i167:a" )
			)
			( pin "R7F13.2"
				( objectStatus "@baseboard_fab2_lib.baseboard_fab2(sch_1):page231_i167:b" )
			)
			( pin "R7F12.1"
				( objectStatus "@baseboard_fab2_lib.baseboard_fab2(sch_1):page231_i168:a" )
			)
			( pin "R7F12.2"
				( objectStatus "@baseboard_fab2_lib.baseboard_fab2(sch_1):page231_i168:b" )
			)
			( pin "R7F35.1"
				( objectStatus "@baseboard_fab2_lib.baseboard_fab2(sch_1):page231_i170:a" )
			)
			( pin "R7F35.2"
				( objectStatus "@baseboard_fab2_lib.baseboard_fab2(sch_1):page231_i170:b" )
			)
			( pin "R7F7.1"
				( objectStatus "@baseboard_fab2_lib.baseboard_fab2(sch_1):page231_i174:a" )
			)
			( pin "R7F7.2"
				( objectStatus "@baseboard_fab2_lib.baseboard_fab2(sch_1):page231_i174:b" )
			)
			( pin "C7F3.1"
				( objectStatus "@baseboard_fab2_lib.baseboard_fab2(sch_1):page231_i175:a" )
			)
			( pin "C7F3.2"
				( objectStatus "@baseboard_fab2_lib.baseboard_fab2(sch_1):page231_i175:b" )
			)
			( pin "R7F10.1"
				( objectStatus "@baseboard_fab2_lib.baseboard_fab2(sch_1):page231_i177:a" )
			)
			( pin "R7F10.2"
				( objectStatus "@baseboard_fab2_lib.baseboard_fab2(sch_1):page231_i177:b" )
			)
			( pin "L7F1.1"
				( objectStatus "@baseboard_fab2_lib.baseboard_fab2(sch_1):page231_i178:ina" )
			)
			( pin "L7F1.2"
				( objectStatus "@baseboard_fab2_lib.baseboard_fab2(sch_1):page231_i178:inb" )
			)
			( pin "C6F4.1"
				( objectStatus "@baseboard_fab2_lib.baseboard_fab2(sch_1):page231_i180:a" )
			)
			( pin "C6F4.2"
				( objectStatus "@baseboard_fab2_lib.baseboard_fab2(sch_1):page231_i180:b" )
			)
			( pin "C3T7.1"
				( objectStatus "@baseboard_fab2_lib.baseboard_fab2(sch_1):page231_i184:a" )
			)
			( pin "C3T7.2"
				( objectStatus "@baseboard_fab2_lib.baseboard_fab2(sch_1):page231_i184:b" )
			)
			( pin "C3T9.1"
				( objectStatus "@baseboard_fab2_lib.baseboard_fab2(sch_1):page231_i186:a" )
			)
			( pin "C3T9.2"
				( objectStatus "@baseboard_fab2_lib.baseboard_fab2(sch_1):page231_i186:b" )
			)
			( pin "EU7F1.5"
				( objectStatus "@baseboard_fab2_lib.baseboard_fab2(sch_1):page231_i193:agnd" )
			)
			( pin "EU7F1.36"
				( objectStatus "@baseboard_fab2_lib.baseboard_fab2(sch_1):page231_i193:bst" )
			)
			( pin "EU7F1.3"
				( objectStatus "@baseboard_fab2_lib.baseboard_fab2(sch_1):page231_i193:comp" )
			)
			( pin "EU7F1.40"
				( objectStatus "@baseboard_fab2_lib.baseboard_fab2(sch_1):page231_i193:en" )
			)
			( pin "EU7F1.2"
				( objectStatus "@baseboard_fab2_lib.baseboard_fab2(sch_1):page231_i193:fb" )
			)
			( pin "EU7F1.41"
				( objectStatus "@baseboard_fab2_lib.baseboard_fab2(sch_1):page231_i193:gnd" )
			)
			( pin "EU7F1.4"
				( objectStatus "@baseboard_fab2_lib.baseboard_fab2(sch_1):page231_i193:iset" )
			)
			( pin "EU7F1.6"
				( objectStatus "@baseboard_fab2_lib.baseboard_fab2(sch_1):page231_i193:ots" )
			)
			( pin "EU7F1.7"
				( objectStatus "@baseboard_fab2_lib.baseboard_fab2(sch_1):page231_i193:pg" )
			)
			( pin "EU7F1.16"
				( objectStatus "@baseboard_fab2_lib.baseboard_fab2(sch_1):page231_i193:pgnd(0)" )
			)
			( pin "EU7F1.17"
				( objectStatus "@baseboard_fab2_lib.baseboard_fab2(sch_1):page231_i193:pgnd(1)" )
			)
			( pin "EU7F1.18"
				( objectStatus "@baseboard_fab2_lib.baseboard_fab2(sch_1):page231_i193:pgnd(2)" )
			)
			( pin "EU7F1.19"
				( objectStatus "@baseboard_fab2_lib.baseboard_fab2(sch_1):page231_i193:pgnd(3)" )
			)
			( pin "EU7F1.20"
				( objectStatus "@baseboard_fab2_lib.baseboard_fab2(sch_1):page231_i193:pgnd(4)" )
			)
			( pin "EU7F1.21"
				( objectStatus "@baseboard_fab2_lib.baseboard_fab2(sch_1):page231_i193:pgnd(5)" )
			)
			( pin "EU7F1.22"
				( objectStatus "@baseboard_fab2_lib.baseboard_fab2(sch_1):page231_i193:pgnd(6)" )
			)
			( pin "EU7F1.23"
				( objectStatus "@baseboard_fab2_lib.baseboard_fab2(sch_1):page231_i193:pgnd(7)" )
			)
			( pin "EU7F1.24"
				( objectStatus "@baseboard_fab2_lib.baseboard_fab2(sch_1):page231_i193:pgnd(8)" )
			)
			( pin "EU7F1.25"
				( objectStatus "@baseboard_fab2_lib.baseboard_fab2(sch_1):page231_i193:pgnd(9)" )
			)
			( pin "EU7F1.26"
				( objectStatus "@baseboard_fab2_lib.baseboard_fab2(sch_1):page231_i193:pgnd(10)" )
			)
			( pin "EU7F1.27"
				( objectStatus "@baseboard_fab2_lib.baseboard_fab2(sch_1):page231_i193:pgnd(11)" )
			)
			( pin "EU7F1.28"
				( objectStatus "@baseboard_fab2_lib.baseboard_fab2(sch_1):page231_i193:pgnd(12)" )
			)
			( pin "EU7F1.37"
				( objectStatus "@baseboard_fab2_lib.baseboard_fab2(sch_1):page231_i193:pgnd(13)" )
			)
			( pin "EU7F1.1"
				( objectStatus "@baseboard_fab2_lib.baseboard_fab2(sch_1):page231_i193:ss" )
			)
			( pin "EU7F1.38"
				( objectStatus "@baseboard_fab2_lib.baseboard_fab2(sch_1):page231_i193:vb" )
			)
			( pin "EU7F1.39"
				( objectStatus "@baseboard_fab2_lib.baseboard_fab2(sch_1):page231_i193:vcc" )
			)
			( pin "EU7F1.8"
				( objectStatus "@baseboard_fab2_lib.baseboard_fab2(sch_1):page231_i193:vin(0)" )
			)
			( pin "EU7F1.9"
				( objectStatus "@baseboard_fab2_lib.baseboard_fab2(sch_1):page231_i193:vin(1)" )
			)
			( pin "EU7F1.10"
				( objectStatus "@baseboard_fab2_lib.baseboard_fab2(sch_1):page231_i193:vin(2)" )
			)
			( pin "EU7F1.11"
				( objectStatus "@baseboard_fab2_lib.baseboard_fab2(sch_1):page231_i193:vin(3)" )
			)
			( pin "EU7F1.12"
				( objectStatus "@baseboard_fab2_lib.baseboard_fab2(sch_1):page231_i193:vin(4)" )
			)
			( pin "EU7F1.13"
				( objectStatus "@baseboard_fab2_lib.baseboard_fab2(sch_1):page231_i193:vin(5)" )
			)
			( pin "EU7F1.14"
				( objectStatus "@baseboard_fab2_lib.baseboard_fab2(sch_1):page231_i193:vin(6)" )
			)
			( pin "EU7F1.42"
				( objectStatus "@baseboard_fab2_lib.baseboard_fab2(sch_1):page231_i193:vin(7)" )
			)
			( pin "EU7F1.35"
				( objectStatus "@baseboard_fab2_lib.baseboard_fab2(sch_1):page231_i193:vsw" )
			)
			( pin "EU7F1.15"
				( objectStatus "@baseboard_fab2_lib.baseboard_fab2(sch_1):page231_i193:vswh(0)" )
			)
			( pin "EU7F1.29"
				( objectStatus "@baseboard_fab2_lib.baseboard_fab2(sch_1):page231_i193:vswh(1)" )
			)
			( pin "EU7F1.30"
				( objectStatus "@baseboard_fab2_lib.baseboard_fab2(sch_1):page231_i193:vswh(2)" )
			)
			( pin "EU7F1.31"
				( objectStatus "@baseboard_fab2_lib.baseboard_fab2(sch_1):page231_i193:vswh(3)" )
			)
			( pin "EU7F1.32"
				( objectStatus "@baseboard_fab2_lib.baseboard_fab2(sch_1):page231_i193:vswh(4)" )
			)
			( pin "EU7F1.33"
				( objectStatus "@baseboard_fab2_lib.baseboard_fab2(sch_1):page231_i193:vswh(5)" )
			)
			( pin "EU7F1.34"
				( objectStatus "@baseboard_fab2_lib.baseboard_fab2(sch_1):page231_i193:vswh(6)" )
			)
			( pin "EU7F1.43"
				( objectStatus "@baseboard_fab2_lib.baseboard_fab2(sch_1):page231_i193:vswh(7)" )
			)
			( pin "C7F10.1"
				( objectStatus "@baseboard_fab2_lib.baseboard_fab2(sch_1):page231_i194:a" )
			)
			( pin "C7F10.2"
				( objectStatus "@baseboard_fab2_lib.baseboard_fab2(sch_1):page231_i194:b" )
			)
			( pin "C7F9.1"
				( objectStatus "@baseboard_fab2_lib.baseboard_fab2(sch_1):page231_i199:a" )
			)
			( pin "C7F9.2"
				( objectStatus "@baseboard_fab2_lib.baseboard_fab2(sch_1):page231_i199:b" )
			)
			( pin "C7F12.1"
				( objectStatus "@baseboard_fab2_lib.baseboard_fab2(sch_1):page231_i200:a" )
			)
			( pin "C7F12.2"
				( objectStatus "@baseboard_fab2_lib.baseboard_fab2(sch_1):page231_i200:b" )
			)
			( pin "R7F18.1"
				( objectStatus "@baseboard_fab2_lib.baseboard_fab2(sch_1):page231_i201:a" )
			)
			( pin "R7F18.2"
				( objectStatus "@baseboard_fab2_lib.baseboard_fab2(sch_1):page231_i201:b" )
			)
			( pin "C3T11.1"
				( objectStatus "@baseboard_fab2_lib.baseboard_fab2(sch_1):page231_i202:a" )
			)
			( pin "C3T11.2"
				( objectStatus "@baseboard_fab2_lib.baseboard_fab2(sch_1):page231_i202:b" )
			)
			( pin "C7F6.1"
				( objectStatus "@baseboard_fab2_lib.baseboard_fab2(sch_1):page231_i205:a" )
			)
			( pin "C7F6.2"
				( objectStatus "@baseboard_fab2_lib.baseboard_fab2(sch_1):page231_i205:b" )
			)
			( pin "R7F16.1"
				( objectStatus "@baseboard_fab2_lib.baseboard_fab2(sch_1):page231_i208:a" )
			)
			( pin "R7F16.2"
				( objectStatus "@baseboard_fab2_lib.baseboard_fab2(sch_1):page231_i208:b" )
			)
			( pin "C7F5.1"
				( objectStatus "@baseboard_fab2_lib.baseboard_fab2(sch_1):page231_i209:a" )
			)
			( pin "C7F5.2"
				( objectStatus "@baseboard_fab2_lib.baseboard_fab2(sch_1):page231_i209:b" )
			)
			( pin "C3T8.1"
				( objectStatus "@baseboard_fab2_lib.baseboard_fab2(sch_1):page231_i210:a" )
			)
			( pin "C3T8.2"
				( objectStatus "@baseboard_fab2_lib.baseboard_fab2(sch_1):page231_i210:b" )
			)
			( pin "C3T14.1"
				( objectStatus "@baseboard_fab2_lib.baseboard_fab2(sch_1):page231_i211:a" )
			)
			( pin "C3T14.2"
				( objectStatus "@baseboard_fab2_lib.baseboard_fab2(sch_1):page231_i211:b" )
			)
			( pin "C3T12.1"
				( objectStatus "@baseboard_fab2_lib.baseboard_fab2(sch_1):page231_i215:a" )
			)
			( pin "C3T12.2"
				( objectStatus "@baseboard_fab2_lib.baseboard_fab2(sch_1):page231_i215:b" )
			)
			( pin "C4T3.1"
				( objectStatus "@baseboard_fab2_lib.baseboard_fab2(sch_1):page231_i217:a" )
			)
			( pin "C4T3.2"
				( objectStatus "@baseboard_fab2_lib.baseboard_fab2(sch_1):page231_i217:b" )
			)
			( pin "R7F17.1"
				( objectStatus "@baseboard_fab2_lib.baseboard_fab2(sch_1):page231_i218:a" )
			)
			( pin "R7F17.2"
				( objectStatus "@baseboard_fab2_lib.baseboard_fab2(sch_1):page231_i218:b" )
			)
			( pin "C7F13.1"
				( objectStatus "@baseboard_fab2_lib.baseboard_fab2(sch_1):page231_i219:a" )
			)
			( pin "C7F13.2"
				( objectStatus "@baseboard_fab2_lib.baseboard_fab2(sch_1):page231_i219:b" )
			)
			( pin "R7F9.1"
				( objectStatus "@baseboard_fab2_lib.baseboard_fab2(sch_1):page231_i220:a" )
			)
			( pin "R7F9.2"
				( objectStatus "@baseboard_fab2_lib.baseboard_fab2(sch_1):page231_i220:b" )
			)
			( pin "C4L2.1"
				( objectStatus "@baseboard_fab2_lib.baseboard_fab2(sch_1):page232_i102:a" )
			)
			( pin "C4L2.2"
				( objectStatus "@baseboard_fab2_lib.baseboard_fab2(sch_1):page232_i102:b" )
			)
			( pin "C6A3.1"
				( objectStatus "@baseboard_fab2_lib.baseboard_fab2(sch_1):page232_i104:a" )
			)
			( pin "C6A3.2"
				( objectStatus "@baseboard_fab2_lib.baseboard_fab2(sch_1):page232_i104:b" )
			)
			( pin "C6A2.1"
				( objectStatus "@baseboard_fab2_lib.baseboard_fab2(sch_1):page232_i105:a" )
			)
			( pin "C6A2.2"
				( objectStatus "@baseboard_fab2_lib.baseboard_fab2(sch_1):page232_i105:b" )
			)
			( pin "C4L3.1"
				( objectStatus "@baseboard_fab2_lib.baseboard_fab2(sch_1):page232_i106:a" )
			)
			( pin "C4L3.2"
				( objectStatus "@baseboard_fab2_lib.baseboard_fab2(sch_1):page232_i106:b" )
			)
			( pin "C4L4.1"
				( objectStatus "@baseboard_fab2_lib.baseboard_fab2(sch_1):page232_i108:a" )
			)
			( pin "C4L4.2"
				( objectStatus "@baseboard_fab2_lib.baseboard_fab2(sch_1):page232_i108:b" )
			)
			( pin "C6A7.1"
				( objectStatus "@baseboard_fab2_lib.baseboard_fab2(sch_1):page232_i109:a" )
			)
			( pin "C6A7.2"
				( objectStatus "@baseboard_fab2_lib.baseboard_fab2(sch_1):page232_i109:b" )
			)
			( pin "C6A6.1"
				( objectStatus "@baseboard_fab2_lib.baseboard_fab2(sch_1):page232_i110:a" )
			)
			( pin "C6A6.2"
				( objectStatus "@baseboard_fab2_lib.baseboard_fab2(sch_1):page232_i110:b" )
			)
			( pin "C4M3.1"
				( objectStatus "@baseboard_fab2_lib.baseboard_fab2(sch_1):page232_i111:a" )
			)
			( pin "C4M3.2"
				( objectStatus "@baseboard_fab2_lib.baseboard_fab2(sch_1):page232_i111:b" )
			)
			( pin "C4M4.1"
				( objectStatus "@baseboard_fab2_lib.baseboard_fab2(sch_1):page232_i125:a" )
			)
			( pin "C4M4.2"
				( objectStatus "@baseboard_fab2_lib.baseboard_fab2(sch_1):page232_i125:b" )
			)
			( pin "C6B2.1"
				( objectStatus "@baseboard_fab2_lib.baseboard_fab2(sch_1):page232_i126:a" )
			)
			( pin "C6B2.2"
				( objectStatus "@baseboard_fab2_lib.baseboard_fab2(sch_1):page232_i126:b" )
			)
			( pin "C6B1.1"
				( objectStatus "@baseboard_fab2_lib.baseboard_fab2(sch_1):page232_i128:a" )
			)
			( pin "C6B1.2"
				( objectStatus "@baseboard_fab2_lib.baseboard_fab2(sch_1):page232_i128:b" )
			)
			( pin "C4L1.1"
				( objectStatus "@baseboard_fab2_lib.baseboard_fab2(sch_1):page232_i129:a" )
			)
			( pin "C4L1.2"
				( objectStatus "@baseboard_fab2_lib.baseboard_fab2(sch_1):page232_i129:b" )
			)
			( pin "R7B20.1"
				( objectStatus "@baseboard_fab2_lib.baseboard_fab2(sch_1):page232_i150:a" )
			)
			( pin "R7B20.2"
				( objectStatus "@baseboard_fab2_lib.baseboard_fab2(sch_1):page232_i150:b" )
			)
			( pin "C7B9.1"
				( objectStatus "@baseboard_fab2_lib.baseboard_fab2(sch_1):page232_i185:a" )
			)
			( pin "C7B9.2"
				( objectStatus "@baseboard_fab2_lib.baseboard_fab2(sch_1):page232_i185:b" )
			)
			( pin "R7B14.1"
				( objectStatus "@baseboard_fab2_lib.baseboard_fab2(sch_1):page232_i193:a" )
			)
			( pin "R7B14.2"
				( objectStatus "@baseboard_fab2_lib.baseboard_fab2(sch_1):page232_i193:b" )
			)
			( pin "C7B11.1"
				( objectStatus "@baseboard_fab2_lib.baseboard_fab2(sch_1):page232_i197:a" )
			)
			( pin "C7B11.2"
				( objectStatus "@baseboard_fab2_lib.baseboard_fab2(sch_1):page232_i197:b" )
			)
			( pin "FB7B1.1"
				( objectStatus "@baseboard_fab2_lib.baseboard_fab2(sch_1):page232_i200:a" )
			)
			( pin "FB7B1.2"
				( objectStatus "@baseboard_fab2_lib.baseboard_fab2(sch_1):page232_i200:b" )
			)
			( pin "C7B8.1"
				( objectStatus "@baseboard_fab2_lib.baseboard_fab2(sch_1):page232_i202:a" )
			)
			( pin "C7B8.2"
				( objectStatus "@baseboard_fab2_lib.baseboard_fab2(sch_1):page232_i202:b" )
			)
			( pin "C3M9.1"
				( objectStatus "@baseboard_fab2_lib.baseboard_fab2(sch_1):page232_i207:a" )
			)
			( pin "C3M9.2"
				( objectStatus "@baseboard_fab2_lib.baseboard_fab2(sch_1):page232_i207:b" )
			)
			( pin "C7B12.1"
				( objectStatus "@baseboard_fab2_lib.baseboard_fab2(sch_1):page232_i209:a" )
			)
			( pin "C7B12.2"
				( objectStatus "@baseboard_fab2_lib.baseboard_fab2(sch_1):page232_i209:b" )
			)
			( pin "R7B17.1"
				( objectStatus "@baseboard_fab2_lib.baseboard_fab2(sch_1):page232_i210:a" )
			)
			( pin "R7B17.2"
				( objectStatus "@baseboard_fab2_lib.baseboard_fab2(sch_1):page232_i210:b" )
			)
			( pin "EU7B1.5"
				( objectStatus "@baseboard_fab2_lib.baseboard_fab2(sch_1):page232_i214:agnd" )
			)
			( pin "EU7B1.36"
				( objectStatus "@baseboard_fab2_lib.baseboard_fab2(sch_1):page232_i214:bst" )
			)
			( pin "EU7B1.3"
				( objectStatus "@baseboard_fab2_lib.baseboard_fab2(sch_1):page232_i214:comp" )
			)
			( pin "EU7B1.40"
				( objectStatus "@baseboard_fab2_lib.baseboard_fab2(sch_1):page232_i214:en" )
			)
			( pin "EU7B1.2"
				( objectStatus "@baseboard_fab2_lib.baseboard_fab2(sch_1):page232_i214:fb" )
			)
			( pin "EU7B1.41"
				( objectStatus "@baseboard_fab2_lib.baseboard_fab2(sch_1):page232_i214:gnd" )
			)
			( pin "EU7B1.4"
				( objectStatus "@baseboard_fab2_lib.baseboard_fab2(sch_1):page232_i214:iset" )
			)
			( pin "EU7B1.6"
				( objectStatus "@baseboard_fab2_lib.baseboard_fab2(sch_1):page232_i214:ots" )
			)
			( pin "EU7B1.7"
				( objectStatus "@baseboard_fab2_lib.baseboard_fab2(sch_1):page232_i214:pg" )
			)
			( pin "EU7B1.16"
				( objectStatus "@baseboard_fab2_lib.baseboard_fab2(sch_1):page232_i214:pgnd(0)" )
			)
			( pin "EU7B1.17"
				( objectStatus "@baseboard_fab2_lib.baseboard_fab2(sch_1):page232_i214:pgnd(1)" )
			)
			( pin "EU7B1.18"
				( objectStatus "@baseboard_fab2_lib.baseboard_fab2(sch_1):page232_i214:pgnd(2)" )
			)
			( pin "EU7B1.19"
				( objectStatus "@baseboard_fab2_lib.baseboard_fab2(sch_1):page232_i214:pgnd(3)" )
			)
			( pin "EU7B1.20"
				( objectStatus "@baseboard_fab2_lib.baseboard_fab2(sch_1):page232_i214:pgnd(4)" )
			)
			( pin "EU7B1.21"
				( objectStatus "@baseboard_fab2_lib.baseboard_fab2(sch_1):page232_i214:pgnd(5)" )
			)
			( pin "EU7B1.22"
				( objectStatus "@baseboard_fab2_lib.baseboard_fab2(sch_1):page232_i214:pgnd(6)" )
			)
			( pin "EU7B1.23"
				( objectStatus "@baseboard_fab2_lib.baseboard_fab2(sch_1):page232_i214:pgnd(7)" )
			)
			( pin "EU7B1.24"
				( objectStatus "@baseboard_fab2_lib.baseboard_fab2(sch_1):page232_i214:pgnd(8)" )
			)
			( pin "EU7B1.25"
				( objectStatus "@baseboard_fab2_lib.baseboard_fab2(sch_1):page232_i214:pgnd(9)" )
			)
			( pin "EU7B1.26"
				( objectStatus "@baseboard_fab2_lib.baseboard_fab2(sch_1):page232_i214:pgnd(10)" )
			)
			( pin "EU7B1.27"
				( objectStatus "@baseboard_fab2_lib.baseboard_fab2(sch_1):page232_i214:pgnd(11)" )
			)
			( pin "EU7B1.28"
				( objectStatus "@baseboard_fab2_lib.baseboard_fab2(sch_1):page232_i214:pgnd(12)" )
			)
			( pin "EU7B1.37"
				( objectStatus "@baseboard_fab2_lib.baseboard_fab2(sch_1):page232_i214:pgnd(13)" )
			)
			( pin "EU7B1.1"
				( objectStatus "@baseboard_fab2_lib.baseboard_fab2(sch_1):page232_i214:ss" )
			)
			( pin "EU7B1.38"
				( objectStatus "@baseboard_fab2_lib.baseboard_fab2(sch_1):page232_i214:vb" )
			)
			( pin "EU7B1.39"
				( objectStatus "@baseboard_fab2_lib.baseboard_fab2(sch_1):page232_i214:vcc" )
			)
			( pin "EU7B1.8"
				( objectStatus "@baseboard_fab2_lib.baseboard_fab2(sch_1):page232_i214:vin(0)" )
			)
			( pin "EU7B1.9"
				( objectStatus "@baseboard_fab2_lib.baseboard_fab2(sch_1):page232_i214:vin(1)" )
			)
			( pin "EU7B1.10"
				( objectStatus "@baseboard_fab2_lib.baseboard_fab2(sch_1):page232_i214:vin(2)" )
			)
			( pin "EU7B1.11"
				( objectStatus "@baseboard_fab2_lib.baseboard_fab2(sch_1):page232_i214:vin(3)" )
			)
			( pin "EU7B1.12"
				( objectStatus "@baseboard_fab2_lib.baseboard_fab2(sch_1):page232_i214:vin(4)" )
			)
			( pin "EU7B1.13"
				( objectStatus "@baseboard_fab2_lib.baseboard_fab2(sch_1):page232_i214:vin(5)" )
			)
			( pin "EU7B1.14"
				( objectStatus "@baseboard_fab2_lib.baseboard_fab2(sch_1):page232_i214:vin(6)" )
			)
			( pin "EU7B1.42"
				( objectStatus "@baseboard_fab2_lib.baseboard_fab2(sch_1):page232_i214:vin(7)" )
			)
			( pin "EU7B1.35"
				( objectStatus "@baseboard_fab2_lib.baseboard_fab2(sch_1):page232_i214:vsw" )
			)
			( pin "EU7B1.15"
				( objectStatus "@baseboard_fab2_lib.baseboard_fab2(sch_1):page232_i214:vswh(0)" )
			)
			( pin "EU7B1.29"
				( objectStatus "@baseboard_fab2_lib.baseboard_fab2(sch_1):page232_i214:vswh(1)" )
			)
			( pin "EU7B1.30"
				( objectStatus "@baseboard_fab2_lib.baseboard_fab2(sch_1):page232_i214:vswh(2)" )
			)
			( pin "EU7B1.31"
				( objectStatus "@baseboard_fab2_lib.baseboard_fab2(sch_1):page232_i214:vswh(3)" )
			)
			( pin "EU7B1.32"
				( objectStatus "@baseboard_fab2_lib.baseboard_fab2(sch_1):page232_i214:vswh(4)" )
			)
			( pin "EU7B1.33"
				( objectStatus "@baseboard_fab2_lib.baseboard_fab2(sch_1):page232_i214:vswh(5)" )
			)
			( pin "EU7B1.34"
				( objectStatus "@baseboard_fab2_lib.baseboard_fab2(sch_1):page232_i214:vswh(6)" )
			)
			( pin "EU7B1.43"
				( objectStatus "@baseboard_fab2_lib.baseboard_fab2(sch_1):page232_i214:vswh(7)" )
			)
			( pin "R7A15.1"
				( objectStatus "@baseboard_fab2_lib.baseboard_fab2(sch_1):page232_i218:a" )
			)
			( pin "R7A15.2"
				( objectStatus "@baseboard_fab2_lib.baseboard_fab2(sch_1):page232_i218:b" )
			)
			( pin "C7A34.1"
				( objectStatus "@baseboard_fab2_lib.baseboard_fab2(sch_1):page232_i220:a" )
			)
			( pin "C7A34.2"
				( objectStatus "@baseboard_fab2_lib.baseboard_fab2(sch_1):page232_i220:b" )
			)
			( pin "R7B10.1"
				( objectStatus "@baseboard_fab2_lib.baseboard_fab2(sch_1):page232_i227:a" )
			)
			( pin "R7B10.2"
				( objectStatus "@baseboard_fab2_lib.baseboard_fab2(sch_1):page232_i227:b" )
			)
			( pin "C6B7.1"
				( objectStatus "@baseboard_fab2_lib.baseboard_fab2(sch_1):page232_i229:a" )
			)
			( pin "C6B7.2"
				( objectStatus "@baseboard_fab2_lib.baseboard_fab2(sch_1):page232_i229:b" )
			)
			( pin "C6B3.1"
				( objectStatus "@baseboard_fab2_lib.baseboard_fab2(sch_1):page232_i236:a" )
			)
			( pin "C6B3.2"
				( objectStatus "@baseboard_fab2_lib.baseboard_fab2(sch_1):page232_i236:b" )
			)
			( pin "C7B7.1"
				( objectStatus "@baseboard_fab2_lib.baseboard_fab2(sch_1):page232_i238:a" )
			)
			( pin "C7B7.2"
				( objectStatus "@baseboard_fab2_lib.baseboard_fab2(sch_1):page232_i238:b" )
			)
			( pin "L7B1.1"
				( objectStatus "@baseboard_fab2_lib.baseboard_fab2(sch_1):page232_i239:ina" )
			)
			( pin "L7B1.2"
				( objectStatus "@baseboard_fab2_lib.baseboard_fab2(sch_1):page232_i239:inb" )
			)
			( pin "R7B19.1"
				( objectStatus "@baseboard_fab2_lib.baseboard_fab2(sch_1):page232_i240:a" )
			)
			( pin "R7B19.2"
				( objectStatus "@baseboard_fab2_lib.baseboard_fab2(sch_1):page232_i240:b" )
			)
			( pin "C7B30.1"
				( objectStatus "@baseboard_fab2_lib.baseboard_fab2(sch_1):page232_i241:a" )
			)
			( pin "C7B30.2"
				( objectStatus "@baseboard_fab2_lib.baseboard_fab2(sch_1):page232_i241:b" )
			)
			( pin "C7B6.1"
				( objectStatus "@baseboard_fab2_lib.baseboard_fab2(sch_1):page232_i252:a" )
			)
			( pin "C7B6.2"
				( objectStatus "@baseboard_fab2_lib.baseboard_fab2(sch_1):page232_i252:b" )
			)
			( pin "C3M10.1"
				( objectStatus "@baseboard_fab2_lib.baseboard_fab2(sch_1):page232_i253:a" )
			)
			( pin "C3M10.2"
				( objectStatus "@baseboard_fab2_lib.baseboard_fab2(sch_1):page232_i253:b" )
			)
			( pin "R7B12.1"
				( objectStatus "@baseboard_fab2_lib.baseboard_fab2(sch_1):page232_i257:a" )
			)
			( pin "R7B12.2"
				( objectStatus "@baseboard_fab2_lib.baseboard_fab2(sch_1):page232_i257:b" )
			)
			( pin "C3M8.1"
				( objectStatus "@baseboard_fab2_lib.baseboard_fab2(sch_1):page232_i259:a" )
			)
			( pin "C3M8.2"
				( objectStatus "@baseboard_fab2_lib.baseboard_fab2(sch_1):page232_i259:b" )
			)
			( pin "C3M15.1"
				( objectStatus "@baseboard_fab2_lib.baseboard_fab2(sch_1):page232_i260:a" )
			)
			( pin "C3M15.2"
				( objectStatus "@baseboard_fab2_lib.baseboard_fab2(sch_1):page232_i260:b" )
			)
			( pin "C3M16.1"
				( objectStatus "@baseboard_fab2_lib.baseboard_fab2(sch_1):page232_i261:a" )
			)
			( pin "C3M16.2"
				( objectStatus "@baseboard_fab2_lib.baseboard_fab2(sch_1):page232_i261:b" )
			)
			( pin "C7B5.1"
				( objectStatus "@baseboard_fab2_lib.baseboard_fab2(sch_1):page232_i262:a" )
			)
			( pin "C7B5.2"
				( objectStatus "@baseboard_fab2_lib.baseboard_fab2(sch_1):page232_i262:b" )
			)
			( pin "C4M1.1"
				( objectStatus "@baseboard_fab2_lib.baseboard_fab2(sch_1):page232_i267:a" )
			)
			( pin "C4M1.2"
				( objectStatus "@baseboard_fab2_lib.baseboard_fab2(sch_1):page232_i267:b" )
			)
			( pin "R7B18.1"
				( objectStatus "@baseboard_fab2_lib.baseboard_fab2(sch_1):page232_i298:a" )
			)
			( pin "R7B18.2"
				( objectStatus "@baseboard_fab2_lib.baseboard_fab2(sch_1):page232_i298:b" )
			)
			( pin "R7B11.1"
				( objectStatus "@baseboard_fab2_lib.baseboard_fab2(sch_1):page232_i299:a" )
			)
			( pin "R7B11.2"
				( objectStatus "@baseboard_fab2_lib.baseboard_fab2(sch_1):page232_i299:b" )
			)
			( pin "R7B16.1"
				( objectStatus "@baseboard_fab2_lib.baseboard_fab2(sch_1):page232_i300:a" )
			)
			( pin "R7B16.2"
				( objectStatus "@baseboard_fab2_lib.baseboard_fab2(sch_1):page232_i300:b" )
			)
			( pin "C7B10.1"
				( objectStatus "@baseboard_fab2_lib.baseboard_fab2(sch_1):page232_i301:a" )
			)
			( pin "C7B10.2"
				( objectStatus "@baseboard_fab2_lib.baseboard_fab2(sch_1):page232_i301:b" )
			)
			( pin "C7B13.1"
				( objectStatus "@baseboard_fab2_lib.baseboard_fab2(sch_1):page232_i302:a" )
			)
			( pin "C7B13.2"
				( objectStatus "@baseboard_fab2_lib.baseboard_fab2(sch_1):page232_i302:b" )
			)
			( pin "R7B15.1"
				( objectStatus "@baseboard_fab2_lib.baseboard_fab2(sch_1):page232_i303:a" )
			)
			( pin "R7B15.2"
				( objectStatus "@baseboard_fab2_lib.baseboard_fab2(sch_1):page232_i303:b" )
			)
			( pin "R7B13.1"
				( objectStatus "@baseboard_fab2_lib.baseboard_fab2(sch_1):page232_i304:a" )
			)
			( pin "R7B13.2"
				( objectStatus "@baseboard_fab2_lib.baseboard_fab2(sch_1):page232_i304:b" )
			)
			( pin "C7B14.1"
				( objectStatus "@baseboard_fab2_lib.baseboard_fab2(sch_1):page232_i306:a" )
			)
			( pin "C7B14.2"
				( objectStatus "@baseboard_fab2_lib.baseboard_fab2(sch_1):page232_i306:b" )
			)
			( pin "R7B9.1"
				( objectStatus "@baseboard_fab2_lib.baseboard_fab2(sch_1):page232_i307:a" )
			)
			( pin "R7B9.2"
				( objectStatus "@baseboard_fab2_lib.baseboard_fab2(sch_1):page232_i307:b" )
			)
			( pin "C7U4.1"
				( objectStatus "@baseboard_fab2_lib.baseboard_fab2(sch_1):page233_i109:a" )
			)
			( pin "C7U4.2"
				( objectStatus "@baseboard_fab2_lib.baseboard_fab2(sch_1):page233_i109:b" )
			)
			( pin "C7U5.1"
				( objectStatus "@baseboard_fab2_lib.baseboard_fab2(sch_1):page233_i111:a" )
			)
			( pin "C7U5.2"
				( objectStatus "@baseboard_fab2_lib.baseboard_fab2(sch_1):page233_i111:b" )
			)
			( pin "C7T2.1"
				( objectStatus "@baseboard_fab2_lib.baseboard_fab2(sch_1):page233_i112:a" )
			)
			( pin "C7T2.2"
				( objectStatus "@baseboard_fab2_lib.baseboard_fab2(sch_1):page233_i112:b" )
			)
			( pin "C7T3.1"
				( objectStatus "@baseboard_fab2_lib.baseboard_fab2(sch_1):page233_i113:a" )
			)
			( pin "C7T3.2"
				( objectStatus "@baseboard_fab2_lib.baseboard_fab2(sch_1):page233_i113:b" )
			)
			( pin "C7U6.1"
				( objectStatus "@baseboard_fab2_lib.baseboard_fab2(sch_1):page233_i115:a" )
			)
			( pin "C7U6.2"
				( objectStatus "@baseboard_fab2_lib.baseboard_fab2(sch_1):page233_i115:b" )
			)
			( pin "C3F3.1"
				( objectStatus "@baseboard_fab2_lib.baseboard_fab2(sch_1):page233_i116:a" )
			)
			( pin "C3F3.2"
				( objectStatus "@baseboard_fab2_lib.baseboard_fab2(sch_1):page233_i116:b" )
			)
			( pin "C3F4.1"
				( objectStatus "@baseboard_fab2_lib.baseboard_fab2(sch_1):page233_i117:a" )
			)
			( pin "C3F4.2"
				( objectStatus "@baseboard_fab2_lib.baseboard_fab2(sch_1):page233_i117:b" )
			)
			( pin "C3G3.1"
				( objectStatus "@baseboard_fab2_lib.baseboard_fab2(sch_1):page233_i118:a" )
			)
			( pin "C3G3.2"
				( objectStatus "@baseboard_fab2_lib.baseboard_fab2(sch_1):page233_i118:b" )
			)
			( pin "C3G7.1"
				( objectStatus "@baseboard_fab2_lib.baseboard_fab2(sch_1):page233_i132:a" )
			)
			( pin "C3G7.2"
				( objectStatus "@baseboard_fab2_lib.baseboard_fab2(sch_1):page233_i132:b" )
			)
			( pin "C3G4.1"
				( objectStatus "@baseboard_fab2_lib.baseboard_fab2(sch_1):page233_i133:a" )
			)
			( pin "C3G4.2"
				( objectStatus "@baseboard_fab2_lib.baseboard_fab2(sch_1):page233_i133:b" )
			)
			( pin "C3G8.1"
				( objectStatus "@baseboard_fab2_lib.baseboard_fab2(sch_1):page233_i135:a" )
			)
			( pin "C3G8.2"
				( objectStatus "@baseboard_fab2_lib.baseboard_fab2(sch_1):page233_i135:b" )
			)
			( pin "C7U3.1"
				( objectStatus "@baseboard_fab2_lib.baseboard_fab2(sch_1):page233_i136:a" )
			)
			( pin "C7U3.2"
				( objectStatus "@baseboard_fab2_lib.baseboard_fab2(sch_1):page233_i136:b" )
			)
			( pin "R4G25.1"
				( objectStatus "@baseboard_fab2_lib.baseboard_fab2(sch_1):page233_i157:a" )
			)
			( pin "R4G25.2"
				( objectStatus "@baseboard_fab2_lib.baseboard_fab2(sch_1):page233_i157:b" )
			)
			( pin "R4G5.1"
				( objectStatus "@baseboard_fab2_lib.baseboard_fab2(sch_1):page233_i182:a" )
			)
			( pin "R4G5.2"
				( objectStatus "@baseboard_fab2_lib.baseboard_fab2(sch_1):page233_i182:b" )
			)
			( pin "C4G7.1"
				( objectStatus "@baseboard_fab2_lib.baseboard_fab2(sch_1):page233_i183:a" )
			)
			( pin "C4G7.2"
				( objectStatus "@baseboard_fab2_lib.baseboard_fab2(sch_1):page233_i183:b" )
			)
			( pin "R4G11.1"
				( objectStatus "@baseboard_fab2_lib.baseboard_fab2(sch_1):page233_i184:a" )
			)
			( pin "R4G11.2"
				( objectStatus "@baseboard_fab2_lib.baseboard_fab2(sch_1):page233_i184:b" )
			)
			( pin "R4G14.1"
				( objectStatus "@baseboard_fab2_lib.baseboard_fab2(sch_1):page233_i185:a" )
			)
			( pin "R4G14.2"
				( objectStatus "@baseboard_fab2_lib.baseboard_fab2(sch_1):page233_i185:b" )
			)
			( pin "C6U6.1"
				( objectStatus "@baseboard_fab2_lib.baseboard_fab2(sch_1):page233_i187:a" )
			)
			( pin "C6U6.2"
				( objectStatus "@baseboard_fab2_lib.baseboard_fab2(sch_1):page233_i187:b" )
			)
			( pin "C4G5.1"
				( objectStatus "@baseboard_fab2_lib.baseboard_fab2(sch_1):page233_i189:a" )
			)
			( pin "C4G5.2"
				( objectStatus "@baseboard_fab2_lib.baseboard_fab2(sch_1):page233_i189:b" )
			)
			( pin "C4G8.1"
				( objectStatus "@baseboard_fab2_lib.baseboard_fab2(sch_1):page233_i194:a" )
			)
			( pin "C4G8.2"
				( objectStatus "@baseboard_fab2_lib.baseboard_fab2(sch_1):page233_i194:b" )
			)
			( pin "C4G4.1"
				( objectStatus "@baseboard_fab2_lib.baseboard_fab2(sch_1):page233_i196:a" )
			)
			( pin "C4G4.2"
				( objectStatus "@baseboard_fab2_lib.baseboard_fab2(sch_1):page233_i196:b" )
			)
			( pin "FB4G1.1"
				( objectStatus "@baseboard_fab2_lib.baseboard_fab2(sch_1):page233_i198:a" )
			)
			( pin "FB4G1.2"
				( objectStatus "@baseboard_fab2_lib.baseboard_fab2(sch_1):page233_i198:b" )
			)
			( pin "R4G24.1"
				( objectStatus "@baseboard_fab2_lib.baseboard_fab2(sch_1):page233_i199:a" )
			)
			( pin "R4G24.2"
				( objectStatus "@baseboard_fab2_lib.baseboard_fab2(sch_1):page233_i199:b" )
			)
			( pin "C4G9.1"
				( objectStatus "@baseboard_fab2_lib.baseboard_fab2(sch_1):page233_i201:a" )
			)
			( pin "C4G9.2"
				( objectStatus "@baseboard_fab2_lib.baseboard_fab2(sch_1):page233_i201:b" )
			)
			( pin "R4F6.1"
				( objectStatus "@baseboard_fab2_lib.baseboard_fab2(sch_1):page233_i208:a" )
			)
			( pin "R4F6.2"
				( objectStatus "@baseboard_fab2_lib.baseboard_fab2(sch_1):page233_i208:b" )
			)
			( pin "C4F12.1"
				( objectStatus "@baseboard_fab2_lib.baseboard_fab2(sch_1):page233_i209:a" )
			)
			( pin "C4F12.2"
				( objectStatus "@baseboard_fab2_lib.baseboard_fab2(sch_1):page233_i209:b" )
			)
			( pin "R4G6.1"
				( objectStatus "@baseboard_fab2_lib.baseboard_fab2(sch_1):page233_i211:a" )
			)
			( pin "R4G6.2"
				( objectStatus "@baseboard_fab2_lib.baseboard_fab2(sch_1):page233_i211:b" )
			)
			( pin "C4F7.1"
				( objectStatus "@baseboard_fab2_lib.baseboard_fab2(sch_1):page233_i217:a" )
			)
			( pin "C4F7.2"
				( objectStatus "@baseboard_fab2_lib.baseboard_fab2(sch_1):page233_i217:b" )
			)
			( pin "C6U3.1"
				( objectStatus "@baseboard_fab2_lib.baseboard_fab2(sch_1):page233_i221:a" )
			)
			( pin "C6U3.2"
				( objectStatus "@baseboard_fab2_lib.baseboard_fab2(sch_1):page233_i221:b" )
			)
			( pin "C6U2.1"
				( objectStatus "@baseboard_fab2_lib.baseboard_fab2(sch_1):page233_i223:a" )
			)
			( pin "C6U2.2"
				( objectStatus "@baseboard_fab2_lib.baseboard_fab2(sch_1):page233_i223:b" )
			)
			( pin "C4G26.1"
				( objectStatus "@baseboard_fab2_lib.baseboard_fab2(sch_1):page233_i224:a" )
			)
			( pin "C4G26.2"
				( objectStatus "@baseboard_fab2_lib.baseboard_fab2(sch_1):page233_i224:b" )
			)
			( pin "EU4G1.5"
				( objectStatus "@baseboard_fab2_lib.baseboard_fab2(sch_1):page233_i225:agnd" )
			)
			( pin "EU4G1.36"
				( objectStatus "@baseboard_fab2_lib.baseboard_fab2(sch_1):page233_i225:bst" )
			)
			( pin "EU4G1.3"
				( objectStatus "@baseboard_fab2_lib.baseboard_fab2(sch_1):page233_i225:comp" )
			)
			( pin "EU4G1.40"
				( objectStatus "@baseboard_fab2_lib.baseboard_fab2(sch_1):page233_i225:en" )
			)
			( pin "EU4G1.2"
				( objectStatus "@baseboard_fab2_lib.baseboard_fab2(sch_1):page233_i225:fb" )
			)
			( pin "EU4G1.41"
				( objectStatus "@baseboard_fab2_lib.baseboard_fab2(sch_1):page233_i225:gnd" )
			)
			( pin "EU4G1.4"
				( objectStatus "@baseboard_fab2_lib.baseboard_fab2(sch_1):page233_i225:iset" )
			)
			( pin "EU4G1.6"
				( objectStatus "@baseboard_fab2_lib.baseboard_fab2(sch_1):page233_i225:ots" )
			)
			( pin "EU4G1.7"
				( objectStatus "@baseboard_fab2_lib.baseboard_fab2(sch_1):page233_i225:pg" )
			)
			( pin "EU4G1.16"
				( objectStatus "@baseboard_fab2_lib.baseboard_fab2(sch_1):page233_i225:pgnd(0)" )
			)
			( pin "EU4G1.17"
				( objectStatus "@baseboard_fab2_lib.baseboard_fab2(sch_1):page233_i225:pgnd(1)" )
			)
			( pin "EU4G1.18"
				( objectStatus "@baseboard_fab2_lib.baseboard_fab2(sch_1):page233_i225:pgnd(2)" )
			)
			( pin "EU4G1.19"
				( objectStatus "@baseboard_fab2_lib.baseboard_fab2(sch_1):page233_i225:pgnd(3)" )
			)
			( pin "EU4G1.20"
				( objectStatus "@baseboard_fab2_lib.baseboard_fab2(sch_1):page233_i225:pgnd(4)" )
			)
			( pin "EU4G1.21"
				( objectStatus "@baseboard_fab2_lib.baseboard_fab2(sch_1):page233_i225:pgnd(5)" )
			)
			( pin "EU4G1.22"
				( objectStatus "@baseboard_fab2_lib.baseboard_fab2(sch_1):page233_i225:pgnd(6)" )
			)
			( pin "EU4G1.23"
				( objectStatus "@baseboard_fab2_lib.baseboard_fab2(sch_1):page233_i225:pgnd(7)" )
			)
			( pin "EU4G1.24"
				( objectStatus "@baseboard_fab2_lib.baseboard_fab2(sch_1):page233_i225:pgnd(8)" )
			)
			( pin "EU4G1.25"
				( objectStatus "@baseboard_fab2_lib.baseboard_fab2(sch_1):page233_i225:pgnd(9)" )
			)
			( pin "EU4G1.26"
				( objectStatus "@baseboard_fab2_lib.baseboard_fab2(sch_1):page233_i225:pgnd(10)" )
			)
			( pin "EU4G1.27"
				( objectStatus "@baseboard_fab2_lib.baseboard_fab2(sch_1):page233_i225:pgnd(11)" )
			)
			( pin "EU4G1.28"
				( objectStatus "@baseboard_fab2_lib.baseboard_fab2(sch_1):page233_i225:pgnd(12)" )
			)
			( pin "EU4G1.37"
				( objectStatus "@baseboard_fab2_lib.baseboard_fab2(sch_1):page233_i225:pgnd(13)" )
			)
			( pin "EU4G1.1"
				( objectStatus "@baseboard_fab2_lib.baseboard_fab2(sch_1):page233_i225:ss" )
			)
			( pin "EU4G1.38"
				( objectStatus "@baseboard_fab2_lib.baseboard_fab2(sch_1):page233_i225:vb" )
			)
			( pin "EU4G1.39"
				( objectStatus "@baseboard_fab2_lib.baseboard_fab2(sch_1):page233_i225:vcc" )
			)
			( pin "EU4G1.8"
				( objectStatus "@baseboard_fab2_lib.baseboard_fab2(sch_1):page233_i225:vin(0)" )
			)
			( pin "EU4G1.9"
				( objectStatus "@baseboard_fab2_lib.baseboard_fab2(sch_1):page233_i225:vin(1)" )
			)
			( pin "EU4G1.10"
				( objectStatus "@baseboard_fab2_lib.baseboard_fab2(sch_1):page233_i225:vin(2)" )
			)
			( pin "EU4G1.11"
				( objectStatus "@baseboard_fab2_lib.baseboard_fab2(sch_1):page233_i225:vin(3)" )
			)
			( pin "EU4G1.12"
				( objectStatus "@baseboard_fab2_lib.baseboard_fab2(sch_1):page233_i225:vin(4)" )
			)
			( pin "EU4G1.13"
				( objectStatus "@baseboard_fab2_lib.baseboard_fab2(sch_1):page233_i225:vin(5)" )
			)
			( pin "EU4G1.14"
				( objectStatus "@baseboard_fab2_lib.baseboard_fab2(sch_1):page233_i225:vin(6)" )
			)
			( pin "EU4G1.42"
				( objectStatus "@baseboard_fab2_lib.baseboard_fab2(sch_1):page233_i225:vin(7)" )
			)
			( pin "EU4G1.35"
				( objectStatus "@baseboard_fab2_lib.baseboard_fab2(sch_1):page233_i225:vsw" )
			)
			( pin "EU4G1.15"
				( objectStatus "@baseboard_fab2_lib.baseboard_fab2(sch_1):page233_i225:vswh(0)" )
			)
			( pin "EU4G1.29"
				( objectStatus "@baseboard_fab2_lib.baseboard_fab2(sch_1):page233_i225:vswh(1)" )
			)
			( pin "EU4G1.30"
				( objectStatus "@baseboard_fab2_lib.baseboard_fab2(sch_1):page233_i225:vswh(2)" )
			)
			( pin "EU4G1.31"
				( objectStatus "@baseboard_fab2_lib.baseboard_fab2(sch_1):page233_i225:vswh(3)" )
			)
			( pin "EU4G1.32"
				( objectStatus "@baseboard_fab2_lib.baseboard_fab2(sch_1):page233_i225:vswh(4)" )
			)
			( pin "EU4G1.33"
				( objectStatus "@baseboard_fab2_lib.baseboard_fab2(sch_1):page233_i225:vswh(5)" )
			)
			( pin "EU4G1.34"
				( objectStatus "@baseboard_fab2_lib.baseboard_fab2(sch_1):page233_i225:vswh(6)" )
			)
			( pin "EU4G1.43"
				( objectStatus "@baseboard_fab2_lib.baseboard_fab2(sch_1):page233_i225:vswh(7)" )
			)
			( pin "C6U5.1"
				( objectStatus "@baseboard_fab2_lib.baseboard_fab2(sch_1):page233_i242:a" )
			)
			( pin "C6U5.2"
				( objectStatus "@baseboard_fab2_lib.baseboard_fab2(sch_1):page233_i242:b" )
			)
			( pin "R4G12.1"
				( objectStatus "@baseboard_fab2_lib.baseboard_fab2(sch_1):page233_i247:a" )
			)
			( pin "R4G12.2"
				( objectStatus "@baseboard_fab2_lib.baseboard_fab2(sch_1):page233_i247:b" )
			)
			( pin "C6U4.1"
				( objectStatus "@baseboard_fab2_lib.baseboard_fab2(sch_1):page233_i248:a" )
			)
			( pin "C6U4.2"
				( objectStatus "@baseboard_fab2_lib.baseboard_fab2(sch_1):page233_i248:b" )
			)
			( pin "C4G2.1"
				( objectStatus "@baseboard_fab2_lib.baseboard_fab2(sch_1):page233_i253:a" )
			)
			( pin "C4G2.2"
				( objectStatus "@baseboard_fab2_lib.baseboard_fab2(sch_1):page233_i253:b" )
			)
			( pin "C6U7.1"
				( objectStatus "@baseboard_fab2_lib.baseboard_fab2(sch_1):page233_i254:a" )
			)
			( pin "C6U7.2"
				( objectStatus "@baseboard_fab2_lib.baseboard_fab2(sch_1):page233_i254:b" )
			)
			( pin "C6U8.1"
				( objectStatus "@baseboard_fab2_lib.baseboard_fab2(sch_1):page233_i255:a" )
			)
			( pin "C6U8.2"
				( objectStatus "@baseboard_fab2_lib.baseboard_fab2(sch_1):page233_i255:b" )
			)
			( pin "C4F11.1"
				( objectStatus "@baseboard_fab2_lib.baseboard_fab2(sch_1):page233_i256:a" )
			)
			( pin "C4F11.2"
				( objectStatus "@baseboard_fab2_lib.baseboard_fab2(sch_1):page233_i256:b" )
			)
			( pin "R4G10.1"
				( objectStatus "@baseboard_fab2_lib.baseboard_fab2(sch_1):page233_i266:a" )
			)
			( pin "R4G10.2"
				( objectStatus "@baseboard_fab2_lib.baseboard_fab2(sch_1):page233_i266:b" )
			)
			( pin "C4G11.1"
				( objectStatus "@baseboard_fab2_lib.baseboard_fab2(sch_1):page233_i267:a" )
			)
			( pin "C4G11.2"
				( objectStatus "@baseboard_fab2_lib.baseboard_fab2(sch_1):page233_i267:b" )
			)
			( pin "R4G9.1"
				( objectStatus "@baseboard_fab2_lib.baseboard_fab2(sch_1):page233_i269:a" )
			)
			( pin "R4G9.2"
				( objectStatus "@baseboard_fab2_lib.baseboard_fab2(sch_1):page233_i269:b" )
			)
			( pin "R4G7.1"
				( objectStatus "@baseboard_fab2_lib.baseboard_fab2(sch_1):page233_i270:a" )
			)
			( pin "R4G7.2"
				( objectStatus "@baseboard_fab2_lib.baseboard_fab2(sch_1):page233_i270:b" )
			)
			( pin "R4G8.1"
				( objectStatus "@baseboard_fab2_lib.baseboard_fab2(sch_1):page233_i271:a" )
			)
			( pin "R4G8.2"
				( objectStatus "@baseboard_fab2_lib.baseboard_fab2(sch_1):page233_i271:b" )
			)
			( pin "R4G13.1"
				( objectStatus "@baseboard_fab2_lib.baseboard_fab2(sch_1):page233_i272:a" )
			)
			( pin "R4G13.2"
				( objectStatus "@baseboard_fab2_lib.baseboard_fab2(sch_1):page233_i272:b" )
			)
			( pin "C4G6.1"
				( objectStatus "@baseboard_fab2_lib.baseboard_fab2(sch_1):page233_i273:a" )
			)
			( pin "C4G6.2"
				( objectStatus "@baseboard_fab2_lib.baseboard_fab2(sch_1):page233_i273:b" )
			)
			( pin "C4G10.1"
				( objectStatus "@baseboard_fab2_lib.baseboard_fab2(sch_1):page233_i274:a" )
			)
			( pin "C4G10.2"
				( objectStatus "@baseboard_fab2_lib.baseboard_fab2(sch_1):page233_i274:b" )
			)
			( pin "R4G4.1"
				( objectStatus "@baseboard_fab2_lib.baseboard_fab2(sch_1):page233_i275:a" )
			)
			( pin "R4G4.2"
				( objectStatus "@baseboard_fab2_lib.baseboard_fab2(sch_1):page233_i275:b" )
			)
			( pin "L4G1.1"
				( objectStatus "@baseboard_fab2_lib.baseboard_fab2(sch_1):page233_i277:ina" )
			)
			( pin "L4G1.2"
				( objectStatus "@baseboard_fab2_lib.baseboard_fab2(sch_1):page233_i277:inb" )
			)
			( pin "R4B14.1"
				( objectStatus "@baseboard_fab2_lib.baseboard_fab2(sch_1):page234_i29:a" )
			)
			( pin "R4B14.2"
				( objectStatus "@baseboard_fab2_lib.baseboard_fab2(sch_1):page234_i29:b" )
			)
			( pin "C3B2.1"
				( objectStatus "@baseboard_fab2_lib.baseboard_fab2(sch_1):page234_i84:a" )
			)
			( pin "C3B2.2"
				( objectStatus "@baseboard_fab2_lib.baseboard_fab2(sch_1):page234_i84:b" )
			)
			( pin "C3A8.1"
				( objectStatus "@baseboard_fab2_lib.baseboard_fab2(sch_1):page234_i86:a" )
			)
			( pin "C3A8.2"
				( objectStatus "@baseboard_fab2_lib.baseboard_fab2(sch_1):page234_i86:b" )
			)
			( pin "C7L3.1"
				( objectStatus "@baseboard_fab2_lib.baseboard_fab2(sch_1):page234_i87:a" )
			)
			( pin "C7L3.2"
				( objectStatus "@baseboard_fab2_lib.baseboard_fab2(sch_1):page234_i87:b" )
			)
			( pin "C7L2.1"
				( objectStatus "@baseboard_fab2_lib.baseboard_fab2(sch_1):page234_i88:a" )
			)
			( pin "C7L2.2"
				( objectStatus "@baseboard_fab2_lib.baseboard_fab2(sch_1):page234_i88:b" )
			)
			( pin "C7L7.1"
				( objectStatus "@baseboard_fab2_lib.baseboard_fab2(sch_1):page234_i89:a" )
			)
			( pin "C7L7.2"
				( objectStatus "@baseboard_fab2_lib.baseboard_fab2(sch_1):page234_i89:b" )
			)
			( pin "C7L6.1"
				( objectStatus "@baseboard_fab2_lib.baseboard_fab2(sch_1):page234_i90:a" )
			)
			( pin "C7L6.2"
				( objectStatus "@baseboard_fab2_lib.baseboard_fab2(sch_1):page234_i90:b" )
			)
			( pin "C7M4.1"
				( objectStatus "@baseboard_fab2_lib.baseboard_fab2(sch_1):page234_i91:a" )
			)
			( pin "C7M4.2"
				( objectStatus "@baseboard_fab2_lib.baseboard_fab2(sch_1):page234_i91:b" )
			)
			( pin "C7M3.1"
				( objectStatus "@baseboard_fab2_lib.baseboard_fab2(sch_1):page234_i92:a" )
			)
			( pin "C7M3.2"
				( objectStatus "@baseboard_fab2_lib.baseboard_fab2(sch_1):page234_i92:b" )
			)
			( pin "C3A4.1"
				( objectStatus "@baseboard_fab2_lib.baseboard_fab2(sch_1):page234_i93:a" )
			)
			( pin "C3A4.2"
				( objectStatus "@baseboard_fab2_lib.baseboard_fab2(sch_1):page234_i93:b" )
			)
			( pin "C3B1.1"
				( objectStatus "@baseboard_fab2_lib.baseboard_fab2(sch_1):page234_i94:a" )
			)
			( pin "C3B1.2"
				( objectStatus "@baseboard_fab2_lib.baseboard_fab2(sch_1):page234_i94:b" )
			)
			( pin "C3A7.1"
				( objectStatus "@baseboard_fab2_lib.baseboard_fab2(sch_1):page234_i95:a" )
			)
			( pin "C3A7.2"
				( objectStatus "@baseboard_fab2_lib.baseboard_fab2(sch_1):page234_i95:b" )
			)
			( pin "C3A3.1"
				( objectStatus "@baseboard_fab2_lib.baseboard_fab2(sch_1):page234_i97:a" )
			)
			( pin "C3A3.2"
				( objectStatus "@baseboard_fab2_lib.baseboard_fab2(sch_1):page234_i97:b" )
			)
			( pin "C4B5.1"
				( objectStatus "@baseboard_fab2_lib.baseboard_fab2(sch_1):page234_i129:a" )
			)
			( pin "C4B5.2"
				( objectStatus "@baseboard_fab2_lib.baseboard_fab2(sch_1):page234_i129:b" )
			)
			( pin "C4B1.1"
				( objectStatus "@baseboard_fab2_lib.baseboard_fab2(sch_1):page234_i130:a" )
			)
			( pin "C4B1.2"
				( objectStatus "@baseboard_fab2_lib.baseboard_fab2(sch_1):page234_i130:b" )
			)
			( pin "C4B8.1"
				( objectStatus "@baseboard_fab2_lib.baseboard_fab2(sch_1):page234_i139:a" )
			)
			( pin "C4B8.2"
				( objectStatus "@baseboard_fab2_lib.baseboard_fab2(sch_1):page234_i139:b" )
			)
			( pin "R4B6.1"
				( objectStatus "@baseboard_fab2_lib.baseboard_fab2(sch_1):page234_i140:a" )
			)
			( pin "R4B6.2"
				( objectStatus "@baseboard_fab2_lib.baseboard_fab2(sch_1):page234_i140:b" )
			)
			( pin "R4B10.1"
				( objectStatus "@baseboard_fab2_lib.baseboard_fab2(sch_1):page234_i143:a" )
			)
			( pin "R4B10.2"
				( objectStatus "@baseboard_fab2_lib.baseboard_fab2(sch_1):page234_i143:b" )
			)
			( pin "C6L12.1"
				( objectStatus "@baseboard_fab2_lib.baseboard_fab2(sch_1):page234_i144:a" )
			)
			( pin "C6L12.2"
				( objectStatus "@baseboard_fab2_lib.baseboard_fab2(sch_1):page234_i144:b" )
			)
			( pin "C4B6.1"
				( objectStatus "@baseboard_fab2_lib.baseboard_fab2(sch_1):page234_i146:a" )
			)
			( pin "C4B6.2"
				( objectStatus "@baseboard_fab2_lib.baseboard_fab2(sch_1):page234_i146:b" )
			)
			( pin "C6L11.1"
				( objectStatus "@baseboard_fab2_lib.baseboard_fab2(sch_1):page234_i152:a" )
			)
			( pin "C6L11.2"
				( objectStatus "@baseboard_fab2_lib.baseboard_fab2(sch_1):page234_i152:b" )
			)
			( pin "FB4A1.1"
				( objectStatus "@baseboard_fab2_lib.baseboard_fab2(sch_1):page234_i154:a" )
			)
			( pin "FB4A1.2"
				( objectStatus "@baseboard_fab2_lib.baseboard_fab2(sch_1):page234_i154:b" )
			)
			( pin "R4B13.1"
				( objectStatus "@baseboard_fab2_lib.baseboard_fab2(sch_1):page234_i155:a" )
			)
			( pin "R4B13.2"
				( objectStatus "@baseboard_fab2_lib.baseboard_fab2(sch_1):page234_i155:b" )
			)
			( pin "R4A7.1"
				( objectStatus "@baseboard_fab2_lib.baseboard_fab2(sch_1):page234_i162:a" )
			)
			( pin "R4A7.2"
				( objectStatus "@baseboard_fab2_lib.baseboard_fab2(sch_1):page234_i162:b" )
			)
			( pin "C4A16.1"
				( objectStatus "@baseboard_fab2_lib.baseboard_fab2(sch_1):page234_i163:a" )
			)
			( pin "C4A16.2"
				( objectStatus "@baseboard_fab2_lib.baseboard_fab2(sch_1):page234_i163:b" )
			)
			( pin "L4A1.1"
				( objectStatus "@baseboard_fab2_lib.baseboard_fab2(sch_1):page234_i164:ina" )
			)
			( pin "L4A1.2"
				( objectStatus "@baseboard_fab2_lib.baseboard_fab2(sch_1):page234_i164:inb" )
			)
			( pin "C3B3.1"
				( objectStatus "@baseboard_fab2_lib.baseboard_fab2(sch_1):page234_i167:a" )
			)
			( pin "C3B3.2"
				( objectStatus "@baseboard_fab2_lib.baseboard_fab2(sch_1):page234_i167:b" )
			)
			( pin "C4B3.1"
				( objectStatus "@baseboard_fab2_lib.baseboard_fab2(sch_1):page234_i177:a" )
			)
			( pin "C4B3.2"
				( objectStatus "@baseboard_fab2_lib.baseboard_fab2(sch_1):page234_i177:b" )
			)
			( pin "C4B2.1"
				( objectStatus "@baseboard_fab2_lib.baseboard_fab2(sch_1):page234_i180:a" )
			)
			( pin "C4B2.2"
				( objectStatus "@baseboard_fab2_lib.baseboard_fab2(sch_1):page234_i180:b" )
			)
			( pin "C4B15.1"
				( objectStatus "@baseboard_fab2_lib.baseboard_fab2(sch_1):page234_i182:a" )
			)
			( pin "C4B15.2"
				( objectStatus "@baseboard_fab2_lib.baseboard_fab2(sch_1):page234_i182:b" )
			)
			( pin "R4B2.1"
				( objectStatus "@baseboard_fab2_lib.baseboard_fab2(sch_1):page234_i183:a" )
			)
			( pin "R4B2.2"
				( objectStatus "@baseboard_fab2_lib.baseboard_fab2(sch_1):page234_i183:b" )
			)
			( pin "EU4A3.5"
				( objectStatus "@baseboard_fab2_lib.baseboard_fab2(sch_1):page234_i184:agnd" )
			)
			( pin "EU4A3.36"
				( objectStatus "@baseboard_fab2_lib.baseboard_fab2(sch_1):page234_i184:bst" )
			)
			( pin "EU4A3.3"
				( objectStatus "@baseboard_fab2_lib.baseboard_fab2(sch_1):page234_i184:comp" )
			)
			( pin "EU4A3.40"
				( objectStatus "@baseboard_fab2_lib.baseboard_fab2(sch_1):page234_i184:en" )
			)
			( pin "EU4A3.2"
				( objectStatus "@baseboard_fab2_lib.baseboard_fab2(sch_1):page234_i184:fb" )
			)
			( pin "EU4A3.41"
				( objectStatus "@baseboard_fab2_lib.baseboard_fab2(sch_1):page234_i184:gnd" )
			)
			( pin "EU4A3.4"
				( objectStatus "@baseboard_fab2_lib.baseboard_fab2(sch_1):page234_i184:iset" )
			)
			( pin "EU4A3.6"
				( objectStatus "@baseboard_fab2_lib.baseboard_fab2(sch_1):page234_i184:ots" )
			)
			( pin "EU4A3.7"
				( objectStatus "@baseboard_fab2_lib.baseboard_fab2(sch_1):page234_i184:pg" )
			)
			( pin "EU4A3.16"
				( objectStatus "@baseboard_fab2_lib.baseboard_fab2(sch_1):page234_i184:pgnd(0)" )
			)
			( pin "EU4A3.17"
				( objectStatus "@baseboard_fab2_lib.baseboard_fab2(sch_1):page234_i184:pgnd(1)" )
			)
			( pin "EU4A3.18"
				( objectStatus "@baseboard_fab2_lib.baseboard_fab2(sch_1):page234_i184:pgnd(2)" )
			)
			( pin "EU4A3.19"
				( objectStatus "@baseboard_fab2_lib.baseboard_fab2(sch_1):page234_i184:pgnd(3)" )
			)
			( pin "EU4A3.20"
				( objectStatus "@baseboard_fab2_lib.baseboard_fab2(sch_1):page234_i184:pgnd(4)" )
			)
			( pin "EU4A3.21"
				( objectStatus "@baseboard_fab2_lib.baseboard_fab2(sch_1):page234_i184:pgnd(5)" )
			)
			( pin "EU4A3.22"
				( objectStatus "@baseboard_fab2_lib.baseboard_fab2(sch_1):page234_i184:pgnd(6)" )
			)
			( pin "EU4A3.23"
				( objectStatus "@baseboard_fab2_lib.baseboard_fab2(sch_1):page234_i184:pgnd(7)" )
			)
			( pin "EU4A3.24"
				( objectStatus "@baseboard_fab2_lib.baseboard_fab2(sch_1):page234_i184:pgnd(8)" )
			)
			( pin "EU4A3.25"
				( objectStatus "@baseboard_fab2_lib.baseboard_fab2(sch_1):page234_i184:pgnd(9)" )
			)
			( pin "EU4A3.26"
				( objectStatus "@baseboard_fab2_lib.baseboard_fab2(sch_1):page234_i184:pgnd(10)" )
			)
			( pin "EU4A3.27"
				( objectStatus "@baseboard_fab2_lib.baseboard_fab2(sch_1):page234_i184:pgnd(11)" )
			)
			( pin "EU4A3.28"
				( objectStatus "@baseboard_fab2_lib.baseboard_fab2(sch_1):page234_i184:pgnd(12)" )
			)
			( pin "EU4A3.37"
				( objectStatus "@baseboard_fab2_lib.baseboard_fab2(sch_1):page234_i184:pgnd(13)" )
			)
			( pin "EU4A3.1"
				( objectStatus "@baseboard_fab2_lib.baseboard_fab2(sch_1):page234_i184:ss" )
			)
			( pin "EU4A3.38"
				( objectStatus "@baseboard_fab2_lib.baseboard_fab2(sch_1):page234_i184:vb" )
			)
			( pin "EU4A3.39"
				( objectStatus "@baseboard_fab2_lib.baseboard_fab2(sch_1):page234_i184:vcc" )
			)
			( pin "EU4A3.8"
				( objectStatus "@baseboard_fab2_lib.baseboard_fab2(sch_1):page234_i184:vin(0)" )
			)
			( pin "EU4A3.9"
				( objectStatus "@baseboard_fab2_lib.baseboard_fab2(sch_1):page234_i184:vin(1)" )
			)
			( pin "EU4A3.10"
				( objectStatus "@baseboard_fab2_lib.baseboard_fab2(sch_1):page234_i184:vin(2)" )
			)
			( pin "EU4A3.11"
				( objectStatus "@baseboard_fab2_lib.baseboard_fab2(sch_1):page234_i184:vin(3)" )
			)
			( pin "EU4A3.12"
				( objectStatus "@baseboard_fab2_lib.baseboard_fab2(sch_1):page234_i184:vin(4)" )
			)
			( pin "EU4A3.13"
				( objectStatus "@baseboard_fab2_lib.baseboard_fab2(sch_1):page234_i184:vin(5)" )
			)
			( pin "EU4A3.14"
				( objectStatus "@baseboard_fab2_lib.baseboard_fab2(sch_1):page234_i184:vin(6)" )
			)
			( pin "EU4A3.42"
				( objectStatus "@baseboard_fab2_lib.baseboard_fab2(sch_1):page234_i184:vin(7)" )
			)
			( pin "EU4A3.35"
				( objectStatus "@baseboard_fab2_lib.baseboard_fab2(sch_1):page234_i184:vsw" )
			)
			( pin "EU4A3.15"
				( objectStatus "@baseboard_fab2_lib.baseboard_fab2(sch_1):page234_i184:vswh(0)" )
			)
			( pin "EU4A3.29"
				( objectStatus "@baseboard_fab2_lib.baseboard_fab2(sch_1):page234_i184:vswh(1)" )
			)
			( pin "EU4A3.30"
				( objectStatus "@baseboard_fab2_lib.baseboard_fab2(sch_1):page234_i184:vswh(2)" )
			)
			( pin "EU4A3.31"
				( objectStatus "@baseboard_fab2_lib.baseboard_fab2(sch_1):page234_i184:vswh(3)" )
			)
			( pin "EU4A3.32"
				( objectStatus "@baseboard_fab2_lib.baseboard_fab2(sch_1):page234_i184:vswh(4)" )
			)
			( pin "EU4A3.33"
				( objectStatus "@baseboard_fab2_lib.baseboard_fab2(sch_1):page234_i184:vswh(5)" )
			)
			( pin "EU4A3.34"
				( objectStatus "@baseboard_fab2_lib.baseboard_fab2(sch_1):page234_i184:vswh(6)" )
			)
			( pin "EU4A3.43"
				( objectStatus "@baseboard_fab2_lib.baseboard_fab2(sch_1):page234_i184:vswh(7)" )
			)
			( pin "C4A20.1"
				( objectStatus "@baseboard_fab2_lib.baseboard_fab2(sch_1):page234_i199:a" )
			)
			( pin "C4A20.2"
				( objectStatus "@baseboard_fab2_lib.baseboard_fab2(sch_1):page234_i199:b" )
			)
			( pin "R4B7.1"
				( objectStatus "@baseboard_fab2_lib.baseboard_fab2(sch_1):page234_i201:a" )
			)
			( pin "R4B7.2"
				( objectStatus "@baseboard_fab2_lib.baseboard_fab2(sch_1):page234_i201:b" )
			)
			( pin "C6L10.1"
				( objectStatus "@baseboard_fab2_lib.baseboard_fab2(sch_1):page234_i202:a" )
			)
			( pin "C6L10.2"
				( objectStatus "@baseboard_fab2_lib.baseboard_fab2(sch_1):page234_i202:b" )
			)
			( pin "C6M3.1"
				( objectStatus "@baseboard_fab2_lib.baseboard_fab2(sch_1):page234_i203:a" )
			)
			( pin "C6M3.2"
				( objectStatus "@baseboard_fab2_lib.baseboard_fab2(sch_1):page234_i203:b" )
			)
			( pin "C6M5.1"
				( objectStatus "@baseboard_fab2_lib.baseboard_fab2(sch_1):page234_i204:a" )
			)
			( pin "C6M5.2"
				( objectStatus "@baseboard_fab2_lib.baseboard_fab2(sch_1):page234_i204:b" )
			)
			( pin "C4A19.1"
				( objectStatus "@baseboard_fab2_lib.baseboard_fab2(sch_1):page234_i205:a" )
			)
			( pin "C4A19.2"
				( objectStatus "@baseboard_fab2_lib.baseboard_fab2(sch_1):page234_i205:b" )
			)
			( pin "C6L8.1"
				( objectStatus "@baseboard_fab2_lib.baseboard_fab2(sch_1):page234_i210:a" )
			)
			( pin "C6L8.2"
				( objectStatus "@baseboard_fab2_lib.baseboard_fab2(sch_1):page234_i210:b" )
			)
			( pin "C4B9.1"
				( objectStatus "@baseboard_fab2_lib.baseboard_fab2(sch_1):page234_i211:a" )
			)
			( pin "C4B9.2"
				( objectStatus "@baseboard_fab2_lib.baseboard_fab2(sch_1):page234_i211:b" )
			)
			( pin "C4B4.1"
				( objectStatus "@baseboard_fab2_lib.baseboard_fab2(sch_1):page234_i212:a" )
			)
			( pin "C4B4.2"
				( objectStatus "@baseboard_fab2_lib.baseboard_fab2(sch_1):page234_i212:b" )
			)
			( pin "R4B8.1"
				( objectStatus "@baseboard_fab2_lib.baseboard_fab2(sch_1):page234_i213:a" )
			)
			( pin "R4B8.2"
				( objectStatus "@baseboard_fab2_lib.baseboard_fab2(sch_1):page234_i213:b" )
			)
			( pin "R4B3.1"
				( objectStatus "@baseboard_fab2_lib.baseboard_fab2(sch_1):page234_i214:a" )
			)
			( pin "R4B3.2"
				( objectStatus "@baseboard_fab2_lib.baseboard_fab2(sch_1):page234_i214:b" )
			)
			( pin "R4B5.1"
				( objectStatus "@baseboard_fab2_lib.baseboard_fab2(sch_1):page234_i215:a" )
			)
			( pin "R4B5.2"
				( objectStatus "@baseboard_fab2_lib.baseboard_fab2(sch_1):page234_i215:b" )
			)
			( pin "R4B4.1"
				( objectStatus "@baseboard_fab2_lib.baseboard_fab2(sch_1):page234_i216:a" )
			)
			( pin "R4B4.2"
				( objectStatus "@baseboard_fab2_lib.baseboard_fab2(sch_1):page234_i216:b" )
			)
			( pin "C4B7.1"
				( objectStatus "@baseboard_fab2_lib.baseboard_fab2(sch_1):page234_i218:a" )
			)
			( pin "C4B7.2"
				( objectStatus "@baseboard_fab2_lib.baseboard_fab2(sch_1):page234_i218:b" )
			)
			( pin "R4B9.1"
				( objectStatus "@baseboard_fab2_lib.baseboard_fab2(sch_1):page234_i219:a" )
			)
			( pin "R4B9.2"
				( objectStatus "@baseboard_fab2_lib.baseboard_fab2(sch_1):page234_i219:b" )
			)
			( pin "R4B1.1"
				( objectStatus "@baseboard_fab2_lib.baseboard_fab2(sch_1):page234_i220:a" )
			)
			( pin "R4B1.2"
				( objectStatus "@baseboard_fab2_lib.baseboard_fab2(sch_1):page234_i220:b" )
			)
			( pin "C8A7.1"
				( objectStatus "@baseboard_fab2_lib.baseboard_fab2(sch_1):page235_i143:a" )
			)
			( pin "C8A7.2"
				( objectStatus "@baseboard_fab2_lib.baseboard_fab2(sch_1):page235_i143:b" )
			)
			( pin "C8A8.1"
				( objectStatus "@baseboard_fab2_lib.baseboard_fab2(sch_1):page235_i145:a" )
			)
			( pin "C8A8.2"
				( objectStatus "@baseboard_fab2_lib.baseboard_fab2(sch_1):page235_i145:b" )
			)
			( pin "R2L16.1"
				( objectStatus "@baseboard_fab2_lib.baseboard_fab2(sch_1):page235_i147:a" )
			)
			( pin "R2L16.2"
				( objectStatus "@baseboard_fab2_lib.baseboard_fab2(sch_1):page235_i147:b" )
			)
			( pin "R2L24.1"
				( objectStatus "@baseboard_fab2_lib.baseboard_fab2(sch_1):page235_i148:a" )
			)
			( pin "R2L24.2"
				( objectStatus "@baseboard_fab2_lib.baseboard_fab2(sch_1):page235_i148:b" )
			)
			( pin "R8A6.1"
				( objectStatus "@baseboard_fab2_lib.baseboard_fab2(sch_1):page235_i149:a" )
			)
			( pin "R8A6.2"
				( objectStatus "@baseboard_fab2_lib.baseboard_fab2(sch_1):page235_i149:b" )
			)
			( pin "C2L8.1"
				( objectStatus "@baseboard_fab2_lib.baseboard_fab2(sch_1):page235_i151:a" )
			)
			( pin "C2L8.2"
				( objectStatus "@baseboard_fab2_lib.baseboard_fab2(sch_1):page235_i151:b" )
			)
			( pin "C2L2.1"
				( objectStatus "@baseboard_fab2_lib.baseboard_fab2(sch_1):page235_i153:a" )
			)
			( pin "C2L2.2"
				( objectStatus "@baseboard_fab2_lib.baseboard_fab2(sch_1):page235_i153:b" )
			)
			( pin "R2L8.1"
				( objectStatus "@baseboard_fab2_lib.baseboard_fab2(sch_1):page235_i154:a" )
			)
			( pin "R2L8.2"
				( objectStatus "@baseboard_fab2_lib.baseboard_fab2(sch_1):page235_i154:b" )
			)
			( pin "R2L14.1"
				( objectStatus "@baseboard_fab2_lib.baseboard_fab2(sch_1):page235_i159:a" )
			)
			( pin "R2L14.2"
				( objectStatus "@baseboard_fab2_lib.baseboard_fab2(sch_1):page235_i159:b" )
			)
			( pin "R8A4.1"
				( objectStatus "@baseboard_fab2_lib.baseboard_fab2(sch_1):page235_i165:a" )
			)
			( pin "R8A4.2"
				( objectStatus "@baseboard_fab2_lib.baseboard_fab2(sch_1):page235_i165:b" )
			)
			( pin "R2L10.1"
				( objectStatus "@baseboard_fab2_lib.baseboard_fab2(sch_1):page235_i166:a" )
			)
			( pin "R2L10.2"
				( objectStatus "@baseboard_fab2_lib.baseboard_fab2(sch_1):page235_i166:b" )
			)
			( pin "C8A3.1"
				( objectStatus "@baseboard_fab2_lib.baseboard_fab2(sch_1):page235_i167:a" )
			)
			( pin "C8A3.2"
				( objectStatus "@baseboard_fab2_lib.baseboard_fab2(sch_1):page235_i167:b" )
			)
			( pin "C2L11.1"
				( objectStatus "@baseboard_fab2_lib.baseboard_fab2(sch_1):page235_i169:a" )
			)
			( pin "C2L11.2"
				( objectStatus "@baseboard_fab2_lib.baseboard_fab2(sch_1):page235_i169:b" )
			)
			( pin "R8A8.1"
				( objectStatus "@baseboard_fab2_lib.baseboard_fab2(sch_1):page235_i172:a" )
			)
			( pin "R8A8.2"
				( objectStatus "@baseboard_fab2_lib.baseboard_fab2(sch_1):page235_i172:b" )
			)
			( pin "R8A9.1"
				( objectStatus "@baseboard_fab2_lib.baseboard_fab2(sch_1):page235_i173:a" )
			)
			( pin "R8A9.2"
				( objectStatus "@baseboard_fab2_lib.baseboard_fab2(sch_1):page235_i173:b" )
			)
			( pin "R2L9.1"
				( objectStatus "@baseboard_fab2_lib.baseboard_fab2(sch_1):page235_i176:a" )
			)
			( pin "R2L9.2"
				( objectStatus "@baseboard_fab2_lib.baseboard_fab2(sch_1):page235_i176:b" )
			)
			( pin "C8A2.1"
				( objectStatus "@baseboard_fab2_lib.baseboard_fab2(sch_1):page235_i209:a" )
			)
			( pin "C8A2.2"
				( objectStatus "@baseboard_fab2_lib.baseboard_fab2(sch_1):page235_i209:b" )
			)
			( pin "R8A1.1"
				( objectStatus "@baseboard_fab2_lib.baseboard_fab2(sch_1):page235_i210:a" )
			)
			( pin "R8A1.2"
				( objectStatus "@baseboard_fab2_lib.baseboard_fab2(sch_1):page235_i210:b" )
			)
			( pin "R8A5.1"
				( objectStatus "@baseboard_fab2_lib.baseboard_fab2(sch_1):page235_i216:a" )
			)
			( pin "R8A5.2"
				( objectStatus "@baseboard_fab2_lib.baseboard_fab2(sch_1):page235_i216:b" )
			)
			( pin "R8A2.1"
				( objectStatus "@baseboard_fab2_lib.baseboard_fab2(sch_1):page235_i217:a" )
			)
			( pin "R8A2.2"
				( objectStatus "@baseboard_fab2_lib.baseboard_fab2(sch_1):page235_i217:b" )
			)
			( pin "C8A9.1"
				( objectStatus "@baseboard_fab2_lib.baseboard_fab2(sch_1):page235_i218:a" )
			)
			( pin "C8A9.2"
				( objectStatus "@baseboard_fab2_lib.baseboard_fab2(sch_1):page235_i218:b" )
			)
			( pin "R2L17.1"
				( objectStatus "@baseboard_fab2_lib.baseboard_fab2(sch_1):page235_i221:a" )
			)
			( pin "R2L17.2"
				( objectStatus "@baseboard_fab2_lib.baseboard_fab2(sch_1):page235_i221:b" )
			)
			( pin "R8A7.1"
				( objectStatus "@baseboard_fab2_lib.baseboard_fab2(sch_1):page235_i222:a" )
			)
			( pin "R8A7.2"
				( objectStatus "@baseboard_fab2_lib.baseboard_fab2(sch_1):page235_i222:b" )
			)
			( pin "R2L1.1"
				( objectStatus "@baseboard_fab2_lib.baseboard_fab2(sch_1):page235_i224:a" )
			)
			( pin "R2L1.2"
				( objectStatus "@baseboard_fab2_lib.baseboard_fab2(sch_1):page235_i224:b" )
			)
			( pin "R2L7.1"
				( objectStatus "@baseboard_fab2_lib.baseboard_fab2(sch_1):page235_i225:a" )
			)
			( pin "R2L7.2"
				( objectStatus "@baseboard_fab2_lib.baseboard_fab2(sch_1):page235_i225:b" )
			)
			( pin "EU8A1.21"
				( objectStatus "@baseboard_fab2_lib.baseboard_fab2(sch_1):page235_i229:airef1" )
			)
			( pin "EU8A1.22"
				( objectStatus "@baseboard_fab2_lib.baseboard_fab2(sch_1):page235_i229:aisen1" )
			)
			( pin "EU8A1.5"
				( objectStatus "@baseboard_fab2_lib.baseboard_fab2(sch_1):page235_i229:apwm1" )
			)
			( pin "EU8A1.35"
				( objectStatus "@baseboard_fab2_lib.baseboard_fab2(sch_1):page235_i229:atsen" )
			)
			( pin "EU8A1.20"
				( objectStatus "@baseboard_fab2_lib.baseboard_fab2(sch_1):page235_i229:avref" )
			)
			( pin "EU8A1.10"
				( objectStatus "@baseboard_fab2_lib.baseboard_fab2(sch_1):page235_i229:avren" )
			)
			( pin "EU8A1.9"
				( objectStatus "@baseboard_fab2_lib.baseboard_fab2(sch_1):page235_i229:avrrdy" )
			)
			( pin "EU8A1.19"
				( objectStatus "@baseboard_fab2_lib.baseboard_fab2(sch_1):page235_i229:avsen" )
			)
			( pin "EU8A1.25"
				( objectStatus "@baseboard_fab2_lib.baseboard_fab2(sch_1):page235_i229:biref1" )
			)
			( pin "EU8A1.26"
				( objectStatus "@baseboard_fab2_lib.baseboard_fab2(sch_1):page235_i229:bisen1" )
			)
			( pin "EU8A1.3"
				( objectStatus "@baseboard_fab2_lib.baseboard_fab2(sch_1):page235_i229:bpwm1" )
			)
			( pin "EU8A1.34"
				( objectStatus "@baseboard_fab2_lib.baseboard_fab2(sch_1):page235_i229:btsen" )
			)
			( pin "EU8A1.30"
				( objectStatus "@baseboard_fab2_lib.baseboard_fab2(sch_1):page235_i229:bvref" )
			)
			( pin "EU8A1.29"
				( objectStatus "@baseboard_fab2_lib.baseboard_fab2(sch_1):page235_i229:bvsen" )
			)
			( pin "EU8A1.1"
				( objectStatus "@baseboard_fab2_lib.baseboard_fab2(sch_1):page235_i229:dnc(0)" )
			)
			( pin "EU8A1.2"
				( objectStatus "@baseboard_fab2_lib.baseboard_fab2(sch_1):page235_i229:dnc(1)" )
			)
			( pin "EU8A1.4"
				( objectStatus "@baseboard_fab2_lib.baseboard_fab2(sch_1):page235_i229:dnc(2)" )
			)
			( pin "EU8A1.24"
				( objectStatus "@baseboard_fab2_lib.baseboard_fab2(sch_1):page235_i229:dnc(3)" )
			)
			( pin "EU8A1.28"
				( objectStatus "@baseboard_fab2_lib.baseboard_fab2(sch_1):page235_i229:dnc(4)" )
			)
			( pin "EU8A1.27"
				( objectStatus "@baseboard_fab2_lib.baseboard_fab2(sch_1):page235_i229:gnd(0)" )
			)
			( pin "EU8A1.23"
				( objectStatus "@baseboard_fab2_lib.baseboard_fab2(sch_1):page235_i229:gnd(1)" )
			)
			( pin "EU8A1.38"
				( objectStatus "@baseboard_fab2_lib.baseboard_fab2(sch_1):page235_i229:iinsen" )
			)
			( pin "EU8A1.13"
				( objectStatus "@baseboard_fab2_lib.baseboard_fab2(sch_1):page235_i229:mp0" )
			)
			( pin "EU8A1.14"
				( objectStatus "@baseboard_fab2_lib.baseboard_fab2(sch_1):page235_i229:mp1" )
			)
			( pin "EU8A1.18"
				( objectStatus "@baseboard_fab2_lib.baseboard_fab2(sch_1):page235_i229:mp2" )
			)
			( pin "EU8A1.31"
				( objectStatus "@baseboard_fab2_lib.baseboard_fab2(sch_1):page235_i229:mp3" )
			)
			( pin "EU8A1.32"
				( objectStatus "@baseboard_fab2_lib.baseboard_fab2(sch_1):page235_i229:mp4" )
			)
			( pin "EU8A1.12"
				( objectStatus "@baseboard_fab2_lib.baseboard_fab2(sch_1):page235_i229:pinalrt_n" )
			)
			( pin "EU8A1.8"
				( objectStatus "@baseboard_fab2_lib.baseboard_fab2(sch_1):page235_i229:reset_n" )
			)
			( pin "EU8A1.7"
				( objectStatus "@baseboard_fab2_lib.baseboard_fab2(sch_1):page235_i229:scl" )
			)
			( pin "EU8A1.6"
				( objectStatus "@baseboard_fab2_lib.baseboard_fab2(sch_1):page235_i229:sda" )
			)
			( pin "EU8A1.41"
				( objectStatus "@baseboard_fab2_lib.baseboard_fab2(sch_1):page235_i229:thpad" )
			)
			( pin "EU8A1.17"
				( objectStatus "@baseboard_fab2_lib.baseboard_fab2(sch_1):page235_i229:valrt_n" )
			)
			( pin "EU8A1.15"
				( objectStatus "@baseboard_fab2_lib.baseboard_fab2(sch_1):page235_i229:vclk" )
			)
			( pin "EU8A1.40"
				( objectStatus "@baseboard_fab2_lib.baseboard_fab2(sch_1):page235_i229:vd12" )
			)
			( pin "EU8A1.39"
				( objectStatus "@baseboard_fab2_lib.baseboard_fab2(sch_1):page235_i229:vdd" )
			)
			( pin "EU8A1.16"
				( objectStatus "@baseboard_fab2_lib.baseboard_fab2(sch_1):page235_i229:vdio" )
			)
			( pin "EU8A1.37"
				( objectStatus "@baseboard_fab2_lib.baseboard_fab2(sch_1):page235_i229:vinsen" )
			)
			( pin "EU8A1.11"
				( objectStatus "@baseboard_fab2_lib.baseboard_fab2(sch_1):page235_i229:vrhot_n" )
			)
			( pin "EU8A1.36"
				( objectStatus "@baseboard_fab2_lib.baseboard_fab2(sch_1):page235_i229:xaddr1" )
			)
			( pin "EU8A1.33"
				( objectStatus "@baseboard_fab2_lib.baseboard_fab2(sch_1):page235_i229:xaddr2" )
			)
			( pin "R2L25.1"
				( objectStatus "@baseboard_fab2_lib.baseboard_fab2(sch_1):page235_i235:a" )
			)
			( pin "R2L25.2"
				( objectStatus "@baseboard_fab2_lib.baseboard_fab2(sch_1):page235_i235:b" )
			)
			( pin "R2L26.1"
				( objectStatus "@baseboard_fab2_lib.baseboard_fab2(sch_1):page235_i236:a" )
			)
			( pin "R2L26.2"
				( objectStatus "@baseboard_fab2_lib.baseboard_fab2(sch_1):page235_i236:b" )
			)
			( pin "C7A30.1"
				( objectStatus "@baseboard_fab2_lib.baseboard_fab2(sch_1):page236_i9:a" )
			)
			( pin "C7A30.2"
				( objectStatus "@baseboard_fab2_lib.baseboard_fab2(sch_1):page236_i9:b" )
			)
			( pin "L7A2.1"
				( objectStatus "@baseboard_fab2_lib.baseboard_fab2(sch_1):page236_i10:ina" )
			)
			( pin "L7A2.2"
				( objectStatus "@baseboard_fab2_lib.baseboard_fab2(sch_1):page236_i10:inb" )
			)
			( pin "R3L1.1"
				( objectStatus "@baseboard_fab2_lib.baseboard_fab2(sch_1):page236_i14:a" )
			)
			( pin "R3L1.2"
				( objectStatus "@baseboard_fab2_lib.baseboard_fab2(sch_1):page236_i14:b" )
			)
			( pin "C7A8.1"
				( objectStatus "@baseboard_fab2_lib.baseboard_fab2(sch_1):page236_i16:a" )
			)
			( pin "C7A8.2"
				( objectStatus "@baseboard_fab2_lib.baseboard_fab2(sch_1):page236_i16:b" )
			)
			( pin "C3L1.1"
				( objectStatus "@baseboard_fab2_lib.baseboard_fab2(sch_1):page236_i17:a" )
			)
			( pin "C3L1.2"
				( objectStatus "@baseboard_fab2_lib.baseboard_fab2(sch_1):page236_i17:b" )
			)
			( pin "C7A6.1"
				( objectStatus "@baseboard_fab2_lib.baseboard_fab2(sch_1):page236_i19:a" )
			)
			( pin "C7A6.2"
				( objectStatus "@baseboard_fab2_lib.baseboard_fab2(sch_1):page236_i19:b" )
			)
			( pin "C7A39.1"
				( objectStatus "@baseboard_fab2_lib.baseboard_fab2(sch_1):page236_i20:a" )
			)
			( pin "C7A39.2"
				( objectStatus "@baseboard_fab2_lib.baseboard_fab2(sch_1):page236_i20:b" )
			)
			( pin "C7A43.1"
				( objectStatus "@baseboard_fab2_lib.baseboard_fab2(sch_1):page236_i21:a" )
			)
			( pin "C7A43.2"
				( objectStatus "@baseboard_fab2_lib.baseboard_fab2(sch_1):page236_i21:b" )
			)
			( pin "C7A7.1"
				( objectStatus "@baseboard_fab2_lib.baseboard_fab2(sch_1):page236_i22:a" )
			)
			( pin "C7A7.2"
				( objectStatus "@baseboard_fab2_lib.baseboard_fab2(sch_1):page236_i22:b" )
			)
			( pin "C3L12.1"
				( objectStatus "@baseboard_fab2_lib.baseboard_fab2(sch_1):page236_i23:a" )
			)
			( pin "C3L12.2"
				( objectStatus "@baseboard_fab2_lib.baseboard_fab2(sch_1):page236_i23:b" )
			)
			( pin "C3L11.1"
				( objectStatus "@baseboard_fab2_lib.baseboard_fab2(sch_1):page236_i24:a" )
			)
			( pin "C3L11.2"
				( objectStatus "@baseboard_fab2_lib.baseboard_fab2(sch_1):page236_i24:b" )
			)
			( pin "C3L8.1"
				( objectStatus "@baseboard_fab2_lib.baseboard_fab2(sch_1):page236_i26:a" )
			)
			( pin "C3L8.2"
				( objectStatus "@baseboard_fab2_lib.baseboard_fab2(sch_1):page236_i26:b" )
			)
			( pin "C3L9.1"
				( objectStatus "@baseboard_fab2_lib.baseboard_fab2(sch_1):page236_i29:a" )
			)
			( pin "C3L9.2"
				( objectStatus "@baseboard_fab2_lib.baseboard_fab2(sch_1):page236_i29:b" )
			)
			( pin "C3L7.1"
				( objectStatus "@baseboard_fab2_lib.baseboard_fab2(sch_1):page236_i31:a" )
			)
			( pin "C3L7.2"
				( objectStatus "@baseboard_fab2_lib.baseboard_fab2(sch_1):page236_i31:b" )
			)
			( pin "C3L10.1"
				( objectStatus "@baseboard_fab2_lib.baseboard_fab2(sch_1):page236_i32:a" )
			)
			( pin "C3L10.2"
				( objectStatus "@baseboard_fab2_lib.baseboard_fab2(sch_1):page236_i32:b" )
			)
			( pin "C7A9.1"
				( objectStatus "@baseboard_fab2_lib.baseboard_fab2(sch_1):page236_i33:a" )
			)
			( pin "C7A9.2"
				( objectStatus "@baseboard_fab2_lib.baseboard_fab2(sch_1):page236_i33:b" )
			)
			( pin "C7A44.1"
				( objectStatus "@baseboard_fab2_lib.baseboard_fab2(sch_1):page236_i34:a" )
			)
			( pin "C7A44.2"
				( objectStatus "@baseboard_fab2_lib.baseboard_fab2(sch_1):page236_i34:b" )
			)
			( pin "C7A40.1"
				( objectStatus "@baseboard_fab2_lib.baseboard_fab2(sch_1):page236_i35:a" )
			)
			( pin "C7A40.2"
				( objectStatus "@baseboard_fab2_lib.baseboard_fab2(sch_1):page236_i35:b" )
			)
			( pin "C7A10.1"
				( objectStatus "@baseboard_fab2_lib.baseboard_fab2(sch_1):page236_i36:a" )
			)
			( pin "C7A10.2"
				( objectStatus "@baseboard_fab2_lib.baseboard_fab2(sch_1):page236_i36:b" )
			)
			( pin "C3L29.1"
				( objectStatus "@baseboard_fab2_lib.baseboard_fab2(sch_1):page236_i38:a" )
			)
			( pin "C3L29.2"
				( objectStatus "@baseboard_fab2_lib.baseboard_fab2(sch_1):page236_i38:b" )
			)
			( pin "C7A41.1"
				( objectStatus "@baseboard_fab2_lib.baseboard_fab2(sch_1):page236_i39:a" )
			)
			( pin "C7A41.2"
				( objectStatus "@baseboard_fab2_lib.baseboard_fab2(sch_1):page236_i39:b" )
			)
			( pin "R3L4.1"
				( objectStatus "@baseboard_fab2_lib.baseboard_fab2(sch_1):page236_i41:a" )
			)
			( pin "R3L4.2"
				( objectStatus "@baseboard_fab2_lib.baseboard_fab2(sch_1):page236_i41:b" )
			)
			( pin "L7A4.1"
				( objectStatus "@baseboard_fab2_lib.baseboard_fab2(sch_1):page236_i45:ina" )
			)
			( pin "L7A4.2"
				( objectStatus "@baseboard_fab2_lib.baseboard_fab2(sch_1):page236_i45:inb" )
			)
			( pin "C7A42.1"
				( objectStatus "@baseboard_fab2_lib.baseboard_fab2(sch_1):page236_i46:a" )
			)
			( pin "C7A42.2"
				( objectStatus "@baseboard_fab2_lib.baseboard_fab2(sch_1):page236_i46:b" )
			)
			( pin "R8B14.1"
				( objectStatus "@baseboard_fab2_lib.baseboard_fab2(sch_1):page236_i56:a" )
			)
			( pin "R8B14.2"
				( objectStatus "@baseboard_fab2_lib.baseboard_fab2(sch_1):page236_i56:b" )
			)
			( pin "R8B15.1"
				( objectStatus "@baseboard_fab2_lib.baseboard_fab2(sch_1):page236_i57:a" )
			)
			( pin "R8B15.2"
				( objectStatus "@baseboard_fab2_lib.baseboard_fab2(sch_1):page236_i57:b" )
			)
			( pin "R8B12.1"
				( objectStatus "@baseboard_fab2_lib.baseboard_fab2(sch_1):page236_i59:a" )
			)
			( pin "R8B12.2"
				( objectStatus "@baseboard_fab2_lib.baseboard_fab2(sch_1):page236_i59:b" )
			)
			( pin "C7A13.1"
				( objectStatus "@baseboard_fab2_lib.baseboard_fab2(sch_1):page236_i63:a" )
			)
			( pin "C7A13.2"
				( objectStatus "@baseboard_fab2_lib.baseboard_fab2(sch_1):page236_i63:b" )
			)
			( pin "C7A14.1"
				( objectStatus "@baseboard_fab2_lib.baseboard_fab2(sch_1):page236_i65:a" )
			)
			( pin "C7A14.2"
				( objectStatus "@baseboard_fab2_lib.baseboard_fab2(sch_1):page236_i65:b" )
			)
			( pin "C3L18.1"
				( objectStatus "@baseboard_fab2_lib.baseboard_fab2(sch_1):page236_i71:a" )
			)
			( pin "C3L18.2"
				( objectStatus "@baseboard_fab2_lib.baseboard_fab2(sch_1):page236_i71:b" )
			)
			( pin "C3L20.1"
				( objectStatus "@baseboard_fab2_lib.baseboard_fab2(sch_1):page236_i73:a" )
			)
			( pin "C3L20.2"
				( objectStatus "@baseboard_fab2_lib.baseboard_fab2(sch_1):page236_i73:b" )
			)
			( pin "C3L21.1"
				( objectStatus "@baseboard_fab2_lib.baseboard_fab2(sch_1):page236_i74:a" )
			)
			( pin "C3L21.2"
				( objectStatus "@baseboard_fab2_lib.baseboard_fab2(sch_1):page236_i74:b" )
			)
			( pin "C7A27.1"
				( objectStatus "@baseboard_fab2_lib.baseboard_fab2(sch_1):page236_i75:a" )
			)
			( pin "C7A27.2"
				( objectStatus "@baseboard_fab2_lib.baseboard_fab2(sch_1):page236_i75:b" )
			)
			( pin "C3L19.1"
				( objectStatus "@baseboard_fab2_lib.baseboard_fab2(sch_1):page236_i76:a" )
			)
			( pin "C3L19.2"
				( objectStatus "@baseboard_fab2_lib.baseboard_fab2(sch_1):page236_i76:b" )
			)
			( pin "C2L46.1"
				( objectStatus "@baseboard_fab2_lib.baseboard_fab2(sch_1):page236_i77:a" )
			)
			( pin "C2L46.2"
				( objectStatus "@baseboard_fab2_lib.baseboard_fab2(sch_1):page236_i77:b" )
			)
			( pin "C8A15.1"
				( objectStatus "@baseboard_fab2_lib.baseboard_fab2(sch_1):page236_i78:a" )
			)
			( pin "C8A15.2"
				( objectStatus "@baseboard_fab2_lib.baseboard_fab2(sch_1):page236_i78:b" )
			)
			( pin "C2L25.1"
				( objectStatus "@baseboard_fab2_lib.baseboard_fab2(sch_1):page236_i79:a" )
			)
			( pin "C2L25.2"
				( objectStatus "@baseboard_fab2_lib.baseboard_fab2(sch_1):page236_i79:b" )
			)
			( pin "R7A13.1"
				( objectStatus "@baseboard_fab2_lib.baseboard_fab2(sch_1):page236_i90:a" )
			)
			( pin "R7A13.2"
				( objectStatus "@baseboard_fab2_lib.baseboard_fab2(sch_1):page236_i90:b" )
			)
			( pin "R7A18.1"
				( objectStatus "@baseboard_fab2_lib.baseboard_fab2(sch_1):page236_i92:a" )
			)
			( pin "R7A18.2"
				( objectStatus "@baseboard_fab2_lib.baseboard_fab2(sch_1):page236_i92:b" )
			)
			( pin "R7A19.1"
				( objectStatus "@baseboard_fab2_lib.baseboard_fab2(sch_1):page236_i93:a" )
			)
			( pin "R7A19.2"
				( objectStatus "@baseboard_fab2_lib.baseboard_fab2(sch_1):page236_i93:b" )
			)
			( pin "R7A14.1"
				( objectStatus "@baseboard_fab2_lib.baseboard_fab2(sch_1):page236_i94:a" )
			)
			( pin "R7A14.2"
				( objectStatus "@baseboard_fab2_lib.baseboard_fab2(sch_1):page236_i94:b" )
			)
			( pin "EU7A3.33"
				( objectStatus "@baseboard_fab2_lib.baseboard_fab2(sch_1):page236_i116:boost" )
			)
			( pin "EU7A3.35"
				( objectStatus "@baseboard_fab2_lib.baseboard_fab2(sch_1):page236_i116:en" )
			)
			( pin "EU7A3.6"
				( objectStatus "@baseboard_fab2_lib.baseboard_fab2(sch_1):page236_i116:gl(0)" )
			)
			( pin "EU7A3.41"
				( objectStatus "@baseboard_fab2_lib.baseboard_fab2(sch_1):page236_i116:gl(1)" )
			)
			( pin "EU7A3.38"
				( objectStatus "@baseboard_fab2_lib.baseboard_fab2(sch_1):page236_i116:iout" )
			)
			( pin "EU7A3.2"
				( objectStatus "@baseboard_fab2_lib.baseboard_fab2(sch_1):page236_i116:lgnd" )
			)
			( pin "EU7A3.31"
				( objectStatus "@baseboard_fab2_lib.baseboard_fab2(sch_1):page236_i116:nc" )
			)
			( pin "EU7A3.37"
				( objectStatus "@baseboard_fab2_lib.baseboard_fab2(sch_1):page236_i116:ocset" )
			)
			( pin "EU7A3.5"
				( objectStatus "@baseboard_fab2_lib.baseboard_fab2(sch_1):page236_i116:pgnd(0)" )
			)
			( pin "EU7A3.7"
				( objectStatus "@baseboard_fab2_lib.baseboard_fab2(sch_1):page236_i116:pgnd(1)" )
			)
			( pin "EU7A3.40"
				( objectStatus "@baseboard_fab2_lib.baseboard_fab2(sch_1):page236_i116:pgnd(2)" )
			)
			( pin "EU7A3.32"
				( objectStatus "@baseboard_fab2_lib.baseboard_fab2(sch_1):page236_i116:phase" )
			)
			( pin "EU7A3.34"
				( objectStatus "@baseboard_fab2_lib.baseboard_fab2(sch_1):page236_i116:pwm" )
			)
			( pin "EU7A3.39"
				( objectStatus "@baseboard_fab2_lib.baseboard_fab2(sch_1):page236_i116:refin" )
			)
			( pin "EU7A3.10"
				( objectStatus "@baseboard_fab2_lib.baseboard_fab2(sch_1):page236_i116:sw" )
			)
			( pin "EU7A3.36"
				( objectStatus "@baseboard_fab2_lib.baseboard_fab2(sch_1):page236_i116:tout_flt" )
			)
			( pin "EU7A3.3"
				( objectStatus "@baseboard_fab2_lib.baseboard_fab2(sch_1):page236_i116:vcc" )
			)
			( pin "EU7A3.4"
				( objectStatus "@baseboard_fab2_lib.baseboard_fab2(sch_1):page236_i116:vdrv" )
			)
			( pin "EU7A3.25"
				( objectStatus "@baseboard_fab2_lib.baseboard_fab2(sch_1):page236_i116:vin(0)" )
			)
			( pin "EU7A3.30"
				( objectStatus "@baseboard_fab2_lib.baseboard_fab2(sch_1):page236_i116:vin(1)" )
			)
			( pin "EU7A3.1"
				( objectStatus "@baseboard_fab2_lib.baseboard_fab2(sch_1):page236_i116:vos" )
			)
			( pin "EU7A2.33"
				( objectStatus "@baseboard_fab2_lib.baseboard_fab2(sch_1):page236_i117:boost" )
			)
			( pin "EU7A2.35"
				( objectStatus "@baseboard_fab2_lib.baseboard_fab2(sch_1):page236_i117:en" )
			)
			( pin "EU7A2.6"
				( objectStatus "@baseboard_fab2_lib.baseboard_fab2(sch_1):page236_i117:gl(0)" )
			)
			( pin "EU7A2.41"
				( objectStatus "@baseboard_fab2_lib.baseboard_fab2(sch_1):page236_i117:gl(1)" )
			)
			( pin "EU7A2.38"
				( objectStatus "@baseboard_fab2_lib.baseboard_fab2(sch_1):page236_i117:iout" )
			)
			( pin "EU7A2.2"
				( objectStatus "@baseboard_fab2_lib.baseboard_fab2(sch_1):page236_i117:lgnd" )
			)
			( pin "EU7A2.31"
				( objectStatus "@baseboard_fab2_lib.baseboard_fab2(sch_1):page236_i117:nc" )
			)
			( pin "EU7A2.37"
				( objectStatus "@baseboard_fab2_lib.baseboard_fab2(sch_1):page236_i117:ocset" )
			)
			( pin "EU7A2.5"
				( objectStatus "@baseboard_fab2_lib.baseboard_fab2(sch_1):page236_i117:pgnd(0)" )
			)
			( pin "EU7A2.7"
				( objectStatus "@baseboard_fab2_lib.baseboard_fab2(sch_1):page236_i117:pgnd(1)" )
			)
			( pin "EU7A2.40"
				( objectStatus "@baseboard_fab2_lib.baseboard_fab2(sch_1):page236_i117:pgnd(2)" )
			)
			( pin "EU7A2.32"
				( objectStatus "@baseboard_fab2_lib.baseboard_fab2(sch_1):page236_i117:phase" )
			)
			( pin "EU7A2.34"
				( objectStatus "@baseboard_fab2_lib.baseboard_fab2(sch_1):page236_i117:pwm" )
			)
			( pin "EU7A2.39"
				( objectStatus "@baseboard_fab2_lib.baseboard_fab2(sch_1):page236_i117:refin" )
			)
			( pin "EU7A2.10"
				( objectStatus "@baseboard_fab2_lib.baseboard_fab2(sch_1):page236_i117:sw" )
			)
			( pin "EU7A2.36"
				( objectStatus "@baseboard_fab2_lib.baseboard_fab2(sch_1):page236_i117:tout_flt" )
			)
			( pin "EU7A2.3"
				( objectStatus "@baseboard_fab2_lib.baseboard_fab2(sch_1):page236_i117:vcc" )
			)
			( pin "EU7A2.4"
				( objectStatus "@baseboard_fab2_lib.baseboard_fab2(sch_1):page236_i117:vdrv" )
			)
			( pin "EU7A2.25"
				( objectStatus "@baseboard_fab2_lib.baseboard_fab2(sch_1):page236_i117:vin(0)" )
			)
			( pin "EU7A2.30"
				( objectStatus "@baseboard_fab2_lib.baseboard_fab2(sch_1):page236_i117:vin(1)" )
			)
			( pin "EU7A2.1"
				( objectStatus "@baseboard_fab2_lib.baseboard_fab2(sch_1):page236_i117:vos" )
			)
			( pin "R3L15.1"
				( objectStatus "@baseboard_fab2_lib.baseboard_fab2(sch_1):page236_i118:a" )
			)
			( pin "R3L15.2"
				( objectStatus "@baseboard_fab2_lib.baseboard_fab2(sch_1):page236_i118:b" )
			)
			( pin "R3L14.1"
				( objectStatus "@baseboard_fab2_lib.baseboard_fab2(sch_1):page236_i120:a" )
			)
			( pin "R3L14.2"
				( objectStatus "@baseboard_fab2_lib.baseboard_fab2(sch_1):page236_i120:b" )
			)
			( pin "R8A10.1"
				( objectStatus "@baseboard_fab2_lib.baseboard_fab2(sch_1):page237_i3:a" )
			)
			( pin "R8A10.2"
				( objectStatus "@baseboard_fab2_lib.baseboard_fab2(sch_1):page237_i3:b" )
			)
			( pin "C8A11.1"
				( objectStatus "@baseboard_fab2_lib.baseboard_fab2(sch_1):page237_i5:a" )
			)
			( pin "C8A11.2"
				( objectStatus "@baseboard_fab2_lib.baseboard_fab2(sch_1):page237_i5:b" )
			)
			( pin "C2L45.1"
				( objectStatus "@baseboard_fab2_lib.baseboard_fab2(sch_1):page237_i12:a" )
			)
			( pin "C2L45.2"
				( objectStatus "@baseboard_fab2_lib.baseboard_fab2(sch_1):page237_i12:b" )
			)
			( pin "C8A14.1"
				( objectStatus "@baseboard_fab2_lib.baseboard_fab2(sch_1):page237_i13:a" )
			)
			( pin "C8A14.2"
				( objectStatus "@baseboard_fab2_lib.baseboard_fab2(sch_1):page237_i13:b" )
			)
			( pin "R8A12.1"
				( objectStatus "@baseboard_fab2_lib.baseboard_fab2(sch_1):page237_i15:a" )
			)
			( pin "R8A12.2"
				( objectStatus "@baseboard_fab2_lib.baseboard_fab2(sch_1):page237_i15:b" )
			)
			( pin "C8A6.1"
				( objectStatus "@baseboard_fab2_lib.baseboard_fab2(sch_1):page237_i29:a" )
			)
			( pin "C8A6.2"
				( objectStatus "@baseboard_fab2_lib.baseboard_fab2(sch_1):page237_i29:b" )
			)
			( pin "C8A4.1"
				( objectStatus "@baseboard_fab2_lib.baseboard_fab2(sch_1):page237_i31:a" )
			)
			( pin "C8A4.2"
				( objectStatus "@baseboard_fab2_lib.baseboard_fab2(sch_1):page237_i31:b" )
			)
			( pin "C8A10.1"
				( objectStatus "@baseboard_fab2_lib.baseboard_fab2(sch_1):page237_i55:a" )
			)
			( pin "C8A10.2"
				( objectStatus "@baseboard_fab2_lib.baseboard_fab2(sch_1):page237_i55:b" )
			)
			( pin "C8A12.1"
				( objectStatus "@baseboard_fab2_lib.baseboard_fab2(sch_1):page237_i77:a" )
			)
			( pin "C8A12.2"
				( objectStatus "@baseboard_fab2_lib.baseboard_fab2(sch_1):page237_i77:b" )
			)
			( pin "C2L32.1"
				( objectStatus "@baseboard_fab2_lib.baseboard_fab2(sch_1):page237_i79:a" )
			)
			( pin "C2L32.2"
				( objectStatus "@baseboard_fab2_lib.baseboard_fab2(sch_1):page237_i79:b" )
			)
			( pin "R2L19.1"
				( objectStatus "@baseboard_fab2_lib.baseboard_fab2(sch_1):page237_i80:a" )
			)
			( pin "R2L19.2"
				( objectStatus "@baseboard_fab2_lib.baseboard_fab2(sch_1):page237_i80:b" )
			)
			( pin "R2L20.1"
				( objectStatus "@baseboard_fab2_lib.baseboard_fab2(sch_1):page237_i81:a" )
			)
			( pin "R2L20.2"
				( objectStatus "@baseboard_fab2_lib.baseboard_fab2(sch_1):page237_i81:b" )
			)
			( pin "EU8A2.4"
				( objectStatus "@baseboard_fab2_lib.baseboard_fab2(sch_1):page237_i86:adj_nc" )
			)
			( pin "EU8A2.6"
				( objectStatus "@baseboard_fab2_lib.baseboard_fab2(sch_1):page237_i86:en" )
			)
			( pin "EU8A2.11"
				( objectStatus "@baseboard_fab2_lib.baseboard_fab2(sch_1):page237_i86:gnd" )
			)
			( pin "EU8A2.5"
				( objectStatus "@baseboard_fab2_lib.baseboard_fab2(sch_1):page237_i86:pgood" )
			)
			( pin "EU8A2.10"
				( objectStatus "@baseboard_fab2_lib.baseboard_fab2(sch_1):page237_i86:vdd" )
			)
			( pin "EU8A2.7"
				( objectStatus "@baseboard_fab2_lib.baseboard_fab2(sch_1):page237_i86:vin(0)" )
			)
			( pin "EU8A2.8"
				( objectStatus "@baseboard_fab2_lib.baseboard_fab2(sch_1):page237_i86:vin(1)" )
			)
			( pin "EU8A2.9"
				( objectStatus "@baseboard_fab2_lib.baseboard_fab2(sch_1):page237_i86:vin(2)" )
			)
			( pin "EU8A2.1"
				( objectStatus "@baseboard_fab2_lib.baseboard_fab2(sch_1):page237_i86:vout(0)" )
			)
			( pin "EU8A2.2"
				( objectStatus "@baseboard_fab2_lib.baseboard_fab2(sch_1):page237_i86:vout(1)" )
			)
			( pin "EU8A2.3"
				( objectStatus "@baseboard_fab2_lib.baseboard_fab2(sch_1):page237_i86:vout(2)" )
			)
			( pin "R8A11.1"
				( objectStatus "@baseboard_fab2_lib.baseboard_fab2(sch_1):page237_i90:a" )
			)
			( pin "R8A11.2"
				( objectStatus "@baseboard_fab2_lib.baseboard_fab2(sch_1):page237_i90:b" )
			)
			( pin "C9F9.1"
				( objectStatus "@baseboard_fab2_lib.baseboard_fab2(sch_1):page238_i5:a" )
			)
			( pin "C9F9.2"
				( objectStatus "@baseboard_fab2_lib.baseboard_fab2(sch_1):page238_i5:b" )
			)
			( pin "C9F3.1"
				( objectStatus "@baseboard_fab2_lib.baseboard_fab2(sch_1):page238_i7:a" )
			)
			( pin "C9F3.2"
				( objectStatus "@baseboard_fab2_lib.baseboard_fab2(sch_1):page238_i7:b" )
			)
			( pin "R9F8.1"
				( objectStatus "@baseboard_fab2_lib.baseboard_fab2(sch_1):page238_i14:a" )
			)
			( pin "R9F8.2"
				( objectStatus "@baseboard_fab2_lib.baseboard_fab2(sch_1):page238_i14:b" )
			)
			( pin "C9F8.1"
				( objectStatus "@baseboard_fab2_lib.baseboard_fab2(sch_1):page238_i19:a" )
			)
			( pin "C9F8.2"
				( objectStatus "@baseboard_fab2_lib.baseboard_fab2(sch_1):page238_i19:b" )
			)
			( pin "R9F13.1"
				( objectStatus "@baseboard_fab2_lib.baseboard_fab2(sch_1):page238_i21:a" )
			)
			( pin "R9F13.2"
				( objectStatus "@baseboard_fab2_lib.baseboard_fab2(sch_1):page238_i21:b" )
			)
			( pin "C9E10.1"
				( objectStatus "@baseboard_fab2_lib.baseboard_fab2(sch_1):page238_i23:a" )
			)
			( pin "C9E10.2"
				( objectStatus "@baseboard_fab2_lib.baseboard_fab2(sch_1):page238_i23:b" )
			)
			( pin "C9F4.1"
				( objectStatus "@baseboard_fab2_lib.baseboard_fab2(sch_1):page238_i30:a" )
			)
			( pin "C9F4.2"
				( objectStatus "@baseboard_fab2_lib.baseboard_fab2(sch_1):page238_i30:b" )
			)
			( pin "C9E11.1"
				( objectStatus "@baseboard_fab2_lib.baseboard_fab2(sch_1):page238_i39:a" )
			)
			( pin "C9E11.2"
				( objectStatus "@baseboard_fab2_lib.baseboard_fab2(sch_1):page238_i39:b" )
			)
			( pin "EU9F1.4"
				( objectStatus "@baseboard_fab2_lib.baseboard_fab2(sch_1):page238_i40:adj_nc" )
			)
			( pin "EU9F1.6"
				( objectStatus "@baseboard_fab2_lib.baseboard_fab2(sch_1):page238_i40:en" )
			)
			( pin "EU9F1.11"
				( objectStatus "@baseboard_fab2_lib.baseboard_fab2(sch_1):page238_i40:gnd" )
			)
			( pin "EU9F1.5"
				( objectStatus "@baseboard_fab2_lib.baseboard_fab2(sch_1):page238_i40:pgood" )
			)
			( pin "EU9F1.10"
				( objectStatus "@baseboard_fab2_lib.baseboard_fab2(sch_1):page238_i40:vdd" )
			)
			( pin "EU9F1.7"
				( objectStatus "@baseboard_fab2_lib.baseboard_fab2(sch_1):page238_i40:vin(0)" )
			)
			( pin "EU9F1.8"
				( objectStatus "@baseboard_fab2_lib.baseboard_fab2(sch_1):page238_i40:vin(1)" )
			)
			( pin "EU9F1.9"
				( objectStatus "@baseboard_fab2_lib.baseboard_fab2(sch_1):page238_i40:vin(2)" )
			)
			( pin "EU9F1.1"
				( objectStatus "@baseboard_fab2_lib.baseboard_fab2(sch_1):page238_i40:vout(0)" )
			)
			( pin "EU9F1.2"
				( objectStatus "@baseboard_fab2_lib.baseboard_fab2(sch_1):page238_i40:vout(1)" )
			)
			( pin "EU9F1.3"
				( objectStatus "@baseboard_fab2_lib.baseboard_fab2(sch_1):page238_i40:vout(2)" )
			)
			( pin "R9F11.1"
				( objectStatus "@baseboard_fab2_lib.baseboard_fab2(sch_1):page238_i41:a" )
			)
			( pin "R9F11.2"
				( objectStatus "@baseboard_fab2_lib.baseboard_fab2(sch_1):page238_i41:b" )
			)
			( pin "C9F10.1"
				( objectStatus "@baseboard_fab2_lib.baseboard_fab2(sch_1):page239_i4:a" )
			)
			( pin "C9F10.2"
				( objectStatus "@baseboard_fab2_lib.baseboard_fab2(sch_1):page239_i4:b" )
			)
			( pin "R9F12.1"
				( objectStatus "@baseboard_fab2_lib.baseboard_fab2(sch_1):page239_i6:a" )
			)
			( pin "R9F12.2"
				( objectStatus "@baseboard_fab2_lib.baseboard_fab2(sch_1):page239_i6:b" )
			)
			( pin "C9F13.1"
				( objectStatus "@baseboard_fab2_lib.baseboard_fab2(sch_1):page239_i7:a" )
			)
			( pin "C9F13.2"
				( objectStatus "@baseboard_fab2_lib.baseboard_fab2(sch_1):page239_i7:b" )
			)
			( pin "C1T15.1"
				( objectStatus "@baseboard_fab2_lib.baseboard_fab2(sch_1):page239_i12:a" )
			)
			( pin "C1T15.2"
				( objectStatus "@baseboard_fab2_lib.baseboard_fab2(sch_1):page239_i12:b" )
			)
			( pin "R9F6.1"
				( objectStatus "@baseboard_fab2_lib.baseboard_fab2(sch_1):page238_i45:\1\" )
			)
			( pin "R9F6.2"
				( objectStatus "@baseboard_fab2_lib.baseboard_fab2(sch_1):page238_i45:\2\" )
			)
			( pin "R9F32.1"
				( objectStatus "@baseboard_fab2_lib.baseboard_fab2(sch_1):page239_i15:a" )
			)
			( pin "R9F32.2"
				( objectStatus "@baseboard_fab2_lib.baseboard_fab2(sch_1):page239_i15:b" )
			)
			( pin "C1T7.1"
				( objectStatus "@baseboard_fab2_lib.baseboard_fab2(sch_1):page239_i22:a" )
			)
			( pin "C1T7.2"
				( objectStatus "@baseboard_fab2_lib.baseboard_fab2(sch_1):page239_i22:b" )
			)
			( pin "C9F6.1"
				( objectStatus "@baseboard_fab2_lib.baseboard_fab2(sch_1):page239_i30:a" )
			)
			( pin "C9F6.2"
				( objectStatus "@baseboard_fab2_lib.baseboard_fab2(sch_1):page239_i30:b" )
			)
			( pin "EU9F2.4"
				( objectStatus "@baseboard_fab2_lib.baseboard_fab2(sch_1):page239_i70:adj_nc" )
			)
			( pin "EU9F2.6"
				( objectStatus "@baseboard_fab2_lib.baseboard_fab2(sch_1):page239_i70:en" )
			)
			( pin "EU9F2.11"
				( objectStatus "@baseboard_fab2_lib.baseboard_fab2(sch_1):page239_i70:gnd" )
			)
			( pin "EU9F2.5"
				( objectStatus "@baseboard_fab2_lib.baseboard_fab2(sch_1):page239_i70:pgood" )
			)
			( pin "EU9F2.10"
				( objectStatus "@baseboard_fab2_lib.baseboard_fab2(sch_1):page239_i70:vdd" )
			)
			( pin "EU9F2.7"
				( objectStatus "@baseboard_fab2_lib.baseboard_fab2(sch_1):page239_i70:vin(0)" )
			)
			( pin "EU9F2.8"
				( objectStatus "@baseboard_fab2_lib.baseboard_fab2(sch_1):page239_i70:vin(1)" )
			)
			( pin "EU9F2.9"
				( objectStatus "@baseboard_fab2_lib.baseboard_fab2(sch_1):page239_i70:vin(2)" )
			)
			( pin "EU9F2.1"
				( objectStatus "@baseboard_fab2_lib.baseboard_fab2(sch_1):page239_i70:vout(0)" )
			)
			( pin "EU9F2.2"
				( objectStatus "@baseboard_fab2_lib.baseboard_fab2(sch_1):page239_i70:vout(1)" )
			)
			( pin "EU9F2.3"
				( objectStatus "@baseboard_fab2_lib.baseboard_fab2(sch_1):page239_i70:vout(2)" )
			)
			( pin "C9F5.1"
				( objectStatus "@baseboard_fab2_lib.baseboard_fab2(sch_1):page239_i71:a" )
			)
			( pin "C9F5.2"
				( objectStatus "@baseboard_fab2_lib.baseboard_fab2(sch_1):page239_i71:b" )
			)
			( pin "R1T9.1"
				( objectStatus "@baseboard_fab2_lib.baseboard_fab2(sch_1):page239_i72:a" )
			)
			( pin "R1T9.2"
				( objectStatus "@baseboard_fab2_lib.baseboard_fab2(sch_1):page239_i72:b" )
			)
			( pin "R8F9.1"
				( objectStatus "@baseboard_fab2_lib.baseboard_fab2(sch_1):page240_i106:a" )
			)
			( pin "R8F9.2"
				( objectStatus "@baseboard_fab2_lib.baseboard_fab2(sch_1):page240_i106:b" )
			)
			( pin "C2R11.1"
				( objectStatus "@baseboard_fab2_lib.baseboard_fab2(sch_1):page240_i109:a" )
			)
			( pin "C2R11.2"
				( objectStatus "@baseboard_fab2_lib.baseboard_fab2(sch_1):page240_i109:b" )
			)
			( pin "R8F1.1"
				( objectStatus "@baseboard_fab2_lib.baseboard_fab2(sch_1):page240_i111:a" )
			)
			( pin "R8F1.2"
				( objectStatus "@baseboard_fab2_lib.baseboard_fab2(sch_1):page240_i111:b" )
			)
			( pin "C8E17.1"
				( objectStatus "@baseboard_fab2_lib.baseboard_fab2(sch_1):page240_i113:a" )
			)
			( pin "C8E17.2"
				( objectStatus "@baseboard_fab2_lib.baseboard_fab2(sch_1):page240_i113:b" )
			)
			( pin "C8F2.1"
				( objectStatus "@baseboard_fab2_lib.baseboard_fab2(sch_1):page240_i116:a" )
			)
			( pin "C8F2.2"
				( objectStatus "@baseboard_fab2_lib.baseboard_fab2(sch_1):page240_i116:b" )
			)
			( pin "R8F5.1"
				( objectStatus "@baseboard_fab2_lib.baseboard_fab2(sch_1):page240_i117:a" )
			)
			( pin "R8F5.2"
				( objectStatus "@baseboard_fab2_lib.baseboard_fab2(sch_1):page240_i117:b" )
			)
			( pin "EU8F1.4"
				( objectStatus "@baseboard_fab2_lib.baseboard_fab2(sch_1):page240_i125:boot" )
			)
			( pin "EU8F1.10"
				( objectStatus "@baseboard_fab2_lib.baseboard_fab2(sch_1):page240_i125:cs" )
			)
			( pin "EU8F1.8"
				( objectStatus "@baseboard_fab2_lib.baseboard_fab2(sch_1):page240_i125:en" )
			)
			( pin "EU8F1.11"
				( objectStatus "@baseboard_fab2_lib.baseboard_fab2(sch_1):page240_i125:g0" )
			)
			( pin "EU8F1.12"
				( objectStatus "@baseboard_fab2_lib.baseboard_fab2(sch_1):page240_i125:gnd(0)" )
			)
			( pin "EU8F1.13"
				( objectStatus "@baseboard_fab2_lib.baseboard_fab2(sch_1):page240_i125:gnd(1)" )
			)
			( pin "EU8F1.1"
				( objectStatus "@baseboard_fab2_lib.baseboard_fab2(sch_1):page240_i125:lgate" )
			)
			( pin "EU8F1.9"
				( objectStatus "@baseboard_fab2_lib.baseboard_fab2(sch_1):page240_i125:pgood" )
			)
			( pin "EU8F1.2"
				( objectStatus "@baseboard_fab2_lib.baseboard_fab2(sch_1):page240_i125:phase" )
			)
			( pin "EU8F1.7"
				( objectStatus "@baseboard_fab2_lib.baseboard_fab2(sch_1):page240_i125:rgnd" )
			)
			( pin "EU8F1.3"
				( objectStatus "@baseboard_fab2_lib.baseboard_fab2(sch_1):page240_i125:ugate" )
			)
			( pin "EU8F1.5"
				( objectStatus "@baseboard_fab2_lib.baseboard_fab2(sch_1):page240_i125:vcc" )
			)
			( pin "EU8F1.6"
				( objectStatus "@baseboard_fab2_lib.baseboard_fab2(sch_1):page240_i125:vout" )
			)
			( pin "R8E35.1"
				( objectStatus "@baseboard_fab2_lib.baseboard_fab2(sch_1):page240_i127:a" )
			)
			( pin "R8E35.2"
				( objectStatus "@baseboard_fab2_lib.baseboard_fab2(sch_1):page240_i127:b" )
			)
			( pin "C8E12.1"
				( objectStatus "@baseboard_fab2_lib.baseboard_fab2(sch_1):page240_i129:a" )
			)
			( pin "C8E12.2"
				( objectStatus "@baseboard_fab2_lib.baseboard_fab2(sch_1):page240_i129:b" )
			)
			( pin "FB9E1.1"
				( objectStatus "@baseboard_fab2_lib.baseboard_fab2(sch_1):page240_i132:a" )
			)
			( pin "FB9E1.2"
				( objectStatus "@baseboard_fab2_lib.baseboard_fab2(sch_1):page240_i132:b" )
			)
			( pin "C9F1.1"
				( objectStatus "@baseboard_fab2_lib.baseboard_fab2(sch_1):page240_i134:a" )
			)
			( pin "C9F1.2"
				( objectStatus "@baseboard_fab2_lib.baseboard_fab2(sch_1):page240_i134:b" )
			)
			( pin "C8E11.1"
				( objectStatus "@baseboard_fab2_lib.baseboard_fab2(sch_1):page240_i135:a" )
			)
			( pin "C8E11.2"
				( objectStatus "@baseboard_fab2_lib.baseboard_fab2(sch_1):page240_i135:b" )
			)
			( pin "C8E10.1"
				( objectStatus "@baseboard_fab2_lib.baseboard_fab2(sch_1):page240_i137:a" )
			)
			( pin "C8E10.2"
				( objectStatus "@baseboard_fab2_lib.baseboard_fab2(sch_1):page240_i137:b" )
			)
			( pin "C8E14.1"
				( objectStatus "@baseboard_fab2_lib.baseboard_fab2(sch_1):page240_i139:a" )
			)
			( pin "C8E14.2"
				( objectStatus "@baseboard_fab2_lib.baseboard_fab2(sch_1):page240_i139:b" )
			)
			( pin "R8E38.1"
				( objectStatus "@baseboard_fab2_lib.baseboard_fab2(sch_1):page240_i140:a" )
			)
			( pin "R8E38.2"
				( objectStatus "@baseboard_fab2_lib.baseboard_fab2(sch_1):page240_i140:b" )
			)
			( pin "R8E34.1"
				( objectStatus "@baseboard_fab2_lib.baseboard_fab2(sch_1):page240_i142:a" )
			)
			( pin "R8E34.2"
				( objectStatus "@baseboard_fab2_lib.baseboard_fab2(sch_1):page240_i142:b" )
			)
			( pin "R8E31.1"
				( objectStatus "@baseboard_fab2_lib.baseboard_fab2(sch_1):page240_i143:a" )
			)
			( pin "R8E31.2"
				( objectStatus "@baseboard_fab2_lib.baseboard_fab2(sch_1):page240_i143:b" )
			)
			( pin "R8E25.1"
				( objectStatus "@baseboard_fab2_lib.baseboard_fab2(sch_1):page240_i144:a" )
			)
			( pin "R8E25.2"
				( objectStatus "@baseboard_fab2_lib.baseboard_fab2(sch_1):page240_i144:b" )
			)
			( pin "R8F11.1"
				( objectStatus "@baseboard_fab2_lib.baseboard_fab2(sch_1):page240_i146:a" )
			)
			( pin "R8F11.2"
				( objectStatus "@baseboard_fab2_lib.baseboard_fab2(sch_1):page240_i146:b" )
			)
			( pin "R8F3.1"
				( objectStatus "@baseboard_fab2_lib.baseboard_fab2(sch_1):page240_i148:a" )
			)
			( pin "R8F3.2"
				( objectStatus "@baseboard_fab2_lib.baseboard_fab2(sch_1):page240_i148:b" )
			)
			( pin "R2T4.1"
				( objectStatus "@baseboard_fab2_lib.baseboard_fab2(sch_1):page240_i152:a" )
			)
			( pin "R2T4.2"
				( objectStatus "@baseboard_fab2_lib.baseboard_fab2(sch_1):page240_i152:b" )
			)
			( pin "C8F14.1"
				( objectStatus "@baseboard_fab2_lib.baseboard_fab2(sch_1):page240_i154:a" )
			)
			( pin "C8F14.2"
				( objectStatus "@baseboard_fab2_lib.baseboard_fab2(sch_1):page240_i154:b" )
			)
			( pin "C8F8.1"
				( objectStatus "@baseboard_fab2_lib.baseboard_fab2(sch_1):page240_i155:a" )
			)
			( pin "C8F8.2"
				( objectStatus "@baseboard_fab2_lib.baseboard_fab2(sch_1):page240_i155:b" )
			)
			( pin "C2T7.1"
				( objectStatus "@baseboard_fab2_lib.baseboard_fab2(sch_1):page240_i158:a" )
			)
			( pin "C2T7.2"
				( objectStatus "@baseboard_fab2_lib.baseboard_fab2(sch_1):page240_i158:b" )
			)
			( pin "C2T6.1"
				( objectStatus "@baseboard_fab2_lib.baseboard_fab2(sch_1):page240_i160:a" )
			)
			( pin "C2T6.2"
				( objectStatus "@baseboard_fab2_lib.baseboard_fab2(sch_1):page240_i160:b" )
			)
			( pin "C8F3.1"
				( objectStatus "@baseboard_fab2_lib.baseboard_fab2(sch_1):page240_i163:a" )
			)
			( pin "C8F3.2"
				( objectStatus "@baseboard_fab2_lib.baseboard_fab2(sch_1):page240_i163:b" )
			)
			( pin "EU8E1.4"
				( objectStatus "@baseboard_fab2_lib.baseboard_fab2(sch_1):page240_i170:bg" )
			)
			( pin "EU8E1.3"
				( objectStatus "@baseboard_fab2_lib.baseboard_fab2(sch_1):page240_i170:pgnd" )
			)
			( pin "EU8E1.1"
				( objectStatus "@baseboard_fab2_lib.baseboard_fab2(sch_1):page240_i170:tg" )
			)
			( pin "EU8E1.2"
				( objectStatus "@baseboard_fab2_lib.baseboard_fab2(sch_1):page240_i170:vin" )
			)
			( pin "EU8E1.5"
				( objectStatus "@baseboard_fab2_lib.baseboard_fab2(sch_1):page240_i170:vsw" )
			)
			( pin "R8F10.1"
				( objectStatus "@baseboard_fab2_lib.baseboard_fab2(sch_1):page240_i171:a" )
			)
			( pin "R8F10.2"
				( objectStatus "@baseboard_fab2_lib.baseboard_fab2(sch_1):page240_i171:b" )
			)
			( pin "L8F1.1"
				( objectStatus "@baseboard_fab2_lib.baseboard_fab2(sch_1):page240_i173:ina" )
			)
			( pin "L8F1.2"
				( objectStatus "@baseboard_fab2_lib.baseboard_fab2(sch_1):page240_i173:inb" )
			)
			( pin "C2T9.1"
				( objectStatus "@baseboard_fab2_lib.baseboard_fab2(sch_1):page240_i174:a" )
			)
			( pin "C2T9.2"
				( objectStatus "@baseboard_fab2_lib.baseboard_fab2(sch_1):page240_i174:b" )
			)
			( pin "R8F2.1"
				( objectStatus "@baseboard_fab2_lib.baseboard_fab2(sch_1):page240_i176:a" )
			)
			( pin "R8F2.2"
				( objectStatus "@baseboard_fab2_lib.baseboard_fab2(sch_1):page240_i176:b" )
			)
			( pin "R8E40.1"
				( objectStatus "@baseboard_fab2_lib.baseboard_fab2(sch_1):page240_i177:a" )
			)
			( pin "R8E40.2"
				( objectStatus "@baseboard_fab2_lib.baseboard_fab2(sch_1):page240_i177:b" )
			)
			( pin "C8E9.1"
				( objectStatus "@baseboard_fab2_lib.baseboard_fab2(sch_1):page241_i2:a" )
			)
			( pin "C8E9.2"
				( objectStatus "@baseboard_fab2_lib.baseboard_fab2(sch_1):page241_i2:b" )
			)
			( pin "C8E7.1"
				( objectStatus "@baseboard_fab2_lib.baseboard_fab2(sch_1):page241_i3:a" )
			)
			( pin "C8E7.2"
				( objectStatus "@baseboard_fab2_lib.baseboard_fab2(sch_1):page241_i3:b" )
			)
			( pin "C8E4.1"
				( objectStatus "@baseboard_fab2_lib.baseboard_fab2(sch_1):page241_i8:a" )
			)
			( pin "C8E4.2"
				( objectStatus "@baseboard_fab2_lib.baseboard_fab2(sch_1):page241_i8:b" )
			)
			( pin "R8E18.1"
				( objectStatus "@baseboard_fab2_lib.baseboard_fab2(sch_1):page241_i9:a" )
			)
			( pin "R8E18.2"
				( objectStatus "@baseboard_fab2_lib.baseboard_fab2(sch_1):page241_i9:b" )
			)
			( pin "R7E12.1"
				( objectStatus "@baseboard_fab2_lib.baseboard_fab2(sch_1):page241_i11:a" )
			)
			( pin "R7E12.2"
				( objectStatus "@baseboard_fab2_lib.baseboard_fab2(sch_1):page241_i11:b" )
			)
			( pin "C8E6.1"
				( objectStatus "@baseboard_fab2_lib.baseboard_fab2(sch_1):page241_i12:a" )
			)
			( pin "C8E6.2"
				( objectStatus "@baseboard_fab2_lib.baseboard_fab2(sch_1):page241_i12:b" )
			)
			( pin "C7E10.1"
				( objectStatus "@baseboard_fab2_lib.baseboard_fab2(sch_1):page241_i14:a" )
			)
			( pin "C7E10.2"
				( objectStatus "@baseboard_fab2_lib.baseboard_fab2(sch_1):page241_i14:b" )
			)
			( pin "R7E14.1"
				( objectStatus "@baseboard_fab2_lib.baseboard_fab2(sch_1):page241_i18:a" )
			)
			( pin "R7E14.2"
				( objectStatus "@baseboard_fab2_lib.baseboard_fab2(sch_1):page241_i18:b" )
			)
			( pin "C7E14.1"
				( objectStatus "@baseboard_fab2_lib.baseboard_fab2(sch_1):page241_i30:a" )
			)
			( pin "C7E14.2"
				( objectStatus "@baseboard_fab2_lib.baseboard_fab2(sch_1):page241_i30:b" )
			)
			( pin "R7E17.1"
				( objectStatus "@baseboard_fab2_lib.baseboard_fab2(sch_1):page241_i37:a" )
			)
			( pin "R7E17.2"
				( objectStatus "@baseboard_fab2_lib.baseboard_fab2(sch_1):page241_i37:b" )
			)
			( pin "C7E11.1"
				( objectStatus "@baseboard_fab2_lib.baseboard_fab2(sch_1):page241_i39:a" )
			)
			( pin "C7E11.2"
				( objectStatus "@baseboard_fab2_lib.baseboard_fab2(sch_1):page241_i39:b" )
			)
			( pin "C8E13.1"
				( objectStatus "@baseboard_fab2_lib.baseboard_fab2(sch_1):page241_i41:a" )
			)
			( pin "C8E13.2"
				( objectStatus "@baseboard_fab2_lib.baseboard_fab2(sch_1):page241_i41:b" )
			)
			( pin "C7E13.1"
				( objectStatus "@baseboard_fab2_lib.baseboard_fab2(sch_1):page241_i45:a" )
			)
			( pin "C7E13.2"
				( objectStatus "@baseboard_fab2_lib.baseboard_fab2(sch_1):page241_i45:b" )
			)
			( pin "C7E12.1"
				( objectStatus "@baseboard_fab2_lib.baseboard_fab2(sch_1):page241_i47:a" )
			)
			( pin "C7E12.2"
				( objectStatus "@baseboard_fab2_lib.baseboard_fab2(sch_1):page241_i47:b" )
			)
			( pin "R7F1.1"
				( objectStatus "@baseboard_fab2_lib.baseboard_fab2(sch_1):page241_i50:a" )
			)
			( pin "R7F1.2"
				( objectStatus "@baseboard_fab2_lib.baseboard_fab2(sch_1):page241_i50:b" )
			)
			( pin "R7E16.1"
				( objectStatus "@baseboard_fab2_lib.baseboard_fab2(sch_1):page241_i51:a" )
			)
			( pin "R7E16.2"
				( objectStatus "@baseboard_fab2_lib.baseboard_fab2(sch_1):page241_i51:b" )
			)
			( pin "C8E16.1"
				( objectStatus "@baseboard_fab2_lib.baseboard_fab2(sch_1):page241_i53:a" )
			)
			( pin "C8E16.2"
				( objectStatus "@baseboard_fab2_lib.baseboard_fab2(sch_1):page241_i53:b" )
			)
			( pin "R8E39.1"
				( objectStatus "@baseboard_fab2_lib.baseboard_fab2(sch_1):page241_i54:a" )
			)
			( pin "R8E39.2"
				( objectStatus "@baseboard_fab2_lib.baseboard_fab2(sch_1):page241_i54:b" )
			)
			( pin "C8F1.1"
				( objectStatus "@baseboard_fab2_lib.baseboard_fab2(sch_1):page241_i57:a" )
			)
			( pin "C8F1.2"
				( objectStatus "@baseboard_fab2_lib.baseboard_fab2(sch_1):page241_i57:b" )
			)
			( pin "R7E13.1"
				( objectStatus "@baseboard_fab2_lib.baseboard_fab2(sch_1):page241_i58:a" )
			)
			( pin "R7E13.2"
				( objectStatus "@baseboard_fab2_lib.baseboard_fab2(sch_1):page241_i58:b" )
			)
			( pin "C8E15.1"
				( objectStatus "@baseboard_fab2_lib.baseboard_fab2(sch_1):page241_i63:a" )
			)
			( pin "C8E15.2"
				( objectStatus "@baseboard_fab2_lib.baseboard_fab2(sch_1):page241_i63:b" )
			)
			( pin "R8E37.1"
				( objectStatus "@baseboard_fab2_lib.baseboard_fab2(sch_1):page241_i78:a" )
			)
			( pin "R8E37.2"
				( objectStatus "@baseboard_fab2_lib.baseboard_fab2(sch_1):page241_i78:b" )
			)
			( pin "FB7E1.1"
				( objectStatus "@baseboard_fab2_lib.baseboard_fab2(sch_1):page241_i82:a" )
			)
			( pin "FB7E1.2"
				( objectStatus "@baseboard_fab2_lib.baseboard_fab2(sch_1):page241_i82:b" )
			)
			( pin "EU7E2.13"
				( objectStatus "@baseboard_fab2_lib.baseboard_fab2(sch_1):page241_i83:boot" )
			)
			( pin "EU7E2.8"
				( objectStatus "@baseboard_fab2_lib.baseboard_fab2(sch_1):page241_i83:comp" )
			)
			( pin "EU7E2.10"
				( objectStatus "@baseboard_fab2_lib.baseboard_fab2(sch_1):page241_i83:en" )
			)
			( pin "EU7E2.2"
				( objectStatus "@baseboard_fab2_lib.baseboard_fab2(sch_1):page241_i83:gnd(0)" )
			)
			( pin "EU7E2.3"
				( objectStatus "@baseboard_fab2_lib.baseboard_fab2(sch_1):page241_i83:gnd(1)" )
			)
			( pin "EU7E2.11"
				( objectStatus "@baseboard_fab2_lib.baseboard_fab2(sch_1):page241_i83:ph(0)" )
			)
			( pin "EU7E2.12"
				( objectStatus "@baseboard_fab2_lib.baseboard_fab2(sch_1):page241_i83:ph(1)" )
			)
			( pin "EU7E2.4"
				( objectStatus "@baseboard_fab2_lib.baseboard_fab2(sch_1):page241_i83:pvin(0)" )
			)
			( pin "EU7E2.5"
				( objectStatus "@baseboard_fab2_lib.baseboard_fab2(sch_1):page241_i83:pvin(1)" )
			)
			( pin "EU7E2.14"
				( objectStatus "@baseboard_fab2_lib.baseboard_fab2(sch_1):page241_i83:pwrgd" )
			)
			( pin "EU7E2.1"
				( objectStatus "@baseboard_fab2_lib.baseboard_fab2(sch_1):page241_i83:rt_clk" )
			)
			( pin "EU7E2.9"
				( objectStatus "@baseboard_fab2_lib.baseboard_fab2(sch_1):page241_i83:ss_tr" )
			)
			( pin "EU7E2.15"
				( objectStatus "@baseboard_fab2_lib.baseboard_fab2(sch_1):page241_i83:thpad" )
			)
			( pin "EU7E2.6"
				( objectStatus "@baseboard_fab2_lib.baseboard_fab2(sch_1):page241_i83:vin" )
			)
			( pin "EU7E2.7"
				( objectStatus "@baseboard_fab2_lib.baseboard_fab2(sch_1):page241_i83:vsense" )
			)
			( pin "R7E15.1"
				( objectStatus "@baseboard_fab2_lib.baseboard_fab2(sch_1):page241_i89:a" )
			)
			( pin "R7E15.2"
				( objectStatus "@baseboard_fab2_lib.baseboard_fab2(sch_1):page241_i89:b" )
			)
			( pin "L8E1.1"
				( objectStatus "@baseboard_fab2_lib.baseboard_fab2(sch_1):page241_i90:ina" )
			)
			( pin "L8E1.2"
				( objectStatus "@baseboard_fab2_lib.baseboard_fab2(sch_1):page241_i90:inb" )
			)
			( pin "R8E33.1"
				( objectStatus "@baseboard_fab2_lib.baseboard_fab2(sch_1):page241_i91:a" )
			)
			( pin "R8E33.2"
				( objectStatus "@baseboard_fab2_lib.baseboard_fab2(sch_1):page241_i91:b" )
			)
			( pin "C5G106.1"
				( objectStatus "@baseboard_fab2_lib.baseboard_fab2(sch_1):page243_i88:a" )
			)
			( pin "C5G106.2"
				( objectStatus "@baseboard_fab2_lib.baseboard_fab2(sch_1):page243_i88:b" )
			)
			( pin "C5G107.1"
				( objectStatus "@baseboard_fab2_lib.baseboard_fab2(sch_1):page243_i87:a" )
			)
			( pin "C5G107.2"
				( objectStatus "@baseboard_fab2_lib.baseboard_fab2(sch_1):page243_i87:b" )
			)
			( pin "C5G108.1"
				( objectStatus "@baseboard_fab2_lib.baseboard_fab2(sch_1):page243_i86:a" )
			)
			( pin "C5G108.2"
				( objectStatus "@baseboard_fab2_lib.baseboard_fab2(sch_1):page243_i86:b" )
			)
			( pin "C5G109.1"
				( objectStatus "@baseboard_fab2_lib.baseboard_fab2(sch_1):page243_i85:a" )
			)
			( pin "C5G109.2"
				( objectStatus "@baseboard_fab2_lib.baseboard_fab2(sch_1):page243_i85:b" )
			)
			( pin "C5G110.1"
				( objectStatus "@baseboard_fab2_lib.baseboard_fab2(sch_1):page243_i84:a" )
			)
			( pin "C5G110.2"
				( objectStatus "@baseboard_fab2_lib.baseboard_fab2(sch_1):page243_i84:b" )
			)
			( pin "C5G21.1"
				( objectStatus "@baseboard_fab2_lib.baseboard_fab2(sch_1):page242_i11:a" )
			)
			( pin "C5G21.2"
				( objectStatus "@baseboard_fab2_lib.baseboard_fab2(sch_1):page242_i11:b" )
			)
			( pin "C5G111.1"
				( objectStatus "@baseboard_fab2_lib.baseboard_fab2(sch_1):page243_i83:a" )
			)
			( pin "C5G111.2"
				( objectStatus "@baseboard_fab2_lib.baseboard_fab2(sch_1):page243_i83:b" )
			)
			( pin "C5G112.1"
				( objectStatus "@baseboard_fab2_lib.baseboard_fab2(sch_1):page243_i82:a" )
			)
			( pin "C5G112.2"
				( objectStatus "@baseboard_fab2_lib.baseboard_fab2(sch_1):page243_i82:b" )
			)
			( pin "C5G113.1"
				( objectStatus "@baseboard_fab2_lib.baseboard_fab2(sch_1):page243_i81:a" )
			)
			( pin "C5G113.2"
				( objectStatus "@baseboard_fab2_lib.baseboard_fab2(sch_1):page243_i81:b" )
			)
			( pin "C5G22.1"
				( objectStatus "@baseboard_fab2_lib.baseboard_fab2(sch_1):page242_i15:a" )
			)
			( pin "C5G22.2"
				( objectStatus "@baseboard_fab2_lib.baseboard_fab2(sch_1):page242_i15:b" )
			)
			( pin "C5G114.1"
				( objectStatus "@baseboard_fab2_lib.baseboard_fab2(sch_1):page243_i80:a" )
			)
			( pin "C5G114.2"
				( objectStatus "@baseboard_fab2_lib.baseboard_fab2(sch_1):page243_i80:b" )
			)
			( pin "C5G97.1"
				( objectStatus "@baseboard_fab2_lib.baseboard_fab2(sch_1):page243_i79:a" )
			)
			( pin "C5G97.2"
				( objectStatus "@baseboard_fab2_lib.baseboard_fab2(sch_1):page243_i79:b" )
			)
			( pin "C5G98.1"
				( objectStatus "@baseboard_fab2_lib.baseboard_fab2(sch_1):page243_i78:a" )
			)
			( pin "C5G98.2"
				( objectStatus "@baseboard_fab2_lib.baseboard_fab2(sch_1):page243_i78:b" )
			)
			( pin "C5G99.1"
				( objectStatus "@baseboard_fab2_lib.baseboard_fab2(sch_1):page243_i77:a" )
			)
			( pin "C5G99.2"
				( objectStatus "@baseboard_fab2_lib.baseboard_fab2(sch_1):page243_i77:b" )
			)
			( pin "C5G100.1"
				( objectStatus "@baseboard_fab2_lib.baseboard_fab2(sch_1):page243_i76:a" )
			)
			( pin "C5G100.2"
				( objectStatus "@baseboard_fab2_lib.baseboard_fab2(sch_1):page243_i76:b" )
			)
			( pin "C5G101.1"
				( objectStatus "@baseboard_fab2_lib.baseboard_fab2(sch_1):page243_i75:a" )
			)
			( pin "C5G101.2"
				( objectStatus "@baseboard_fab2_lib.baseboard_fab2(sch_1):page243_i75:b" )
			)
			( pin "C5G102.1"
				( objectStatus "@baseboard_fab2_lib.baseboard_fab2(sch_1):page243_i74:a" )
			)
			( pin "C5G102.2"
				( objectStatus "@baseboard_fab2_lib.baseboard_fab2(sch_1):page243_i74:b" )
			)
			( pin "C5G105.1"
				( objectStatus "@baseboard_fab2_lib.baseboard_fab2(sch_1):page243_i73:a" )
			)
			( pin "C5G105.2"
				( objectStatus "@baseboard_fab2_lib.baseboard_fab2(sch_1):page243_i73:b" )
			)
			( pin "C5G104.1"
				( objectStatus "@baseboard_fab2_lib.baseboard_fab2(sch_1):page243_i72:a" )
			)
			( pin "C5G104.2"
				( objectStatus "@baseboard_fab2_lib.baseboard_fab2(sch_1):page243_i72:b" )
			)
			( pin "C5G103.1"
				( objectStatus "@baseboard_fab2_lib.baseboard_fab2(sch_1):page243_i71:a" )
			)
			( pin "C5G103.2"
				( objectStatus "@baseboard_fab2_lib.baseboard_fab2(sch_1):page243_i71:b" )
			)
			( pin "C5G88.1"
				( objectStatus "@baseboard_fab2_lib.baseboard_fab2(sch_1):page243_i70:a" )
			)
			( pin "C5G88.2"
				( objectStatus "@baseboard_fab2_lib.baseboard_fab2(sch_1):page243_i70:b" )
			)
			( pin "C5G89.1"
				( objectStatus "@baseboard_fab2_lib.baseboard_fab2(sch_1):page243_i69:a" )
			)
			( pin "C5G89.2"
				( objectStatus "@baseboard_fab2_lib.baseboard_fab2(sch_1):page243_i69:b" )
			)
			( pin "C5G90.1"
				( objectStatus "@baseboard_fab2_lib.baseboard_fab2(sch_1):page243_i68:a" )
			)
			( pin "C5G90.2"
				( objectStatus "@baseboard_fab2_lib.baseboard_fab2(sch_1):page243_i68:b" )
			)
			( pin "C5G91.1"
				( objectStatus "@baseboard_fab2_lib.baseboard_fab2(sch_1):page243_i67:a" )
			)
			( pin "C5G91.2"
				( objectStatus "@baseboard_fab2_lib.baseboard_fab2(sch_1):page243_i67:b" )
			)
			( pin "C5G92.1"
				( objectStatus "@baseboard_fab2_lib.baseboard_fab2(sch_1):page243_i66:a" )
			)
			( pin "C5G92.2"
				( objectStatus "@baseboard_fab2_lib.baseboard_fab2(sch_1):page243_i66:b" )
			)
			( pin "C5G77.1"
				( objectStatus "@baseboard_fab2_lib.baseboard_fab2(sch_1):page242_i37:a" )
			)
			( pin "C5G77.2"
				( objectStatus "@baseboard_fab2_lib.baseboard_fab2(sch_1):page242_i37:b" )
			)
			( pin "C5G93.1"
				( objectStatus "@baseboard_fab2_lib.baseboard_fab2(sch_1):page243_i65:a" )
			)
			( pin "C5G93.2"
				( objectStatus "@baseboard_fab2_lib.baseboard_fab2(sch_1):page243_i65:b" )
			)
			( pin "C5G94.1"
				( objectStatus "@baseboard_fab2_lib.baseboard_fab2(sch_1):page243_i64:a" )
			)
			( pin "C5G94.2"
				( objectStatus "@baseboard_fab2_lib.baseboard_fab2(sch_1):page243_i64:b" )
			)
			( pin "C5G95.1"
				( objectStatus "@baseboard_fab2_lib.baseboard_fab2(sch_1):page243_i63:a" )
			)
			( pin "C5G95.2"
				( objectStatus "@baseboard_fab2_lib.baseboard_fab2(sch_1):page243_i63:b" )
			)
			( pin "C5G78.1"
				( objectStatus "@baseboard_fab2_lib.baseboard_fab2(sch_1):page242_i41:a" )
			)
			( pin "C5G78.2"
				( objectStatus "@baseboard_fab2_lib.baseboard_fab2(sch_1):page242_i41:b" )
			)
			( pin "C5G96.1"
				( objectStatus "@baseboard_fab2_lib.baseboard_fab2(sch_1):page243_i62:a" )
			)
			( pin "C5G96.2"
				( objectStatus "@baseboard_fab2_lib.baseboard_fab2(sch_1):page243_i62:b" )
			)
			( pin "C5G80.1"
				( objectStatus "@baseboard_fab2_lib.baseboard_fab2(sch_1):page243_i61:a" )
			)
			( pin "C5G80.2"
				( objectStatus "@baseboard_fab2_lib.baseboard_fab2(sch_1):page243_i61:b" )
			)
			( pin "C5G81.1"
				( objectStatus "@baseboard_fab2_lib.baseboard_fab2(sch_1):page243_i60:a" )
			)
			( pin "C5G81.2"
				( objectStatus "@baseboard_fab2_lib.baseboard_fab2(sch_1):page243_i60:b" )
			)
			( pin "C5G82.1"
				( objectStatus "@baseboard_fab2_lib.baseboard_fab2(sch_1):page243_i59:a" )
			)
			( pin "C5G82.2"
				( objectStatus "@baseboard_fab2_lib.baseboard_fab2(sch_1):page243_i59:b" )
			)
			( pin "C5G83.1"
				( objectStatus "@baseboard_fab2_lib.baseboard_fab2(sch_1):page243_i58:a" )
			)
			( pin "C5G83.2"
				( objectStatus "@baseboard_fab2_lib.baseboard_fab2(sch_1):page243_i58:b" )
			)
			( pin "C5G84.1"
				( objectStatus "@baseboard_fab2_lib.baseboard_fab2(sch_1):page243_i57:a" )
			)
			( pin "C5G84.2"
				( objectStatus "@baseboard_fab2_lib.baseboard_fab2(sch_1):page243_i57:b" )
			)
			( pin "C5G85.1"
				( objectStatus "@baseboard_fab2_lib.baseboard_fab2(sch_1):page243_i56:a" )
			)
			( pin "C5G85.2"
				( objectStatus "@baseboard_fab2_lib.baseboard_fab2(sch_1):page243_i56:b" )
			)
			( pin "C5G86.1"
				( objectStatus "@baseboard_fab2_lib.baseboard_fab2(sch_1):page243_i55:a" )
			)
			( pin "C5G86.2"
				( objectStatus "@baseboard_fab2_lib.baseboard_fab2(sch_1):page243_i55:b" )
			)
			( pin "C5G87.1"
				( objectStatus "@baseboard_fab2_lib.baseboard_fab2(sch_1):page243_i54:a" )
			)
			( pin "C5G87.2"
				( objectStatus "@baseboard_fab2_lib.baseboard_fab2(sch_1):page243_i54:b" )
			)
			( pin "C5G79.1"
				( objectStatus "@baseboard_fab2_lib.baseboard_fab2(sch_1):page243_i53:a" )
			)
			( pin "C5G79.2"
				( objectStatus "@baseboard_fab2_lib.baseboard_fab2(sch_1):page243_i53:b" )
			)
			( pin "C5G117.1"
				( objectStatus "@baseboard_fab2_lib.baseboard_fab2(sch_1):page243_i12:a" )
			)
			( pin "C5G117.2"
				( objectStatus "@baseboard_fab2_lib.baseboard_fab2(sch_1):page243_i12:b" )
			)
			( pin "C5G118.1"
				( objectStatus "@baseboard_fab2_lib.baseboard_fab2(sch_1):page243_i13:a" )
			)
			( pin "C5G118.2"
				( objectStatus "@baseboard_fab2_lib.baseboard_fab2(sch_1):page243_i13:b" )
			)
			( pin "C5G115.1"
				( objectStatus "@baseboard_fab2_lib.baseboard_fab2(sch_1):page243_i39:a" )
			)
			( pin "C5G115.2"
				( objectStatus "@baseboard_fab2_lib.baseboard_fab2(sch_1):page243_i39:b" )
			)
			( pin "C5G116.1"
				( objectStatus "@baseboard_fab2_lib.baseboard_fab2(sch_1):page243_i43:a" )
			)
			( pin "C5G116.2"
				( objectStatus "@baseboard_fab2_lib.baseboard_fab2(sch_1):page243_i43:b" )
			)
			( pin "C5G41.1"
				( objectStatus "@baseboard_fab2_lib.baseboard_fab2(sch_1):page242_i53:a" )
			)
			( pin "C5G41.2"
				( objectStatus "@baseboard_fab2_lib.baseboard_fab2(sch_1):page242_i53:b" )
			)
			( pin "C5G42.1"
				( objectStatus "@baseboard_fab2_lib.baseboard_fab2(sch_1):page242_i54:a" )
			)
			( pin "C5G42.2"
				( objectStatus "@baseboard_fab2_lib.baseboard_fab2(sch_1):page242_i54:b" )
			)
			( pin "C5G44.1"
				( objectStatus "@baseboard_fab2_lib.baseboard_fab2(sch_1):page242_i55:a" )
			)
			( pin "C5G44.2"
				( objectStatus "@baseboard_fab2_lib.baseboard_fab2(sch_1):page242_i55:b" )
			)
			( pin "C5G43.1"
				( objectStatus "@baseboard_fab2_lib.baseboard_fab2(sch_1):page242_i56:a" )
			)
			( pin "C5G43.2"
				( objectStatus "@baseboard_fab2_lib.baseboard_fab2(sch_1):page242_i56:b" )
			)
			( pin "C5G48.1"
				( objectStatus "@baseboard_fab2_lib.baseboard_fab2(sch_1):page242_i57:a" )
			)
			( pin "C5G48.2"
				( objectStatus "@baseboard_fab2_lib.baseboard_fab2(sch_1):page242_i57:b" )
			)
			( pin "C5G47.1"
				( objectStatus "@baseboard_fab2_lib.baseboard_fab2(sch_1):page242_i58:a" )
			)
			( pin "C5G47.2"
				( objectStatus "@baseboard_fab2_lib.baseboard_fab2(sch_1):page242_i58:b" )
			)
			( pin "C5G46.1"
				( objectStatus "@baseboard_fab2_lib.baseboard_fab2(sch_1):page242_i59:a" )
			)
			( pin "C5G46.2"
				( objectStatus "@baseboard_fab2_lib.baseboard_fab2(sch_1):page242_i59:b" )
			)
			( pin "C5G45.1"
				( objectStatus "@baseboard_fab2_lib.baseboard_fab2(sch_1):page242_i60:a" )
			)
			( pin "C5G45.2"
				( objectStatus "@baseboard_fab2_lib.baseboard_fab2(sch_1):page242_i60:b" )
			)
			( pin "C5G49.1"
				( objectStatus "@baseboard_fab2_lib.baseboard_fab2(sch_1):page242_i61:a" )
			)
			( pin "C5G49.2"
				( objectStatus "@baseboard_fab2_lib.baseboard_fab2(sch_1):page242_i61:b" )
			)
			( pin "C5G54.1"
				( objectStatus "@baseboard_fab2_lib.baseboard_fab2(sch_1):page242_i62:a" )
			)
			( pin "C5G54.2"
				( objectStatus "@baseboard_fab2_lib.baseboard_fab2(sch_1):page242_i62:b" )
			)
			( pin "C5G58.1"
				( objectStatus "@baseboard_fab2_lib.baseboard_fab2(sch_1):page242_i63:a" )
			)
			( pin "C5G58.2"
				( objectStatus "@baseboard_fab2_lib.baseboard_fab2(sch_1):page242_i63:b" )
			)
			( pin "C5G57.1"
				( objectStatus "@baseboard_fab2_lib.baseboard_fab2(sch_1):page242_i64:a" )
			)
			( pin "C5G57.2"
				( objectStatus "@baseboard_fab2_lib.baseboard_fab2(sch_1):page242_i64:b" )
			)
			( pin "C5G56.1"
				( objectStatus "@baseboard_fab2_lib.baseboard_fab2(sch_1):page242_i65:a" )
			)
			( pin "C5G56.2"
				( objectStatus "@baseboard_fab2_lib.baseboard_fab2(sch_1):page242_i65:b" )
			)
			( pin "C5G55.1"
				( objectStatus "@baseboard_fab2_lib.baseboard_fab2(sch_1):page242_i66:a" )
			)
			( pin "C5G55.2"
				( objectStatus "@baseboard_fab2_lib.baseboard_fab2(sch_1):page242_i66:b" )
			)
			( pin "C5G53.1"
				( objectStatus "@baseboard_fab2_lib.baseboard_fab2(sch_1):page242_i67:a" )
			)
			( pin "C5G53.2"
				( objectStatus "@baseboard_fab2_lib.baseboard_fab2(sch_1):page242_i67:b" )
			)
			( pin "C5G52.1"
				( objectStatus "@baseboard_fab2_lib.baseboard_fab2(sch_1):page242_i68:a" )
			)
			( pin "C5G52.2"
				( objectStatus "@baseboard_fab2_lib.baseboard_fab2(sch_1):page242_i68:b" )
			)
			( pin "C5G51.1"
				( objectStatus "@baseboard_fab2_lib.baseboard_fab2(sch_1):page242_i69:a" )
			)
			( pin "C5G51.2"
				( objectStatus "@baseboard_fab2_lib.baseboard_fab2(sch_1):page242_i69:b" )
			)
			( pin "C5G50.1"
				( objectStatus "@baseboard_fab2_lib.baseboard_fab2(sch_1):page242_i70:a" )
			)
			( pin "C5G50.2"
				( objectStatus "@baseboard_fab2_lib.baseboard_fab2(sch_1):page242_i70:b" )
			)
			( pin "C5G67.1"
				( objectStatus "@baseboard_fab2_lib.baseboard_fab2(sch_1):page242_i71:a" )
			)
			( pin "C5G67.2"
				( objectStatus "@baseboard_fab2_lib.baseboard_fab2(sch_1):page242_i71:b" )
			)
			( pin "C5G66.1"
				( objectStatus "@baseboard_fab2_lib.baseboard_fab2(sch_1):page242_i72:a" )
			)
			( pin "C5G66.2"
				( objectStatus "@baseboard_fab2_lib.baseboard_fab2(sch_1):page242_i72:b" )
			)
			( pin "C5G65.1"
				( objectStatus "@baseboard_fab2_lib.baseboard_fab2(sch_1):page242_i73:a" )
			)
			( pin "C5G65.2"
				( objectStatus "@baseboard_fab2_lib.baseboard_fab2(sch_1):page242_i73:b" )
			)
			( pin "C5G64.1"
				( objectStatus "@baseboard_fab2_lib.baseboard_fab2(sch_1):page242_i74:a" )
			)
			( pin "C5G64.2"
				( objectStatus "@baseboard_fab2_lib.baseboard_fab2(sch_1):page242_i74:b" )
			)
			( pin "C5G63.1"
				( objectStatus "@baseboard_fab2_lib.baseboard_fab2(sch_1):page242_i75:a" )
			)
			( pin "C5G63.2"
				( objectStatus "@baseboard_fab2_lib.baseboard_fab2(sch_1):page242_i75:b" )
			)
			( pin "C5G62.1"
				( objectStatus "@baseboard_fab2_lib.baseboard_fab2(sch_1):page242_i76:a" )
			)
			( pin "C5G62.2"
				( objectStatus "@baseboard_fab2_lib.baseboard_fab2(sch_1):page242_i76:b" )
			)
			( pin "C5G61.1"
				( objectStatus "@baseboard_fab2_lib.baseboard_fab2(sch_1):page242_i77:a" )
			)
			( pin "C5G61.2"
				( objectStatus "@baseboard_fab2_lib.baseboard_fab2(sch_1):page242_i77:b" )
			)
			( pin "C5G60.1"
				( objectStatus "@baseboard_fab2_lib.baseboard_fab2(sch_1):page242_i78:a" )
			)
			( pin "C5G60.2"
				( objectStatus "@baseboard_fab2_lib.baseboard_fab2(sch_1):page242_i78:b" )
			)
			( pin "C5G59.1"
				( objectStatus "@baseboard_fab2_lib.baseboard_fab2(sch_1):page242_i79:a" )
			)
			( pin "C5G59.2"
				( objectStatus "@baseboard_fab2_lib.baseboard_fab2(sch_1):page242_i79:b" )
			)
			( pin "C5G76.1"
				( objectStatus "@baseboard_fab2_lib.baseboard_fab2(sch_1):page242_i80:a" )
			)
			( pin "C5G76.2"
				( objectStatus "@baseboard_fab2_lib.baseboard_fab2(sch_1):page242_i80:b" )
			)
			( pin "C5G75.1"
				( objectStatus "@baseboard_fab2_lib.baseboard_fab2(sch_1):page242_i81:a" )
			)
			( pin "C5G75.2"
				( objectStatus "@baseboard_fab2_lib.baseboard_fab2(sch_1):page242_i81:b" )
			)
			( pin "C5G74.1"
				( objectStatus "@baseboard_fab2_lib.baseboard_fab2(sch_1):page242_i82:a" )
			)
			( pin "C5G74.2"
				( objectStatus "@baseboard_fab2_lib.baseboard_fab2(sch_1):page242_i82:b" )
			)
			( pin "C5G73.1"
				( objectStatus "@baseboard_fab2_lib.baseboard_fab2(sch_1):page242_i83:a" )
			)
			( pin "C5G73.2"
				( objectStatus "@baseboard_fab2_lib.baseboard_fab2(sch_1):page242_i83:b" )
			)
			( pin "C5G72.1"
				( objectStatus "@baseboard_fab2_lib.baseboard_fab2(sch_1):page242_i84:a" )
			)
			( pin "C5G72.2"
				( objectStatus "@baseboard_fab2_lib.baseboard_fab2(sch_1):page242_i84:b" )
			)
			( pin "C5G71.1"
				( objectStatus "@baseboard_fab2_lib.baseboard_fab2(sch_1):page242_i85:a" )
			)
			( pin "C5G71.2"
				( objectStatus "@baseboard_fab2_lib.baseboard_fab2(sch_1):page242_i85:b" )
			)
			( pin "C5G70.1"
				( objectStatus "@baseboard_fab2_lib.baseboard_fab2(sch_1):page242_i86:a" )
			)
			( pin "C5G70.2"
				( objectStatus "@baseboard_fab2_lib.baseboard_fab2(sch_1):page242_i86:b" )
			)
			( pin "C5G69.1"
				( objectStatus "@baseboard_fab2_lib.baseboard_fab2(sch_1):page242_i87:a" )
			)
			( pin "C5G69.2"
				( objectStatus "@baseboard_fab2_lib.baseboard_fab2(sch_1):page242_i87:b" )
			)
			( pin "C5G68.1"
				( objectStatus "@baseboard_fab2_lib.baseboard_fab2(sch_1):page242_i88:a" )
			)
			( pin "C5G68.2"
				( objectStatus "@baseboard_fab2_lib.baseboard_fab2(sch_1):page242_i88:b" )
			)
			( pin "RT3.1"
				( objectStatus "@baseboard_fab2_lib.baseboard_fab2(sch_1):page202_i89:a" )
			)
			( pin "RT3.2"
				( objectStatus "@baseboard_fab2_lib.baseboard_fab2(sch_1):page202_i89:b" )
			)
			( pin "CT1.1"
				( objectStatus "@baseboard_fab2_lib.baseboard_fab2(sch_1):page202_i70:a" )
			)
			( pin "CT1.2"
				( objectStatus "@baseboard_fab2_lib.baseboard_fab2(sch_1):page202_i70:b" )
			)
			( pin "RT2.1"
				( objectStatus "@baseboard_fab2_lib.baseboard_fab2(sch_1):page202_i75:\1\" )
			)
			( pin "RT2.2"
				( objectStatus "@baseboard_fab2_lib.baseboard_fab2(sch_1):page202_i75:\2\" )
			)
			( pin "CT3.1"
				( objectStatus "@baseboard_fab2_lib.baseboard_fab2(sch_1):page202_i76:\1\" )
			)
			( pin "CT3.2"
				( objectStatus "@baseboard_fab2_lib.baseboard_fab2(sch_1):page202_i76:\2\" )
			)
			( pin "CT2.1"
				( objectStatus "@baseboard_fab2_lib.baseboard_fab2(sch_1):page202_i78:a" )
			)
			( pin "CT2.2"
				( objectStatus "@baseboard_fab2_lib.baseboard_fab2(sch_1):page202_i78:b" )
			)
			( pin "CT6.1"
				( objectStatus "@baseboard_fab2_lib.baseboard_fab2(sch_1):page202_i81:a" )
			)
			( pin "CT6.2"
				( objectStatus "@baseboard_fab2_lib.baseboard_fab2(sch_1):page202_i81:b" )
			)
			( pin "CT5.1"
				( objectStatus "@baseboard_fab2_lib.baseboard_fab2(sch_1):page202_i82:\1\" )
			)
			( pin "CT5.2"
				( objectStatus "@baseboard_fab2_lib.baseboard_fab2(sch_1):page202_i82:\2\" )
			)
			( pin "RT4.1"
				( objectStatus "@baseboard_fab2_lib.baseboard_fab2(sch_1):page202_i83:\1\" )
			)
			( pin "RT4.2"
				( objectStatus "@baseboard_fab2_lib.baseboard_fab2(sch_1):page202_i83:\2\" )
			)
			( pin "CT7.1"
				( objectStatus "@baseboard_fab2_lib.baseboard_fab2(sch_1):page227_i109:a" )
			)
			( pin "CT7.2"
				( objectStatus "@baseboard_fab2_lib.baseboard_fab2(sch_1):page227_i109:b" )
			)
			( pin "CT9.1"
				( objectStatus "@baseboard_fab2_lib.baseboard_fab2(sch_1):page227_i111:\1\" )
			)
			( pin "CT9.2"
				( objectStatus "@baseboard_fab2_lib.baseboard_fab2(sch_1):page227_i111:\2\" )
			)
			( pin "CT8.1"
				( objectStatus "@baseboard_fab2_lib.baseboard_fab2(sch_1):page227_i114:a" )
			)
			( pin "CT8.2"
				( objectStatus "@baseboard_fab2_lib.baseboard_fab2(sch_1):page227_i114:b" )
			)
			( pin "CT11.1"
				( objectStatus "@baseboard_fab2_lib.baseboard_fab2(sch_1):page227_i116:\1\" )
			)
			( pin "CT11.2"
				( objectStatus "@baseboard_fab2_lib.baseboard_fab2(sch_1):page227_i116:\2\" )
			)
			( pin "RT6.1"
				( objectStatus "@baseboard_fab2_lib.baseboard_fab2(sch_1):page227_i125:\1\" )
			)
			( pin "RT6.2"
				( objectStatus "@baseboard_fab2_lib.baseboard_fab2(sch_1):page227_i125:\2\" )
			)
			( pin "CT10.1"
				( objectStatus "@baseboard_fab2_lib.baseboard_fab2(sch_1):page227_i119:a" )
			)
			( pin "CT10.2"
				( objectStatus "@baseboard_fab2_lib.baseboard_fab2(sch_1):page227_i119:b" )
			)
			( pin "CT12.1"
				( objectStatus "@baseboard_fab2_lib.baseboard_fab2(sch_1):page227_i122:a" )
			)
			( pin "CT12.2"
				( objectStatus "@baseboard_fab2_lib.baseboard_fab2(sch_1):page227_i122:b" )
			)
			( pin "RT11.1"
				( objectStatus "@baseboard_fab2_lib.baseboard_fab2(sch_1):page208_i96:a" )
			)
			( pin "RT11.2"
				( objectStatus "@baseboard_fab2_lib.baseboard_fab2(sch_1):page208_i96:b" )
			)
			( pin "CT13.1"
				( objectStatus "@baseboard_fab2_lib.baseboard_fab2(sch_1):page209_i62:a" )
			)
			( pin "CT13.2"
				( objectStatus "@baseboard_fab2_lib.baseboard_fab2(sch_1):page209_i62:b" )
			)
			( pin "CT14.1"
				( objectStatus "@baseboard_fab2_lib.baseboard_fab2(sch_1):page209_i64:\1\" )
			)
			( pin "CT14.2"
				( objectStatus "@baseboard_fab2_lib.baseboard_fab2(sch_1):page209_i64:\2\" )
			)
			( pin "RT10.1"
				( objectStatus "@baseboard_fab2_lib.baseboard_fab2(sch_1):page209_i66:\1\" )
			)
			( pin "RT10.2"
				( objectStatus "@baseboard_fab2_lib.baseboard_fab2(sch_1):page209_i66:\2\" )
			)
			( pin "CT15.1"
				( objectStatus "@baseboard_fab2_lib.baseboard_fab2(sch_1):page209_i67:a" )
			)
			( pin "CT15.2"
				( objectStatus "@baseboard_fab2_lib.baseboard_fab2(sch_1):page209_i67:b" )
			)
			( pin "CT16.1"
				( objectStatus "@baseboard_fab2_lib.baseboard_fab2(sch_1):page208_i80:a" )
			)
			( pin "CT16.2"
				( objectStatus "@baseboard_fab2_lib.baseboard_fab2(sch_1):page208_i80:b" )
			)
			( pin "CTI7.1"
				( objectStatus "@baseboard_fab2_lib.baseboard_fab2(sch_1):page208_i82:a" )
			)
			( pin "CTI7.2"
				( objectStatus "@baseboard_fab2_lib.baseboard_fab2(sch_1):page208_i82:b" )
			)
			( pin "CT18.1"
				( objectStatus "@baseboard_fab2_lib.baseboard_fab2(sch_1):page208_i84:\1\" )
			)
			( pin "CT18.2"
				( objectStatus "@baseboard_fab2_lib.baseboard_fab2(sch_1):page208_i84:\2\" )
			)
			( pin "RT12.1"
				( objectStatus "@baseboard_fab2_lib.baseboard_fab2(sch_1):page208_i86:\1\" )
			)
			( pin "RT12.2"
				( objectStatus "@baseboard_fab2_lib.baseboard_fab2(sch_1):page208_i86:\2\" )
			)
			( pin "CT21.1"
				( objectStatus "@baseboard_fab2_lib.baseboard_fab2(sch_1):page208_i87:a" )
			)
			( pin "CT21.2"
				( objectStatus "@baseboard_fab2_lib.baseboard_fab2(sch_1):page208_i87:b" )
			)
			( pin "CT19.1"
				( objectStatus "@baseboard_fab2_lib.baseboard_fab2(sch_1):page208_i90:a" )
			)
			( pin "CT19.2"
				( objectStatus "@baseboard_fab2_lib.baseboard_fab2(sch_1):page208_i90:b" )
			)
			( pin "CT20.1"
				( objectStatus "@baseboard_fab2_lib.baseboard_fab2(sch_1):page208_i92:\1\" )
			)
			( pin "CT20.2"
				( objectStatus "@baseboard_fab2_lib.baseboard_fab2(sch_1):page208_i92:\2\" )
			)
			( pin "RT13.1"
				( objectStatus "@baseboard_fab2_lib.baseboard_fab2(sch_1):page208_i94:\1\" )
			)
			( pin "RT13.2"
				( objectStatus "@baseboard_fab2_lib.baseboard_fab2(sch_1):page208_i94:\2\" )
			)
			( pin "CT24.1"
				( objectStatus "@baseboard_fab2_lib.baseboard_fab2(sch_1):page207_i71:a" )
			)
			( pin "CT24.2"
				( objectStatus "@baseboard_fab2_lib.baseboard_fab2(sch_1):page207_i71:b" )
			)
			( pin "CT22.1"
				( objectStatus "@baseboard_fab2_lib.baseboard_fab2(sch_1):page207_i74:a" )
			)
			( pin "CT22.2"
				( objectStatus "@baseboard_fab2_lib.baseboard_fab2(sch_1):page207_i74:b" )
			)
			( pin "RT16.1"
				( objectStatus "@baseboard_fab2_lib.baseboard_fab2(sch_1):page207_i76:\1\" )
			)
			( pin "RT16.2"
				( objectStatus "@baseboard_fab2_lib.baseboard_fab2(sch_1):page207_i76:\2\" )
			)
			( pin "CT23.1"
				( objectStatus "@baseboard_fab2_lib.baseboard_fab2(sch_1):page207_i77:\1\" )
			)
			( pin "CT23.2"
				( objectStatus "@baseboard_fab2_lib.baseboard_fab2(sch_1):page207_i77:\2\" )
			)
			( pin "CT30.1"
				( objectStatus "@baseboard_fab2_lib.baseboard_fab2(sch_1):page224_i117:a" )
			)
			( pin "CT30.2"
				( objectStatus "@baseboard_fab2_lib.baseboard_fab2(sch_1):page224_i117:b" )
			)
			( pin "RT20.1"
				( objectStatus "@baseboard_fab2_lib.baseboard_fab2(sch_1):page224_i119:\1\" )
			)
			( pin "RT20.2"
				( objectStatus "@baseboard_fab2_lib.baseboard_fab2(sch_1):page224_i119:\2\" )
			)
			( pin "CT29.1"
				( objectStatus "@baseboard_fab2_lib.baseboard_fab2(sch_1):page224_i121:\1\" )
			)
			( pin "CT29.2"
				( objectStatus "@baseboard_fab2_lib.baseboard_fab2(sch_1):page224_i121:\2\" )
			)
			( pin "CT28.1"
				( objectStatus "@baseboard_fab2_lib.baseboard_fab2(sch_1):page224_i122:a" )
			)
			( pin "CT28.2"
				( objectStatus "@baseboard_fab2_lib.baseboard_fab2(sch_1):page224_i122:b" )
			)
			( pin "CT31.1"
				( objectStatus "@baseboard_fab2_lib.baseboard_fab2(sch_1):page224_i124:a" )
			)
			( pin "CT31.2"
				( objectStatus "@baseboard_fab2_lib.baseboard_fab2(sch_1):page224_i124:b" )
			)
			( pin "CT33.1"
				( objectStatus "@baseboard_fab2_lib.baseboard_fab2(sch_1):page224_i127:\1\" )
			)
			( pin "CT33.2"
				( objectStatus "@baseboard_fab2_lib.baseboard_fab2(sch_1):page224_i127:\2\" )
			)
			( pin "RT22.1"
				( objectStatus "@baseboard_fab2_lib.baseboard_fab2(sch_1):page224_i129:\1\" )
			)
			( pin "RT22.2"
				( objectStatus "@baseboard_fab2_lib.baseboard_fab2(sch_1):page224_i129:\2\" )
			)
			( pin "CT32.1"
				( objectStatus "@baseboard_fab2_lib.baseboard_fab2(sch_1):page224_i130:a" )
			)
			( pin "CT32.2"
				( objectStatus "@baseboard_fab2_lib.baseboard_fab2(sch_1):page224_i130:b" )
			)
			( pin "CT36.1"
				( objectStatus "@baseboard_fab2_lib.baseboard_fab2(sch_1):page204_i85:a" )
			)
			( pin "CT36.2"
				( objectStatus "@baseboard_fab2_lib.baseboard_fab2(sch_1):page204_i85:b" )
			)
			( pin "RT25.1"
				( objectStatus "@baseboard_fab2_lib.baseboard_fab2(sch_1):page203_i110:a" )
			)
			( pin "RT25.2"
				( objectStatus "@baseboard_fab2_lib.baseboard_fab2(sch_1):page203_i110:b" )
			)
			( pin "CT34.1"
				( objectStatus "@baseboard_fab2_lib.baseboard_fab2(sch_1):page204_i88:a" )
			)
			( pin "CT34.2"
				( objectStatus "@baseboard_fab2_lib.baseboard_fab2(sch_1):page204_i88:b" )
			)
			( pin "CT35.1"
				( objectStatus "@baseboard_fab2_lib.baseboard_fab2(sch_1):page204_i90:\1\" )
			)
			( pin "CT35.2"
				( objectStatus "@baseboard_fab2_lib.baseboard_fab2(sch_1):page204_i90:\2\" )
			)
			( pin "RT24.1"
				( objectStatus "@baseboard_fab2_lib.baseboard_fab2(sch_1):page204_i91:\1\" )
			)
			( pin "RT24.2"
				( objectStatus "@baseboard_fab2_lib.baseboard_fab2(sch_1):page204_i91:\2\" )
			)
			( pin "CT40.1"
				( objectStatus "@baseboard_fab2_lib.baseboard_fab2(sch_1):page203_i93:a" )
			)
			( pin "CT40.2"
				( objectStatus "@baseboard_fab2_lib.baseboard_fab2(sch_1):page203_i93:b" )
			)
			( pin "RT31.1"
				( objectStatus "@baseboard_fab2_lib.baseboard_fab2(sch_1):page219_i130:a" )
			)
			( pin "RT31.2"
				( objectStatus "@baseboard_fab2_lib.baseboard_fab2(sch_1):page219_i130:b" )
			)
			( pin "CT39.1"
				( objectStatus "@baseboard_fab2_lib.baseboard_fab2(sch_1):page203_i96:a" )
			)
			( pin "CT39.2"
				( objectStatus "@baseboard_fab2_lib.baseboard_fab2(sch_1):page203_i96:b" )
			)
			( pin "RT30.1"
				( objectStatus "@baseboard_fab2_lib.baseboard_fab2(sch_1):page219_i129:a" )
			)
			( pin "RT30.2"
				( objectStatus "@baseboard_fab2_lib.baseboard_fab2(sch_1):page219_i129:b" )
			)
			( pin "CT37.1"
				( objectStatus "@baseboard_fab2_lib.baseboard_fab2(sch_1):page203_i99:a" )
			)
			( pin "CT37.2"
				( objectStatus "@baseboard_fab2_lib.baseboard_fab2(sch_1):page203_i99:b" )
			)
			( pin "CT38.1"
				( objectStatus "@baseboard_fab2_lib.baseboard_fab2(sch_1):page203_i101:\1\" )
			)
			( pin "CT38.2"
				( objectStatus "@baseboard_fab2_lib.baseboard_fab2(sch_1):page203_i101:\2\" )
			)
			( pin "RT26.1"
				( objectStatus "@baseboard_fab2_lib.baseboard_fab2(sch_1):page203_i102:\1\" )
			)
			( pin "RT26.2"
				( objectStatus "@baseboard_fab2_lib.baseboard_fab2(sch_1):page203_i102:\2\" )
			)
			( pin "RT27.1"
				( objectStatus "@baseboard_fab2_lib.baseboard_fab2(sch_1):page203_i105:\1\" )
			)
			( pin "RT27.2"
				( objectStatus "@baseboard_fab2_lib.baseboard_fab2(sch_1):page203_i105:\2\" )
			)
			( pin "CT41.1"
				( objectStatus "@baseboard_fab2_lib.baseboard_fab2(sch_1):page203_i106:\1\" )
			)
			( pin "CT41.2"
				( objectStatus "@baseboard_fab2_lib.baseboard_fab2(sch_1):page203_i106:\2\" )
			)
			( pin "CT42.1"
				( objectStatus "@baseboard_fab2_lib.baseboard_fab2(sch_1):page203_i108:a" )
			)
			( pin "CT42.2"
				( objectStatus "@baseboard_fab2_lib.baseboard_fab2(sch_1):page203_i108:b" )
			)
			( pin "CT46.1"
				( objectStatus "@baseboard_fab2_lib.baseboard_fab2(sch_1):page219_i113:a" )
			)
			( pin "CT46.2"
				( objectStatus "@baseboard_fab2_lib.baseboard_fab2(sch_1):page219_i113:b" )
			)
			( pin "RT36.1"
				( objectStatus "@baseboard_fab2_lib.baseboard_fab2(sch_1):page216_i127:a" )
			)
			( pin "RT36.2"
				( objectStatus "@baseboard_fab2_lib.baseboard_fab2(sch_1):page216_i127:b" )
			)
			( pin "CT45.1"
				( objectStatus "@baseboard_fab2_lib.baseboard_fab2(sch_1):page219_i116:a" )
			)
			( pin "CT45.2"
				( objectStatus "@baseboard_fab2_lib.baseboard_fab2(sch_1):page219_i116:b" )
			)
			( pin "RT33.1"
				( objectStatus "@baseboard_fab2_lib.baseboard_fab2(sch_1):page216_i126:a" )
			)
			( pin "RT33.2"
				( objectStatus "@baseboard_fab2_lib.baseboard_fab2(sch_1):page216_i126:b" )
			)
			( pin "CT48.1"
				( objectStatus "@baseboard_fab2_lib.baseboard_fab2(sch_1):page219_i119:a" )
			)
			( pin "CT48.2"
				( objectStatus "@baseboard_fab2_lib.baseboard_fab2(sch_1):page219_i119:b" )
			)
			( pin "CT47.1"
				( objectStatus "@baseboard_fab2_lib.baseboard_fab2(sch_1):page219_i121:\1\" )
			)
			( pin "CT47.2"
				( objectStatus "@baseboard_fab2_lib.baseboard_fab2(sch_1):page219_i121:\2\" )
			)
			( pin "RT32.1"
				( objectStatus "@baseboard_fab2_lib.baseboard_fab2(sch_1):page219_i123:\1\" )
			)
			( pin "RT32.2"
				( objectStatus "@baseboard_fab2_lib.baseboard_fab2(sch_1):page219_i123:\2\" )
			)
			( pin "CT43.1"
				( objectStatus "@baseboard_fab2_lib.baseboard_fab2(sch_1):page219_i124:a" )
			)
			( pin "CT43.2"
				( objectStatus "@baseboard_fab2_lib.baseboard_fab2(sch_1):page219_i124:b" )
			)
			( pin "RT29.1"
				( objectStatus "@baseboard_fab2_lib.baseboard_fab2(sch_1):page219_i126:\1\" )
			)
			( pin "RT29.2"
				( objectStatus "@baseboard_fab2_lib.baseboard_fab2(sch_1):page219_i126:\2\" )
			)
			( pin "CT44.1"
				( objectStatus "@baseboard_fab2_lib.baseboard_fab2(sch_1):page219_i127:\1\" )
			)
			( pin "CT44.2"
				( objectStatus "@baseboard_fab2_lib.baseboard_fab2(sch_1):page219_i127:\2\" )
			)
			( pin "CT51.1"
				( objectStatus "@baseboard_fab2_lib.baseboard_fab2(sch_1):page216_i108:a" )
			)
			( pin "CT51.2"
				( objectStatus "@baseboard_fab2_lib.baseboard_fab2(sch_1):page216_i108:b" )
			)
			( pin "C7G38.1"
				( objectStatus "@baseboard_fab2_lib.baseboard_fab2(sch_1):page216_i128:a" )
			)
			( pin "C7G38.2"
				( objectStatus "@baseboard_fab2_lib.baseboard_fab2(sch_1):page216_i128:b" )
			)
			( pin "CT52.1"
				( objectStatus "@baseboard_fab2_lib.baseboard_fab2(sch_1):page216_i111:a" )
			)
			( pin "CT52.2"
				( objectStatus "@baseboard_fab2_lib.baseboard_fab2(sch_1):page216_i111:b" )
			)
			( pin "RT37.1"
				( objectStatus "@baseboard_fab2_lib.baseboard_fab2(sch_1):page210_i62:a" )
			)
			( pin "RT37.2"
				( objectStatus "@baseboard_fab2_lib.baseboard_fab2(sch_1):page210_i62:b" )
			)
			( pin "RT34.1"
				( objectStatus "@baseboard_fab2_lib.baseboard_fab2(sch_1):page216_i114:\1\" )
			)
			( pin "RT34.2"
				( objectStatus "@baseboard_fab2_lib.baseboard_fab2(sch_1):page216_i114:\2\" )
			)
			( pin "CT49.1"
				( objectStatus "@baseboard_fab2_lib.baseboard_fab2(sch_1):page216_i118:a" )
			)
			( pin "CT49.2"
				( objectStatus "@baseboard_fab2_lib.baseboard_fab2(sch_1):page216_i118:b" )
			)
			( pin "CT53.1"
				( objectStatus "@baseboard_fab2_lib.baseboard_fab2(sch_1):page216_i119:\1\" )
			)
			( pin "CT53.2"
				( objectStatus "@baseboard_fab2_lib.baseboard_fab2(sch_1):page216_i119:\2\" )
			)
			( pin "CT54.1"
				( objectStatus "@baseboard_fab2_lib.baseboard_fab2(sch_1):page216_i121:a" )
			)
			( pin "CT54.2"
				( objectStatus "@baseboard_fab2_lib.baseboard_fab2(sch_1):page216_i121:b" )
			)
			( pin "RT35.1"
				( objectStatus "@baseboard_fab2_lib.baseboard_fab2(sch_1):page216_i123:\1\" )
			)
			( pin "RT35.2"
				( objectStatus "@baseboard_fab2_lib.baseboard_fab2(sch_1):page216_i123:\2\" )
			)
			( pin "CT50.1"
				( objectStatus "@baseboard_fab2_lib.baseboard_fab2(sch_1):page216_i124:\1\" )
			)
			( pin "CT50.2"
				( objectStatus "@baseboard_fab2_lib.baseboard_fab2(sch_1):page216_i124:\2\" )
			)
			( pin "L7G1.1"
				( objectStatus "@baseboard_fab2_lib.baseboard_fab2(sch_1):page216_i125:ina" )
			)
			( pin "L7G1.2"
				( objectStatus "@baseboard_fab2_lib.baseboard_fab2(sch_1):page216_i125:inb" )
			)
			( pin "RT40.1"
				( objectStatus "@baseboard_fab2_lib.baseboard_fab2(sch_1):page205_i72:a" )
			)
			( pin "RT40.2"
				( objectStatus "@baseboard_fab2_lib.baseboard_fab2(sch_1):page205_i72:b" )
			)
			( pin "CT56.1"
				( objectStatus "@baseboard_fab2_lib.baseboard_fab2(sch_1):page210_i57:\1\" )
			)
			( pin "CT56.2"
				( objectStatus "@baseboard_fab2_lib.baseboard_fab2(sch_1):page210_i57:\2\" )
			)
			( pin "RT38.1"
				( objectStatus "@baseboard_fab2_lib.baseboard_fab2(sch_1):page210_i59:\1\" )
			)
			( pin "RT38.2"
				( objectStatus "@baseboard_fab2_lib.baseboard_fab2(sch_1):page210_i59:\2\" )
			)
			( pin "CT55.1"
				( objectStatus "@baseboard_fab2_lib.baseboard_fab2(sch_1):page210_i60:a" )
			)
			( pin "CT55.2"
				( objectStatus "@baseboard_fab2_lib.baseboard_fab2(sch_1):page210_i60:b" )
			)
			( pin "CT59.1"
				( objectStatus "@baseboard_fab2_lib.baseboard_fab2(sch_1):page205_i64:\1\" )
			)
			( pin "CT59.2"
				( objectStatus "@baseboard_fab2_lib.baseboard_fab2(sch_1):page205_i64:\2\" )
			)
			( pin "CT58.1"
				( objectStatus "@baseboard_fab2_lib.baseboard_fab2(sch_1):page205_i65:a" )
			)
			( pin "CT58.2"
				( objectStatus "@baseboard_fab2_lib.baseboard_fab2(sch_1):page205_i65:b" )
			)
			( pin "RT39.1"
				( objectStatus "@baseboard_fab2_lib.baseboard_fab2(sch_1):page205_i68:\1\" )
			)
			( pin "RT39.2"
				( objectStatus "@baseboard_fab2_lib.baseboard_fab2(sch_1):page205_i68:\2\" )
			)
			( pin "CT60.1"
				( objectStatus "@baseboard_fab2_lib.baseboard_fab2(sch_1):page205_i69:a" )
			)
			( pin "CT60.2"
				( objectStatus "@baseboard_fab2_lib.baseboard_fab2(sch_1):page205_i69:b" )
			)
			( pin "RT41.1"
				( objectStatus "@baseboard_fab2_lib.baseboard_fab2(sch_1):page214_i139:a" )
			)
			( pin "RT41.2"
				( objectStatus "@baseboard_fab2_lib.baseboard_fab2(sch_1):page214_i139:b" )
			)
			( pin "CT62.1"
				( objectStatus "@baseboard_fab2_lib.baseboard_fab2(sch_1):page214_i131:\1\" )
			)
			( pin "CT62.2"
				( objectStatus "@baseboard_fab2_lib.baseboard_fab2(sch_1):page214_i131:\2\" )
			)
			( pin "RT42.1"
				( objectStatus "@baseboard_fab2_lib.baseboard_fab2(sch_1):page214_i132:\1\" )
			)
			( pin "RT42.2"
				( objectStatus "@baseboard_fab2_lib.baseboard_fab2(sch_1):page214_i132:\2\" )
			)
			( pin "CT61.1"
				( objectStatus "@baseboard_fab2_lib.baseboard_fab2(sch_1):page214_i134:a" )
			)
			( pin "CT61.2"
				( objectStatus "@baseboard_fab2_lib.baseboard_fab2(sch_1):page214_i134:b" )
			)
			( pin "CT63.1"
				( objectStatus "@baseboard_fab2_lib.baseboard_fab2(sch_1):page214_i137:a" )
			)
			( pin "CT63.2"
				( objectStatus "@baseboard_fab2_lib.baseboard_fab2(sch_1):page214_i137:b" )
			)
			( pin "RT44.1"
				( objectStatus "@baseboard_fab2_lib.baseboard_fab2(sch_1):page236_i141:a" )
			)
			( pin "RT44.2"
				( objectStatus "@baseboard_fab2_lib.baseboard_fab2(sch_1):page236_i141:b" )
			)
			( pin "R9F70.1"
				( objectStatus "@baseboard_fab2_lib.baseboard_fab2(sch_1):page181_i280:a" )
			)
			( pin "R9F70.2"
				( objectStatus "@baseboard_fab2_lib.baseboard_fab2(sch_1):page181_i280:b" )
			)
			( pin "CT67.1"
				( objectStatus "@baseboard_fab2_lib.baseboard_fab2(sch_1):page236_i124:a" )
			)
			( pin "CT67.2"
				( objectStatus "@baseboard_fab2_lib.baseboard_fab2(sch_1):page236_i124:b" )
			)
			( pin "CT66.1"
				( objectStatus "@baseboard_fab2_lib.baseboard_fab2(sch_1):page236_i127:a" )
			)
			( pin "CT66.2"
				( objectStatus "@baseboard_fab2_lib.baseboard_fab2(sch_1):page236_i127:b" )
			)
			( pin "RT47.1"
				( objectStatus "@baseboard_fab2_lib.baseboard_fab2(sch_1):page212_i114:a" )
			)
			( pin "RT47.2"
				( objectStatus "@baseboard_fab2_lib.baseboard_fab2(sch_1):page212_i114:b" )
			)
			( pin "CT65.1"
				( objectStatus "@baseboard_fab2_lib.baseboard_fab2(sch_1):page236_i131:\1\" )
			)
			( pin "CT65.2"
				( objectStatus "@baseboard_fab2_lib.baseboard_fab2(sch_1):page236_i131:\2\" )
			)
			( pin "RT43.1"
				( objectStatus "@baseboard_fab2_lib.baseboard_fab2(sch_1):page236_i132:\1\" )
			)
			( pin "RT43.2"
				( objectStatus "@baseboard_fab2_lib.baseboard_fab2(sch_1):page236_i132:\2\" )
			)
			( pin "CT69.1"
				( objectStatus "@baseboard_fab2_lib.baseboard_fab2(sch_1):page236_i134:a" )
			)
			( pin "CT69.2"
				( objectStatus "@baseboard_fab2_lib.baseboard_fab2(sch_1):page236_i134:b" )
			)
			( pin "CT64.1"
				( objectStatus "@baseboard_fab2_lib.baseboard_fab2(sch_1):page236_i136:a" )
			)
			( pin "CT64.2"
				( objectStatus "@baseboard_fab2_lib.baseboard_fab2(sch_1):page236_i136:b" )
			)
			( pin "RT45.1"
				( objectStatus "@baseboard_fab2_lib.baseboard_fab2(sch_1):page236_i137:\1\" )
			)
			( pin "RT45.2"
				( objectStatus "@baseboard_fab2_lib.baseboard_fab2(sch_1):page236_i137:\2\" )
			)
			( pin "CT68.1"
				( objectStatus "@baseboard_fab2_lib.baseboard_fab2(sch_1):page236_i140:\1\" )
			)
			( pin "CT68.2"
				( objectStatus "@baseboard_fab2_lib.baseboard_fab2(sch_1):page236_i140:\2\" )
			)
			( pin "CT70.1"
				( objectStatus "@baseboard_fab2_lib.baseboard_fab2(sch_1):page212_i106:a" )
			)
			( pin "CT70.2"
				( objectStatus "@baseboard_fab2_lib.baseboard_fab2(sch_1):page212_i106:b" )
			)
			( pin "R9F65.1"
				( objectStatus "@baseboard_fab2_lib.baseboard_fab2(sch_1):page158_i148:a" )
			)
			( pin "R9F65.2"
				( objectStatus "@baseboard_fab2_lib.baseboard_fab2(sch_1):page158_i148:b" )
			)
			( pin "CT71.1"
				( objectStatus "@baseboard_fab2_lib.baseboard_fab2(sch_1):page212_i109:a" )
			)
			( pin "CT71.2"
				( objectStatus "@baseboard_fab2_lib.baseboard_fab2(sch_1):page212_i109:b" )
			)
			( pin "CT72.1"
				( objectStatus "@baseboard_fab2_lib.baseboard_fab2(sch_1):page212_i111:\1\" )
			)
			( pin "CT72.2"
				( objectStatus "@baseboard_fab2_lib.baseboard_fab2(sch_1):page212_i111:\2\" )
			)
			( pin "RT48.1"
				( objectStatus "@baseboard_fab2_lib.baseboard_fab2(sch_1):page212_i112:\1\" )
			)
			( pin "RT48.2"
				( objectStatus "@baseboard_fab2_lib.baseboard_fab2(sch_1):page212_i112:\2\" )
			)
			( pin "CT25.1"
				( objectStatus "@baseboard_fab2_lib.baseboard_fab2(sch_1):page207_i81:a" )
			)
			( pin "CT25.2"
				( objectStatus "@baseboard_fab2_lib.baseboard_fab2(sch_1):page207_i81:b" )
			)
			( pin "CT26.1"
				( objectStatus "@baseboard_fab2_lib.baseboard_fab2(sch_1):page207_i82:a" )
			)
			( pin "CT26.2"
				( objectStatus "@baseboard_fab2_lib.baseboard_fab2(sch_1):page207_i82:b" )
			)
			( pin "CT27.1"
				( objectStatus "@baseboard_fab2_lib.baseboard_fab2(sch_1):page207_i84:\1\" )
			)
			( pin "CT27.2"
				( objectStatus "@baseboard_fab2_lib.baseboard_fab2(sch_1):page207_i84:\2\" )
			)
			( pin "RT18.1"
				( objectStatus "@baseboard_fab2_lib.baseboard_fab2(sch_1):page207_i85:\1\" )
			)
			( pin "RT18.2"
				( objectStatus "@baseboard_fab2_lib.baseboard_fab2(sch_1):page207_i85:\2\" )
			)
			( pin "RT7.1"
				( objectStatus "@baseboard_fab2_lib.baseboard_fab2(sch_1):page227_i124:\1\" )
			)
			( pin "RT7.2"
				( objectStatus "@baseboard_fab2_lib.baseboard_fab2(sch_1):page227_i124:\2\" )
			)
			( pin "CT4.1"
				( objectStatus "@baseboard_fab2_lib.baseboard_fab2(sch_1):page202_i87:a" )
			)
			( pin "CT4.2"
				( objectStatus "@baseboard_fab2_lib.baseboard_fab2(sch_1):page202_i87:b" )
			)
			( pin "C831.1"
				( objectStatus "@baseboard_fab2_lib.baseboard_fab2(sch_1):page244_i2:a" )
			)
			( pin "C831.2"
				( objectStatus "@baseboard_fab2_lib.baseboard_fab2(sch_1):page244_i2:b" )
			)
			( pin "C829.1"
				( objectStatus "@baseboard_fab2_lib.baseboard_fab2(sch_1):page244_i5:a" )
			)
			( pin "C829.2"
				( objectStatus "@baseboard_fab2_lib.baseboard_fab2(sch_1):page244_i5:b" )
			)
			( pin "C833.1"
				( objectStatus "@baseboard_fab2_lib.baseboard_fab2(sch_1):page244_i8:a" )
			)
			( pin "C833.2"
				( objectStatus "@baseboard_fab2_lib.baseboard_fab2(sch_1):page244_i8:b" )
			)
			( pin "C827.1"
				( objectStatus "@baseboard_fab2_lib.baseboard_fab2(sch_1):page244_i12:a" )
			)
			( pin "C827.2"
				( objectStatus "@baseboard_fab2_lib.baseboard_fab2(sch_1):page244_i12:b" )
			)
			( pin "C841.1"
				( objectStatus "@baseboard_fab2_lib.baseboard_fab2(sch_1):page244_i17:a" )
			)
			( pin "C841.2"
				( objectStatus "@baseboard_fab2_lib.baseboard_fab2(sch_1):page244_i17:b" )
			)
			( pin "C830.1"
				( objectStatus "@baseboard_fab2_lib.baseboard_fab2(sch_1):page244_i23:a" )
			)
			( pin "C830.2"
				( objectStatus "@baseboard_fab2_lib.baseboard_fab2(sch_1):page244_i23:b" )
			)
			( pin "C826.1"
				( objectStatus "@baseboard_fab2_lib.baseboard_fab2(sch_1):page244_i24:a" )
			)
			( pin "C826.2"
				( objectStatus "@baseboard_fab2_lib.baseboard_fab2(sch_1):page244_i24:b" )
			)
			( pin "C828.1"
				( objectStatus "@baseboard_fab2_lib.baseboard_fab2(sch_1):page244_i28:a" )
			)
			( pin "C828.2"
				( objectStatus "@baseboard_fab2_lib.baseboard_fab2(sch_1):page244_i28:b" )
			)
			( pin "C840.1"
				( objectStatus "@baseboard_fab2_lib.baseboard_fab2(sch_1):page244_i29:a" )
			)
			( pin "C840.2"
				( objectStatus "@baseboard_fab2_lib.baseboard_fab2(sch_1):page244_i29:b" )
			)
			( pin "C832.1"
				( objectStatus "@baseboard_fab2_lib.baseboard_fab2(sch_1):page244_i30:a" )
			)
			( pin "C832.2"
				( objectStatus "@baseboard_fab2_lib.baseboard_fab2(sch_1):page244_i30:b" )
			)
			( pin "C845.1"
				( objectStatus "@baseboard_fab2_lib.baseboard_fab2(sch_1):page244_i35:a" )
			)
			( pin "C845.2"
				( objectStatus "@baseboard_fab2_lib.baseboard_fab2(sch_1):page244_i35:b" )
			)
			( pin "R767.1"
				( objectStatus "@baseboard_fab2_lib.baseboard_fab2(sch_1):page244_i39:a" )
			)
			( pin "R767.2"
				( objectStatus "@baseboard_fab2_lib.baseboard_fab2(sch_1):page244_i39:b" )
			)
			( pin "C835.1"
				( objectStatus "@baseboard_fab2_lib.baseboard_fab2(sch_1):page244_i41:a" )
			)
			( pin "C835.2"
				( objectStatus "@baseboard_fab2_lib.baseboard_fab2(sch_1):page244_i41:b" )
			)
			( pin "C843.1"
				( objectStatus "@baseboard_fab2_lib.baseboard_fab2(sch_1):page244_i47:a" )
			)
			( pin "C843.2"
				( objectStatus "@baseboard_fab2_lib.baseboard_fab2(sch_1):page244_i47:b" )
			)
			( pin "C834.1"
				( objectStatus "@baseboard_fab2_lib.baseboard_fab2(sch_1):page244_i50:a" )
			)
			( pin "C834.2"
				( objectStatus "@baseboard_fab2_lib.baseboard_fab2(sch_1):page244_i50:b" )
			)
			( pin "C844.1"
				( objectStatus "@baseboard_fab2_lib.baseboard_fab2(sch_1):page244_i51:a" )
			)
			( pin "C844.2"
				( objectStatus "@baseboard_fab2_lib.baseboard_fab2(sch_1):page244_i51:b" )
			)
			( pin "C842.1"
				( objectStatus "@baseboard_fab2_lib.baseboard_fab2(sch_1):page244_i52:a" )
			)
			( pin "C842.2"
				( objectStatus "@baseboard_fab2_lib.baseboard_fab2(sch_1):page244_i52:b" )
			)
			( pin "R769.1"
				( objectStatus "@baseboard_fab2_lib.baseboard_fab2(sch_1):page244_i58:a" )
			)
			( pin "R769.2"
				( objectStatus "@baseboard_fab2_lib.baseboard_fab2(sch_1):page244_i58:b" )
			)
			( pin "R760.1"
				( objectStatus "@baseboard_fab2_lib.baseboard_fab2(sch_1):page244_i64:a" )
			)
			( pin "R760.2"
				( objectStatus "@baseboard_fab2_lib.baseboard_fab2(sch_1):page244_i64:b" )
			)
			( pin "R771.1"
				( objectStatus "@baseboard_fab2_lib.baseboard_fab2(sch_1):page244_i65:a" )
			)
			( pin "R771.2"
				( objectStatus "@baseboard_fab2_lib.baseboard_fab2(sch_1):page244_i65:b" )
			)
			( pin "R768.1"
				( objectStatus "@baseboard_fab2_lib.baseboard_fab2(sch_1):page244_i66:a" )
			)
			( pin "R768.2"
				( objectStatus "@baseboard_fab2_lib.baseboard_fab2(sch_1):page244_i66:b" )
			)
			( pin "R774.1"
				( objectStatus "@baseboard_fab2_lib.baseboard_fab2(sch_1):page244_i72:a" )
			)
			( pin "R774.2"
				( objectStatus "@baseboard_fab2_lib.baseboard_fab2(sch_1):page244_i72:b" )
			)
			( pin "R779.1"
				( objectStatus "@baseboard_fab2_lib.baseboard_fab2(sch_1):page244_i74:a" )
			)
			( pin "R779.2"
				( objectStatus "@baseboard_fab2_lib.baseboard_fab2(sch_1):page244_i74:b" )
			)
			( pin "R783.1"
				( objectStatus "@baseboard_fab2_lib.baseboard_fab2(sch_1):page244_i77:a" )
			)
			( pin "R783.2"
				( objectStatus "@baseboard_fab2_lib.baseboard_fab2(sch_1):page244_i77:b" )
			)
			( pin "R777.1"
				( objectStatus "@baseboard_fab2_lib.baseboard_fab2(sch_1):page244_i80:a" )
			)
			( pin "R777.2"
				( objectStatus "@baseboard_fab2_lib.baseboard_fab2(sch_1):page244_i80:b" )
			)
			( pin "R781.1"
				( objectStatus "@baseboard_fab2_lib.baseboard_fab2(sch_1):page244_i86:a" )
			)
			( pin "R781.2"
				( objectStatus "@baseboard_fab2_lib.baseboard_fab2(sch_1):page244_i86:b" )
			)
			( pin "R775.1"
				( objectStatus "@baseboard_fab2_lib.baseboard_fab2(sch_1):page244_i93:a" )
			)
			( pin "R775.2"
				( objectStatus "@baseboard_fab2_lib.baseboard_fab2(sch_1):page244_i93:b" )
			)
			( pin "R778.1"
				( objectStatus "@baseboard_fab2_lib.baseboard_fab2(sch_1):page244_i94:a" )
			)
			( pin "R778.2"
				( objectStatus "@baseboard_fab2_lib.baseboard_fab2(sch_1):page244_i94:b" )
			)
			( pin "R780.1"
				( objectStatus "@baseboard_fab2_lib.baseboard_fab2(sch_1):page244_i97:a" )
			)
			( pin "R780.2"
				( objectStatus "@baseboard_fab2_lib.baseboard_fab2(sch_1):page244_i97:b" )
			)
			( pin "R782.1"
				( objectStatus "@baseboard_fab2_lib.baseboard_fab2(sch_1):page244_i98:a" )
			)
			( pin "R782.2"
				( objectStatus "@baseboard_fab2_lib.baseboard_fab2(sch_1):page244_i98:b" )
			)
			( pin "R784.1"
				( objectStatus "@baseboard_fab2_lib.baseboard_fab2(sch_1):page244_i99:a" )
			)
			( pin "R784.2"
				( objectStatus "@baseboard_fab2_lib.baseboard_fab2(sch_1):page244_i99:b" )
			)
			( pin "R785.1"
				( objectStatus "@baseboard_fab2_lib.baseboard_fab2(sch_1):page244_i103:a" )
			)
			( pin "R785.2"
				( objectStatus "@baseboard_fab2_lib.baseboard_fab2(sch_1):page244_i103:b" )
			)
			( pin "CONX8.1"
				( objectStatus "@baseboard_fab2_lib.baseboard_fab2(sch_1):page245_i48:\1\" )
			)
			( pin "CONX8.2"
				( objectStatus "@baseboard_fab2_lib.baseboard_fab2(sch_1):page245_i48:\2\" )
			)
			( pin "CONX8.3"
				( objectStatus "@baseboard_fab2_lib.baseboard_fab2(sch_1):page245_i48:\3\" )
			)
			( pin "CONX8.4"
				( objectStatus "@baseboard_fab2_lib.baseboard_fab2(sch_1):page245_i48:\4\" )
			)
			( pin "CONX8.5"
				( objectStatus "@baseboard_fab2_lib.baseboard_fab2(sch_1):page245_i48:\5\" )
			)
			( pin "CONX8.6"
				( objectStatus "@baseboard_fab2_lib.baseboard_fab2(sch_1):page245_i48:\6\" )
			)
			( pin "CONX8.7"
				( objectStatus "@baseboard_fab2_lib.baseboard_fab2(sch_1):page245_i48:\7\" )
			)
			( pin "CONX8.8"
				( objectStatus "@baseboard_fab2_lib.baseboard_fab2(sch_1):page245_i48:\8\" )
			)
			( pin "CONX8.9"
				( objectStatus "@baseboard_fab2_lib.baseboard_fab2(sch_1):page245_i48:\9\" )
			)
			( pin "CONX8.10"
				( objectStatus "@baseboard_fab2_lib.baseboard_fab2(sch_1):page245_i48:\10\" )
			)
			( pin "CONX8.11"
				( objectStatus "@baseboard_fab2_lib.baseboard_fab2(sch_1):page245_i48:\11\" )
			)
			( pin "CONX8.12"
				( objectStatus "@baseboard_fab2_lib.baseboard_fab2(sch_1):page245_i48:\12\" )
			)
			( pin "CONX8.13"
				( objectStatus "@baseboard_fab2_lib.baseboard_fab2(sch_1):page245_i48:\13\" )
			)
			( pin "CONX8.14"
				( objectStatus "@baseboard_fab2_lib.baseboard_fab2(sch_1):page245_i48:\14\" )
			)
			( pin "CONX8.15"
				( objectStatus "@baseboard_fab2_lib.baseboard_fab2(sch_1):page245_i48:\15\" )
			)
			( pin "CONX8.16"
				( objectStatus "@baseboard_fab2_lib.baseboard_fab2(sch_1):page245_i48:\16\" )
			)
			( pin "CONX8.17"
				( objectStatus "@baseboard_fab2_lib.baseboard_fab2(sch_1):page245_i48:\17\" )
			)
			( pin "CONX8.18"
				( objectStatus "@baseboard_fab2_lib.baseboard_fab2(sch_1):page245_i48:\18\" )
			)
			( pin "CONX8.19"
				( objectStatus "@baseboard_fab2_lib.baseboard_fab2(sch_1):page245_i48:\19\" )
			)
			( pin "CONX8.20"
				( objectStatus "@baseboard_fab2_lib.baseboard_fab2(sch_1):page245_i48:\20\" )
			)
			( pin "CONX8.21"
				( objectStatus "@baseboard_fab2_lib.baseboard_fab2(sch_1):page245_i48:\21\" )
			)
			( pin "CONX8.22"
				( objectStatus "@baseboard_fab2_lib.baseboard_fab2(sch_1):page245_i48:\22\" )
			)
			( pin "CONX8.23"
				( objectStatus "@baseboard_fab2_lib.baseboard_fab2(sch_1):page245_i48:\23\" )
			)
			( pin "CONX8.24"
				( objectStatus "@baseboard_fab2_lib.baseboard_fab2(sch_1):page245_i48:\24\" )
			)
			( pin "CONX8.25"
				( objectStatus "@baseboard_fab2_lib.baseboard_fab2(sch_1):page245_i48:\25\" )
			)
			( pin "CONX8.26"
				( objectStatus "@baseboard_fab2_lib.baseboard_fab2(sch_1):page245_i48:\26\" )
			)
			( pin "CONX8.27"
				( objectStatus "@baseboard_fab2_lib.baseboard_fab2(sch_1):page245_i48:\27\" )
			)
			( pin "CONX8.28"
				( objectStatus "@baseboard_fab2_lib.baseboard_fab2(sch_1):page245_i48:\28\" )
			)
			( pin "CONX8.29"
				( objectStatus "@baseboard_fab2_lib.baseboard_fab2(sch_1):page245_i48:\29\" )
			)
			( pin "CONX8.30"
				( objectStatus "@baseboard_fab2_lib.baseboard_fab2(sch_1):page245_i48:\30\" )
			)
			( pin "CONX8.31"
				( objectStatus "@baseboard_fab2_lib.baseboard_fab2(sch_1):page245_i48:\31\" )
			)
			( pin "CONX8.32"
				( objectStatus "@baseboard_fab2_lib.baseboard_fab2(sch_1):page245_i48:\32\" )
			)
			( pin "CONX8.33"
				( objectStatus "@baseboard_fab2_lib.baseboard_fab2(sch_1):page245_i48:\33\" )
			)
			( pin "CONX8.34"
				( objectStatus "@baseboard_fab2_lib.baseboard_fab2(sch_1):page245_i48:\34\" )
			)
			( pin "CONX8.35"
				( objectStatus "@baseboard_fab2_lib.baseboard_fab2(sch_1):page245_i48:\35\" )
			)
			( pin "CONX8.36"
				( objectStatus "@baseboard_fab2_lib.baseboard_fab2(sch_1):page245_i48:\36\" )
			)
			( pin "CONX8.37"
				( objectStatus "@baseboard_fab2_lib.baseboard_fab2(sch_1):page245_i48:\37\" )
			)
			( pin "CONX8.38"
				( objectStatus "@baseboard_fab2_lib.baseboard_fab2(sch_1):page245_i48:\38\" )
			)
			( pin "CONX8.39"
				( objectStatus "@baseboard_fab2_lib.baseboard_fab2(sch_1):page245_i48:\39\" )
			)
			( pin "CONX8.40"
				( objectStatus "@baseboard_fab2_lib.baseboard_fab2(sch_1):page245_i48:\40\" )
			)
			( pin "CONX8.41"
				( objectStatus "@baseboard_fab2_lib.baseboard_fab2(sch_1):page245_i48:\41\" )
			)
			( pin "CONX8.42"
				( objectStatus "@baseboard_fab2_lib.baseboard_fab2(sch_1):page245_i48:\42\" )
			)
			( pin "CONX8.43"
				( objectStatus "@baseboard_fab2_lib.baseboard_fab2(sch_1):page245_i48:\43\" )
			)
			( pin "CONX8.44"
				( objectStatus "@baseboard_fab2_lib.baseboard_fab2(sch_1):page245_i48:\44\" )
			)
			( pin "CONX8.45"
				( objectStatus "@baseboard_fab2_lib.baseboard_fab2(sch_1):page245_i48:\45\" )
			)
			( pin "CONX8.46"
				( objectStatus "@baseboard_fab2_lib.baseboard_fab2(sch_1):page245_i48:\46\" )
			)
			( pin "CONX8.47"
				( objectStatus "@baseboard_fab2_lib.baseboard_fab2(sch_1):page245_i48:\47\" )
			)
			( pin "CONX8.48"
				( objectStatus "@baseboard_fab2_lib.baseboard_fab2(sch_1):page245_i48:\48\" )
			)
			( pin "CONX8.49"
				( objectStatus "@baseboard_fab2_lib.baseboard_fab2(sch_1):page245_i48:\49\" )
			)
			( pin "CONX8.50"
				( objectStatus "@baseboard_fab2_lib.baseboard_fab2(sch_1):page245_i48:\50\" )
			)
			( pin "CONX8.51"
				( objectStatus "@baseboard_fab2_lib.baseboard_fab2(sch_1):page245_i48:\51\" )
			)
			( pin "CONX8.52"
				( objectStatus "@baseboard_fab2_lib.baseboard_fab2(sch_1):page245_i48:\52\" )
			)
			( pin "CONX8.53"
				( objectStatus "@baseboard_fab2_lib.baseboard_fab2(sch_1):page245_i48:\53\" )
			)
			( pin "CONX8.54"
				( objectStatus "@baseboard_fab2_lib.baseboard_fab2(sch_1):page245_i48:\54\" )
			)
			( pin "CONX8.55"
				( objectStatus "@baseboard_fab2_lib.baseboard_fab2(sch_1):page245_i48:\55\" )
			)
			( pin "CONX8.56"
				( objectStatus "@baseboard_fab2_lib.baseboard_fab2(sch_1):page245_i48:\56\" )
			)
			( pin "CONX8.57"
				( objectStatus "@baseboard_fab2_lib.baseboard_fab2(sch_1):page245_i48:\57\" )
			)
			( pin "CONX8.58"
				( objectStatus "@baseboard_fab2_lib.baseboard_fab2(sch_1):page245_i48:\58\" )
			)
			( pin "CONX8.59"
				( objectStatus "@baseboard_fab2_lib.baseboard_fab2(sch_1):page245_i48:\59\" )
			)
			( pin "CONX8.60"
				( objectStatus "@baseboard_fab2_lib.baseboard_fab2(sch_1):page245_i48:\60\" )
			)
			( pin "CONX8.NP1"
				( objectStatus "@baseboard_fab2_lib.baseboard_fab2(sch_1):page245_i48:np1" )
			)
			( pin "CONX8.NP2"
				( objectStatus "@baseboard_fab2_lib.baseboard_fab2(sch_1):page245_i48:np2" )
			)
			( pin "CONX8.PTH1"
				( objectStatus "@baseboard_fab2_lib.baseboard_fab2(sch_1):page245_i48:pth1" )
			)
			( pin "CONX8.PTH2"
				( objectStatus "@baseboard_fab2_lib.baseboard_fab2(sch_1):page245_i48:pth2" )
			)
			( pin "J8G1.101"
				( objectStatus "@baseboard_fab2_lib.baseboard_fab2(sch_1):page109_i78:io101" )
			)
			( pin "J8G1.102"
				( objectStatus "@baseboard_fab2_lib.baseboard_fab2(sch_1):page109_i78:io102" )
			)
			( pin "J8G1.103"
				( objectStatus "@baseboard_fab2_lib.baseboard_fab2(sch_1):page109_i78:io103" )
			)
			( pin "J8G1.104"
				( objectStatus "@baseboard_fab2_lib.baseboard_fab2(sch_1):page109_i78:io104" )
			)
			( pin "J8G1.105"
				( objectStatus "@baseboard_fab2_lib.baseboard_fab2(sch_1):page109_i78:io105" )
			)
			( pin "J8G1.106"
				( objectStatus "@baseboard_fab2_lib.baseboard_fab2(sch_1):page109_i78:io106" )
			)
			( pin "J8G1.107"
				( objectStatus "@baseboard_fab2_lib.baseboard_fab2(sch_1):page109_i78:io107" )
			)
			( pin "J8G1.108"
				( objectStatus "@baseboard_fab2_lib.baseboard_fab2(sch_1):page109_i78:io108" )
			)
			( pin "J8G1.109"
				( objectStatus "@baseboard_fab2_lib.baseboard_fab2(sch_1):page109_i78:io109" )
			)
			( pin "J8G1.110"
				( objectStatus "@baseboard_fab2_lib.baseboard_fab2(sch_1):page109_i78:io110" )
			)
			( pin "J8G1.111"
				( objectStatus "@baseboard_fab2_lib.baseboard_fab2(sch_1):page109_i78:io111" )
			)
			( pin "J8G1.112"
				( objectStatus "@baseboard_fab2_lib.baseboard_fab2(sch_1):page109_i78:io112" )
			)
			( pin "J8G1.113"
				( objectStatus "@baseboard_fab2_lib.baseboard_fab2(sch_1):page109_i78:io113" )
			)
			( pin "J8G1.114"
				( objectStatus "@baseboard_fab2_lib.baseboard_fab2(sch_1):page109_i78:io114" )
			)
			( pin "J8G1.115"
				( objectStatus "@baseboard_fab2_lib.baseboard_fab2(sch_1):page109_i78:io115" )
			)
			( pin "J8G1.116"
				( objectStatus "@baseboard_fab2_lib.baseboard_fab2(sch_1):page109_i78:io116" )
			)
			( pin "J8G1.117"
				( objectStatus "@baseboard_fab2_lib.baseboard_fab2(sch_1):page109_i78:io117" )
			)
			( pin "J8G1.118"
				( objectStatus "@baseboard_fab2_lib.baseboard_fab2(sch_1):page109_i78:io118" )
			)
			( pin "J8G1.119"
				( objectStatus "@baseboard_fab2_lib.baseboard_fab2(sch_1):page109_i78:io119" )
			)
			( pin "J8G1.120"
				( objectStatus "@baseboard_fab2_lib.baseboard_fab2(sch_1):page109_i78:io120" )
			)
			( pin "J8G1.121"
				( objectStatus "@baseboard_fab2_lib.baseboard_fab2(sch_1):page109_i78:io121" )
			)
			( pin "J8G1.122"
				( objectStatus "@baseboard_fab2_lib.baseboard_fab2(sch_1):page109_i78:io122" )
			)
			( pin "J8G1.123"
				( objectStatus "@baseboard_fab2_lib.baseboard_fab2(sch_1):page109_i78:io123" )
			)
			( pin "J8G1.124"
				( objectStatus "@baseboard_fab2_lib.baseboard_fab2(sch_1):page109_i78:io124" )
			)
			( pin "J8G1.125"
				( objectStatus "@baseboard_fab2_lib.baseboard_fab2(sch_1):page109_i78:io125" )
			)
			( pin "J8G1.126"
				( objectStatus "@baseboard_fab2_lib.baseboard_fab2(sch_1):page109_i78:io126" )
			)
			( pin "J8G1.127"
				( objectStatus "@baseboard_fab2_lib.baseboard_fab2(sch_1):page109_i78:io127" )
			)
			( pin "J8G1.128"
				( objectStatus "@baseboard_fab2_lib.baseboard_fab2(sch_1):page109_i78:io128" )
			)
			( pin "J8G1.129"
				( objectStatus "@baseboard_fab2_lib.baseboard_fab2(sch_1):page109_i78:io129" )
			)
			( pin "J8G1.130"
				( objectStatus "@baseboard_fab2_lib.baseboard_fab2(sch_1):page109_i78:io130" )
			)
			( pin "J8G1.131"
				( objectStatus "@baseboard_fab2_lib.baseboard_fab2(sch_1):page109_i78:io131" )
			)
			( pin "J8G1.132"
				( objectStatus "@baseboard_fab2_lib.baseboard_fab2(sch_1):page109_i78:io132" )
			)
			( pin "J8G1.133"
				( objectStatus "@baseboard_fab2_lib.baseboard_fab2(sch_1):page109_i78:io133" )
			)
			( pin "J8G1.134"
				( objectStatus "@baseboard_fab2_lib.baseboard_fab2(sch_1):page109_i78:io134" )
			)
			( pin "J8G1.135"
				( objectStatus "@baseboard_fab2_lib.baseboard_fab2(sch_1):page109_i78:io135" )
			)
			( pin "J8G1.136"
				( objectStatus "@baseboard_fab2_lib.baseboard_fab2(sch_1):page109_i78:io136" )
			)
			( pin "J8G1.137"
				( objectStatus "@baseboard_fab2_lib.baseboard_fab2(sch_1):page109_i78:io137" )
			)
			( pin "J8G1.138"
				( objectStatus "@baseboard_fab2_lib.baseboard_fab2(sch_1):page109_i78:io138" )
			)
			( pin "J8G1.139"
				( objectStatus "@baseboard_fab2_lib.baseboard_fab2(sch_1):page109_i78:io139" )
			)
			( pin "J8G1.140"
				( objectStatus "@baseboard_fab2_lib.baseboard_fab2(sch_1):page109_i78:io140" )
			)
			( pin "J8G1.141"
				( objectStatus "@baseboard_fab2_lib.baseboard_fab2(sch_1):page109_i78:io141" )
			)
			( pin "J8G1.142"
				( objectStatus "@baseboard_fab2_lib.baseboard_fab2(sch_1):page109_i78:io142" )
			)
			( pin "J8G1.143"
				( objectStatus "@baseboard_fab2_lib.baseboard_fab2(sch_1):page109_i78:io143" )
			)
			( pin "J8G1.144"
				( objectStatus "@baseboard_fab2_lib.baseboard_fab2(sch_1):page109_i78:io144" )
			)
			( pin "J8G1.145"
				( objectStatus "@baseboard_fab2_lib.baseboard_fab2(sch_1):page109_i78:io145" )
			)
			( pin "J8G1.146"
				( objectStatus "@baseboard_fab2_lib.baseboard_fab2(sch_1):page109_i78:io146" )
			)
			( pin "J8G1.147"
				( objectStatus "@baseboard_fab2_lib.baseboard_fab2(sch_1):page109_i78:io147" )
			)
			( pin "J8G1.148"
				( objectStatus "@baseboard_fab2_lib.baseboard_fab2(sch_1):page109_i78:io148" )
			)
			( pin "J8G1.149"
				( objectStatus "@baseboard_fab2_lib.baseboard_fab2(sch_1):page109_i78:io149" )
			)
			( pin "J8G1.150"
				( objectStatus "@baseboard_fab2_lib.baseboard_fab2(sch_1):page109_i78:io150" )
			)
			( pin "J8G1.151"
				( objectStatus "@baseboard_fab2_lib.baseboard_fab2(sch_1):page109_i78:io151" )
			)
			( pin "J8G1.152"
				( objectStatus "@baseboard_fab2_lib.baseboard_fab2(sch_1):page109_i78:io152" )
			)
			( pin "J8G1.153"
				( objectStatus "@baseboard_fab2_lib.baseboard_fab2(sch_1):page109_i78:io153" )
			)
			( pin "J8G1.154"
				( objectStatus "@baseboard_fab2_lib.baseboard_fab2(sch_1):page109_i78:io154" )
			)
			( pin "J8G1.155"
				( objectStatus "@baseboard_fab2_lib.baseboard_fab2(sch_1):page109_i78:io155" )
			)
			( pin "J8G1.156"
				( objectStatus "@baseboard_fab2_lib.baseboard_fab2(sch_1):page109_i78:io156" )
			)
			( pin "J8G1.157"
				( objectStatus "@baseboard_fab2_lib.baseboard_fab2(sch_1):page109_i78:io157" )
			)
			( pin "J8G1.158"
				( objectStatus "@baseboard_fab2_lib.baseboard_fab2(sch_1):page109_i78:io158" )
			)
			( pin "J8G1.159"
				( objectStatus "@baseboard_fab2_lib.baseboard_fab2(sch_1):page109_i78:io159" )
			)
			( pin "J8G1.160"
				( objectStatus "@baseboard_fab2_lib.baseboard_fab2(sch_1):page109_i78:io160" )
			)
			( pin "J8G1.161"
				( objectStatus "@baseboard_fab2_lib.baseboard_fab2(sch_1):page109_i78:io161" )
			)
			( pin "J8G1.162"
				( objectStatus "@baseboard_fab2_lib.baseboard_fab2(sch_1):page109_i78:io162" )
			)
			( pin "J8G1.163"
				( objectStatus "@baseboard_fab2_lib.baseboard_fab2(sch_1):page109_i78:io163" )
			)
			( pin "J8G1.164"
				( objectStatus "@baseboard_fab2_lib.baseboard_fab2(sch_1):page109_i78:io164" )
			)
			( pin "J8G1.165"
				( objectStatus "@baseboard_fab2_lib.baseboard_fab2(sch_1):page109_i78:io165" )
			)
			( pin "J8G1.166"
				( objectStatus "@baseboard_fab2_lib.baseboard_fab2(sch_1):page109_i78:io166" )
			)
			( pin "J8G1.167"
				( objectStatus "@baseboard_fab2_lib.baseboard_fab2(sch_1):page109_i78:io167" )
			)
			( pin "J8G1.168"
				( objectStatus "@baseboard_fab2_lib.baseboard_fab2(sch_1):page109_i78:io168" )
			)
			( pin "J8G1.169"
				( objectStatus "@baseboard_fab2_lib.baseboard_fab2(sch_1):page109_i78:io169" )
			)
			( pin "J8G1.170"
				( objectStatus "@baseboard_fab2_lib.baseboard_fab2(sch_1):page109_i78:io170" )
			)
			( pin "J8G1.171"
				( objectStatus "@baseboard_fab2_lib.baseboard_fab2(sch_1):page109_i78:io171" )
			)
			( pin "J8G1.172"
				( objectStatus "@baseboard_fab2_lib.baseboard_fab2(sch_1):page109_i78:io172" )
			)
			( pin "J8G1.173"
				( objectStatus "@baseboard_fab2_lib.baseboard_fab2(sch_1):page109_i78:io173" )
			)
			( pin "J8G1.174"
				( objectStatus "@baseboard_fab2_lib.baseboard_fab2(sch_1):page109_i78:io174" )
			)
			( pin "J8G1.175"
				( objectStatus "@baseboard_fab2_lib.baseboard_fab2(sch_1):page109_i78:io175" )
			)
			( pin "J8G1.176"
				( objectStatus "@baseboard_fab2_lib.baseboard_fab2(sch_1):page109_i78:io176" )
			)
			( pin "J8G1.177"
				( objectStatus "@baseboard_fab2_lib.baseboard_fab2(sch_1):page109_i78:io177" )
			)
			( pin "J8G1.178"
				( objectStatus "@baseboard_fab2_lib.baseboard_fab2(sch_1):page109_i78:io178" )
			)
			( pin "J8G1.179"
				( objectStatus "@baseboard_fab2_lib.baseboard_fab2(sch_1):page109_i78:io179" )
			)
			( pin "J8G1.180"
				( objectStatus "@baseboard_fab2_lib.baseboard_fab2(sch_1):page109_i78:io180" )
			)
			( pin "J8G1.181"
				( objectStatus "@baseboard_fab2_lib.baseboard_fab2(sch_1):page109_i78:io181" )
			)
			( pin "J8G1.182"
				( objectStatus "@baseboard_fab2_lib.baseboard_fab2(sch_1):page109_i78:io182" )
			)
			( pin "J8G1.183"
				( objectStatus "@baseboard_fab2_lib.baseboard_fab2(sch_1):page109_i78:io183" )
			)
			( pin "J8G1.184"
				( objectStatus "@baseboard_fab2_lib.baseboard_fab2(sch_1):page109_i78:io184" )
			)
			( pin "J8G1.185"
				( objectStatus "@baseboard_fab2_lib.baseboard_fab2(sch_1):page109_i78:io185" )
			)
			( pin "J8G1.186"
				( objectStatus "@baseboard_fab2_lib.baseboard_fab2(sch_1):page109_i78:io186" )
			)
			( pin "J8G1.187"
				( objectStatus "@baseboard_fab2_lib.baseboard_fab2(sch_1):page109_i78:io187" )
			)
			( pin "J8G1.188"
				( objectStatus "@baseboard_fab2_lib.baseboard_fab2(sch_1):page109_i78:io188" )
			)
			( pin "J8G1.189"
				( objectStatus "@baseboard_fab2_lib.baseboard_fab2(sch_1):page109_i78:io189" )
			)
			( pin "J8G1.190"
				( objectStatus "@baseboard_fab2_lib.baseboard_fab2(sch_1):page109_i78:io190" )
			)
			( pin "J8G1.191"
				( objectStatus "@baseboard_fab2_lib.baseboard_fab2(sch_1):page109_i78:io191" )
			)
			( pin "J8G1.192"
				( objectStatus "@baseboard_fab2_lib.baseboard_fab2(sch_1):page109_i78:io192" )
			)
			( pin "J8G1.193"
				( objectStatus "@baseboard_fab2_lib.baseboard_fab2(sch_1):page109_i78:io193" )
			)
			( pin "J8G1.194"
				( objectStatus "@baseboard_fab2_lib.baseboard_fab2(sch_1):page109_i78:io194" )
			)
			( pin "J8G1.195"
				( objectStatus "@baseboard_fab2_lib.baseboard_fab2(sch_1):page109_i78:io195" )
			)
			( pin "J8G1.196"
				( objectStatus "@baseboard_fab2_lib.baseboard_fab2(sch_1):page109_i78:io196" )
			)
			( pin "J8G1.197"
				( objectStatus "@baseboard_fab2_lib.baseboard_fab2(sch_1):page109_i78:io197" )
			)
			( pin "J8G1.198"
				( objectStatus "@baseboard_fab2_lib.baseboard_fab2(sch_1):page109_i78:io198" )
			)
			( pin "J8G1.199"
				( objectStatus "@baseboard_fab2_lib.baseboard_fab2(sch_1):page109_i78:io199" )
			)
			( pin "J8G1.200"
				( objectStatus "@baseboard_fab2_lib.baseboard_fab2(sch_1):page109_i78:io200" )
			)
			( pin "RN8F1.1"
				( objectStatus "@baseboard_fab2_lib.baseboard_fab2(sch_1):page246_i5:a" )
			)
			( pin "RN8F1.2"
				( objectStatus "@baseboard_fab2_lib.baseboard_fab2(sch_1):page246_i5:b" )
			)
			( pin "RN8F6.1"
				( objectStatus "@baseboard_fab2_lib.baseboard_fab2(sch_1):page246_i8:a" )
			)
			( pin "RN8F6.2"
				( objectStatus "@baseboard_fab2_lib.baseboard_fab2(sch_1):page246_i8:b" )
			)
			( pin "RN8F5.1"
				( objectStatus "@baseboard_fab2_lib.baseboard_fab2(sch_1):page246_i9:a" )
			)
			( pin "RN8F5.2"
				( objectStatus "@baseboard_fab2_lib.baseboard_fab2(sch_1):page246_i9:b" )
			)
			( pin "RN8F2.1"
				( objectStatus "@baseboard_fab2_lib.baseboard_fab2(sch_1):page246_i10:a" )
			)
			( pin "RN8F2.2"
				( objectStatus "@baseboard_fab2_lib.baseboard_fab2(sch_1):page246_i10:b" )
			)
			( pin "RN8F3.1"
				( objectStatus "@baseboard_fab2_lib.baseboard_fab2(sch_1):page246_i11:a" )
			)
			( pin "RN8F3.2"
				( objectStatus "@baseboard_fab2_lib.baseboard_fab2(sch_1):page246_i11:b" )
			)
			( pin "RN8F4.1"
				( objectStatus "@baseboard_fab2_lib.baseboard_fab2(sch_1):page246_i12:a" )
			)
			( pin "RN8F4.2"
				( objectStatus "@baseboard_fab2_lib.baseboard_fab2(sch_1):page246_i12:b" )
			)
			( pin "CN8F1.1"
				( objectStatus "@baseboard_fab2_lib.baseboard_fab2(sch_1):page246_i15:a" )
			)
			( pin "CN8F1.2"
				( objectStatus "@baseboard_fab2_lib.baseboard_fab2(sch_1):page246_i15:b" )
			)
			( pin "CN8F2.1"
				( objectStatus "@baseboard_fab2_lib.baseboard_fab2(sch_1):page246_i16:a" )
			)
			( pin "CN8F2.2"
				( objectStatus "@baseboard_fab2_lib.baseboard_fab2(sch_1):page246_i16:b" )
			)
			( pin "UN8F2.16"
				( objectStatus "@baseboard_fab2_lib.baseboard_fab2(sch_1):page246_i17:clk" )
			)
			( pin "UN8F2.7"
				( objectStatus "@baseboard_fab2_lib.baseboard_fab2(sch_1):page246_i17:cs_n" )
			)
			( pin "UN8F2.15"
				( objectStatus "@baseboard_fab2_lib.baseboard_fab2(sch_1):page246_i17:di_io(0)" )
			)
			( pin "UN8F2.8"
				( objectStatus "@baseboard_fab2_lib.baseboard_fab2(sch_1):page246_i17:do_io(1)" )
			)
			( pin "UN8F2.10"
				( objectStatus "@baseboard_fab2_lib.baseboard_fab2(sch_1):page246_i17:gnd" )
			)
			( pin "UN8F2.1"
				( objectStatus "@baseboard_fab2_lib.baseboard_fab2(sch_1):page246_i17:hold_n_io(3)" )
			)
			( pin "UN8F2.14"
				( objectStatus "@baseboard_fab2_lib.baseboard_fab2(sch_1):page246_i17:nc(0)" )
			)
			( pin "UN8F2.13"
				( objectStatus "@baseboard_fab2_lib.baseboard_fab2(sch_1):page246_i17:nc(1)" )
			)
			( pin "UN8F2.12"
				( objectStatus "@baseboard_fab2_lib.baseboard_fab2(sch_1):page246_i17:nc(2)" )
			)
			( pin "UN8F2.11"
				( objectStatus "@baseboard_fab2_lib.baseboard_fab2(sch_1):page246_i17:nc(3)" )
			)
			( pin "UN8F2.6"
				( objectStatus "@baseboard_fab2_lib.baseboard_fab2(sch_1):page246_i17:nc(4)" )
			)
			( pin "UN8F2.5"
				( objectStatus "@baseboard_fab2_lib.baseboard_fab2(sch_1):page246_i17:nc(5)" )
			)
			( pin "UN8F2.4"
				( objectStatus "@baseboard_fab2_lib.baseboard_fab2(sch_1):page246_i17:nc(6)" )
			)
			( pin "UN8F2.3"
				( objectStatus "@baseboard_fab2_lib.baseboard_fab2(sch_1):page246_i17:reset_n" )
			)
			( pin "UN8F2.2"
				( objectStatus "@baseboard_fab2_lib.baseboard_fab2(sch_1):page246_i17:vcc" )
			)
			( pin "UN8F2.9"
				( objectStatus "@baseboard_fab2_lib.baseboard_fab2(sch_1):page246_i17:wp_n_io(2)" )
			)
			( pin "Q6W1.3"
				( objectStatus "@baseboard_fab2_lib.baseboard_fab2(sch_1):page200_i225:drn" )
			)
			( pin "Q6W1.1"
				( objectStatus "@baseboard_fab2_lib.baseboard_fab2(sch_1):page200_i225:gate" )
			)
			( pin "Q6W1.2"
				( objectStatus "@baseboard_fab2_lib.baseboard_fab2(sch_1):page200_i225:src" )
			)
			( pin "R6W10.1"
				( objectStatus "@baseboard_fab2_lib.baseboard_fab2(sch_1):page247_i1:a" )
			)
			( pin "R6W10.2"
				( objectStatus "@baseboard_fab2_lib.baseboard_fab2(sch_1):page247_i1:b" )
			)
			( pin "R6W1.1"
				( objectStatus "@baseboard_fab2_lib.baseboard_fab2(sch_1):page200_i229:a" )
			)
			( pin "R6W1.2"
				( objectStatus "@baseboard_fab2_lib.baseboard_fab2(sch_1):page200_i229:b" )
			)
			( pin "R6W2.1"
				( objectStatus "@baseboard_fab2_lib.baseboard_fab2(sch_1):page200_i230:a" )
			)
			( pin "R6W2.2"
				( objectStatus "@baseboard_fab2_lib.baseboard_fab2(sch_1):page200_i230:b" )
			)
			( pin "C6W10.1"
				( objectStatus "@baseboard_fab2_lib.baseboard_fab2(sch_1):page176_i124:a" )
			)
			( pin "C6W10.2"
				( objectStatus "@baseboard_fab2_lib.baseboard_fab2(sch_1):page176_i124:b" )
			)
			( pin "R6W7.1"
				( objectStatus "@baseboard_fab2_lib.baseboard_fab2(sch_1):page247_i3:a" )
			)
			( pin "R6W7.2"
				( objectStatus "@baseboard_fab2_lib.baseboard_fab2(sch_1):page247_i3:b" )
			)
			( pin "R6W4.1"
				( objectStatus "@baseboard_fab2_lib.baseboard_fab2(sch_1):page247_i5:a" )
			)
			( pin "R6W4.2"
				( objectStatus "@baseboard_fab2_lib.baseboard_fab2(sch_1):page247_i5:b" )
			)
			( pin "R6W8.1"
				( objectStatus "@baseboard_fab2_lib.baseboard_fab2(sch_1):page247_i8:a" )
			)
			( pin "R6W8.2"
				( objectStatus "@baseboard_fab2_lib.baseboard_fab2(sch_1):page247_i8:b" )
			)
			( pin "R6W9.1"
				( objectStatus "@baseboard_fab2_lib.baseboard_fab2(sch_1):page247_i9:a" )
			)
			( pin "R6W9.2"
				( objectStatus "@baseboard_fab2_lib.baseboard_fab2(sch_1):page247_i9:b" )
			)
			( pin "R6W5.1"
				( objectStatus "@baseboard_fab2_lib.baseboard_fab2(sch_1):page247_i10:a" )
			)
			( pin "R6W5.2"
				( objectStatus "@baseboard_fab2_lib.baseboard_fab2(sch_1):page247_i10:b" )
			)
			( pin "R6W6.1"
				( objectStatus "@baseboard_fab2_lib.baseboard_fab2(sch_1):page247_i11:a" )
			)
			( pin "R6W6.2"
				( objectStatus "@baseboard_fab2_lib.baseboard_fab2(sch_1):page247_i11:b" )
			)
			( pin "R25W63.1"
				( objectStatus "@baseboard_fab2_lib.baseboard_fab2(sch_1):page146_i65:a" )
			)
			( pin "R25W63.2"
				( objectStatus "@baseboard_fab2_lib.baseboard_fab2(sch_1):page146_i65:b" )
			)
			( pin "C6W1.1"
				( objectStatus "@baseboard_fab2_lib.baseboard_fab2(sch_1):page247_i18:a" )
			)
			( pin "C6W1.2"
				( objectStatus "@baseboard_fab2_lib.baseboard_fab2(sch_1):page247_i18:b" )
			)
			( pin "Q6W2.6"
				( objectStatus "@baseboard_fab2_lib.baseboard_fab2(sch_1):page168_i30:drain(0)" )
			)
			( pin "Q6W2.2"
				( objectStatus "@baseboard_fab2_lib.baseboard_fab2(sch_1):page168_i30:gate(0)" )
			)
			( pin "Q6W2.1"
				( objectStatus "@baseboard_fab2_lib.baseboard_fab2(sch_1):page168_i30:source(0)" )
			)
			( pin "R6W14.1"
				( objectStatus "@baseboard_fab2_lib.baseboard_fab2(sch_1):page168_i33:a" )
			)
			( pin "R6W14.2"
				( objectStatus "@baseboard_fab2_lib.baseboard_fab2(sch_1):page168_i33:b" )
			)
			( pin "R6W13.1"
				( objectStatus "@baseboard_fab2_lib.baseboard_fab2(sch_1):page168_i34:a" )
			)
			( pin "R6W13.2"
				( objectStatus "@baseboard_fab2_lib.baseboard_fab2(sch_1):page168_i34:b" )
			)
			( pin "Q6W3.1"
				( objectStatus "@baseboard_fab2_lib.baseboard_fab2(sch_1):page168_i37:b" )
			)
			( pin "Q6W3.3"
				( objectStatus "@baseboard_fab2_lib.baseboard_fab2(sch_1):page168_i37:c" )
			)
			( pin "Q6W3.2"
				( objectStatus "@baseboard_fab2_lib.baseboard_fab2(sch_1):page168_i37:e" )
			)
			( pin "R6W16.1"
				( objectStatus "@baseboard_fab2_lib.baseboard_fab2(sch_1):page168_i39:a" )
			)
			( pin "R6W16.2"
				( objectStatus "@baseboard_fab2_lib.baseboard_fab2(sch_1):page168_i39:b" )
			)
			( pin "R6W15.1"
				( objectStatus "@baseboard_fab2_lib.baseboard_fab2(sch_1):page168_i40:a" )
			)
			( pin "R6W15.2"
				( objectStatus "@baseboard_fab2_lib.baseboard_fab2(sch_1):page168_i40:b" )
			)
			( pin "R9W31.1"
				( objectStatus "@baseboard_fab2_lib.baseboard_fab2(sch_1):page239_i99:\1\" )
			)
			( pin "R9W31.2"
				( objectStatus "@baseboard_fab2_lib.baseboard_fab2(sch_1):page239_i99:\2\" )
			)
			( pin "R3W1.1"
				( objectStatus "@baseboard_fab2_lib.baseboard_fab2(sch_1):page249_i2:a" )
			)
			( pin "R3W1.2"
				( objectStatus "@baseboard_fab2_lib.baseboard_fab2(sch_1):page249_i2:b" )
			)
			( pin "R3W9.1"
				( objectStatus "@baseboard_fab2_lib.baseboard_fab2(sch_1):page249_i7:a" )
			)
			( pin "R3W9.2"
				( objectStatus "@baseboard_fab2_lib.baseboard_fab2(sch_1):page249_i7:b" )
			)
			( pin "R3W7.1"
				( objectStatus "@baseboard_fab2_lib.baseboard_fab2(sch_1):page249_i8:a" )
			)
			( pin "R3W7.2"
				( objectStatus "@baseboard_fab2_lib.baseboard_fab2(sch_1):page249_i8:b" )
			)
			( pin "R3W2.1"
				( objectStatus "@baseboard_fab2_lib.baseboard_fab2(sch_1):page249_i12:a" )
			)
			( pin "R3W2.2"
				( objectStatus "@baseboard_fab2_lib.baseboard_fab2(sch_1):page249_i12:b" )
			)
			( pin "R3W4.1"
				( objectStatus "@baseboard_fab2_lib.baseboard_fab2(sch_1):page249_i31:\1\" )
			)
			( pin "R3W4.2"
				( objectStatus "@baseboard_fab2_lib.baseboard_fab2(sch_1):page249_i31:\2\" )
			)
			( pin "Q9W4.1"
				( objectStatus "@baseboard_fab2_lib.baseboard_fab2(sch_1):page249_i15:\+in\" )
			)
			( pin "Q9W4.3"
				( objectStatus "@baseboard_fab2_lib.baseboard_fab2(sch_1):page249_i15:\-in\" )
			)
			( pin "Q9W4.2"
				( objectStatus "@baseboard_fab2_lib.baseboard_fab2(sch_1):page249_i15:gnd" )
			)
			( pin "Q9W4.4"
				( objectStatus "@baseboard_fab2_lib.baseboard_fab2(sch_1):page249_i15:\out\" )
			)
			( pin "Q9W4.5"
				( objectStatus "@baseboard_fab2_lib.baseboard_fab2(sch_1):page249_i15:vcc" )
			)
			( pin "R3W3.1"
				( objectStatus "@baseboard_fab2_lib.baseboard_fab2(sch_1):page249_i17:a" )
			)
			( pin "R3W3.2"
				( objectStatus "@baseboard_fab2_lib.baseboard_fab2(sch_1):page249_i17:b" )
			)
			( pin "C8W2.1"
				( objectStatus "@baseboard_fab2_lib.baseboard_fab2(sch_1):page249_i21:a" )
			)
			( pin "C8W2.2"
				( objectStatus "@baseboard_fab2_lib.baseboard_fab2(sch_1):page249_i21:b" )
			)
			( pin "Q9W3.1"
				( objectStatus "@baseboard_fab2_lib.baseboard_fab2(sch_1):page249_i26:b" )
			)
			( pin "Q9W3.3"
				( objectStatus "@baseboard_fab2_lib.baseboard_fab2(sch_1):page249_i26:c" )
			)
			( pin "Q9W3.2"
				( objectStatus "@baseboard_fab2_lib.baseboard_fab2(sch_1):page249_i26:e" )
			)
			( pin "R3W6.1"
				( objectStatus "@baseboard_fab2_lib.baseboard_fab2(sch_1):page249_i27:a" )
			)
			( pin "R3W6.2"
				( objectStatus "@baseboard_fab2_lib.baseboard_fab2(sch_1):page249_i27:b" )
			)
			( pin "Q9W2.1"
				( objectStatus "@baseboard_fab2_lib.baseboard_fab2(sch_1):page249_i29:b" )
			)
			( pin "Q9W2.3"
				( objectStatus "@baseboard_fab2_lib.baseboard_fab2(sch_1):page249_i29:c" )
			)
			( pin "Q9W2.2"
				( objectStatus "@baseboard_fab2_lib.baseboard_fab2(sch_1):page249_i29:e" )
			)
			( pin "R6W3.1"
				( objectStatus "@baseboard_fab2_lib.baseboard_fab2(sch_1):page200_i239:\1\" )
			)
			( pin "R6W3.2"
				( objectStatus "@baseboard_fab2_lib.baseboard_fab2(sch_1):page200_i239:\2\" )
			)
			( pin "C25W41.1"
				( objectStatus "@baseboard_fab2_lib.baseboard_fab2(sch_1):page150_i81:a" )
			)
			( pin "C25W41.2"
				( objectStatus "@baseboard_fab2_lib.baseboard_fab2(sch_1):page150_i81:b" )
			)
			( pin "C25W42.1"
				( objectStatus "@baseboard_fab2_lib.baseboard_fab2(sch_1):page150_i80:a" )
			)
			( pin "C25W42.2"
				( objectStatus "@baseboard_fab2_lib.baseboard_fab2(sch_1):page150_i80:b" )
			)
			( pin "C25W31.1"
				( objectStatus "@baseboard_fab2_lib.baseboard_fab2(sch_1):page150_i79:\1\" )
			)
			( pin "C25W31.2"
				( objectStatus "@baseboard_fab2_lib.baseboard_fab2(sch_1):page150_i79:\2\" )
			)
			( pin "C25W32.1"
				( objectStatus "@baseboard_fab2_lib.baseboard_fab2(sch_1):page150_i78:a" )
			)
			( pin "C25W32.2"
				( objectStatus "@baseboard_fab2_lib.baseboard_fab2(sch_1):page150_i78:b" )
			)
			( pin "R25W35.1"
				( objectStatus "@baseboard_fab2_lib.baseboard_fab2(sch_1):page149_i194:\1\" )
			)
			( pin "R25W35.2"
				( objectStatus "@baseboard_fab2_lib.baseboard_fab2(sch_1):page149_i194:\2\" )
			)
			( pin "R25W67.1"
				( objectStatus "@baseboard_fab2_lib.baseboard_fab2(sch_1):page145_i46:a" )
			)
			( pin "R25W67.2"
				( objectStatus "@baseboard_fab2_lib.baseboard_fab2(sch_1):page145_i46:b" )
			)
			( pin "C25W20.1"
				( objectStatus "@baseboard_fab2_lib.baseboard_fab2(sch_1):page145_i45:a" )
			)
			( pin "C25W20.2"
				( objectStatus "@baseboard_fab2_lib.baseboard_fab2(sch_1):page145_i45:b" )
			)
			( pin "C25W21.1"
				( objectStatus "@baseboard_fab2_lib.baseboard_fab2(sch_1):page145_i44:a" )
			)
			( pin "C25W21.2"
				( objectStatus "@baseboard_fab2_lib.baseboard_fab2(sch_1):page145_i44:b" )
			)
			( pin "R25W65.1"
				( objectStatus "@baseboard_fab2_lib.baseboard_fab2(sch_1):page145_i38:a" )
			)
			( pin "R25W65.2"
				( objectStatus "@baseboard_fab2_lib.baseboard_fab2(sch_1):page145_i38:b" )
			)
			( pin "R25W64.1"
				( objectStatus "@baseboard_fab2_lib.baseboard_fab2(sch_1):page145_i36:a" )
			)
			( pin "R25W64.2"
				( objectStatus "@baseboard_fab2_lib.baseboard_fab2(sch_1):page145_i36:b" )
			)
			( pin "R25W34.1"
				( objectStatus "@baseboard_fab2_lib.baseboard_fab2(sch_1):page149_i193:\1\" )
			)
			( pin "R25W34.2"
				( objectStatus "@baseboard_fab2_lib.baseboard_fab2(sch_1):page149_i193:\2\" )
			)
			( pin "R25W33.1"
				( objectStatus "@baseboard_fab2_lib.baseboard_fab2(sch_1):page149_i192:\1\" )
			)
			( pin "R25W33.2"
				( objectStatus "@baseboard_fab2_lib.baseboard_fab2(sch_1):page149_i192:\2\" )
			)
			( pin "R25W32.1"
				( objectStatus "@baseboard_fab2_lib.baseboard_fab2(sch_1):page149_i191:\1\" )
			)
			( pin "R25W32.2"
				( objectStatus "@baseboard_fab2_lib.baseboard_fab2(sch_1):page149_i191:\2\" )
			)
			( pin "C9F23.1"
				( objectStatus "@baseboard_fab2_lib.baseboard_fab2(sch_1):page145_i15:a" )
			)
			( pin "C9F23.2"
				( objectStatus "@baseboard_fab2_lib.baseboard_fab2(sch_1):page145_i15:b" )
			)
			( pin "R9F33.1"
				( objectStatus "@baseboard_fab2_lib.baseboard_fab2(sch_1):page145_i20:a" )
			)
			( pin "R9F33.2"
				( objectStatus "@baseboard_fab2_lib.baseboard_fab2(sch_1):page145_i20:b" )
			)
			( pin "R9F34.1"
				( objectStatus "@baseboard_fab2_lib.baseboard_fab2(sch_1):page149_i14:a" )
			)
			( pin "R9F34.2"
				( objectStatus "@baseboard_fab2_lib.baseboard_fab2(sch_1):page149_i14:b" )
			)
			( pin "R1U52.1"
				( objectStatus "@baseboard_fab2_lib.baseboard_fab2(sch_1):page146_i51:a" )
			)
			( pin "R1U52.2"
				( objectStatus "@baseboard_fab2_lib.baseboard_fab2(sch_1):page146_i51:b" )
			)
			( pin "R25W58.1"
				( objectStatus "@baseboard_fab2_lib.baseboard_fab2(sch_1):page144_i73:a" )
			)
			( pin "R25W58.2"
				( objectStatus "@baseboard_fab2_lib.baseboard_fab2(sch_1):page144_i73:b" )
			)
			( pin "C25W7.1"
				( objectStatus "@baseboard_fab2_lib.baseboard_fab2(sch_1):page147_i36:a" )
			)
			( pin "C25W7.2"
				( objectStatus "@baseboard_fab2_lib.baseboard_fab2(sch_1):page147_i36:b" )
			)
			( pin "R25W61.1"
				( objectStatus "@baseboard_fab2_lib.baseboard_fab2(sch_1):page145_i30:a" )
			)
			( pin "R25W61.2"
				( objectStatus "@baseboard_fab2_lib.baseboard_fab2(sch_1):page145_i30:b" )
			)
			( pin "R25W62.1"
				( objectStatus "@baseboard_fab2_lib.baseboard_fab2(sch_1):page145_i31:a" )
			)
			( pin "R25W62.2"
				( objectStatus "@baseboard_fab2_lib.baseboard_fab2(sch_1):page145_i31:b" )
			)
			( pin "C25W30.1"
				( objectStatus "@baseboard_fab2_lib.baseboard_fab2(sch_1):page150_i43:\1\" )
			)
			( pin "C25W30.2"
				( objectStatus "@baseboard_fab2_lib.baseboard_fab2(sch_1):page150_i43:\2\" )
			)
			( pin "FB2T7.1"
				( objectStatus "@baseboard_fab2_lib.baseboard_fab2(sch_1):page150_i39:\1\" )
			)
			( pin "FB2T7.2"
				( objectStatus "@baseboard_fab2_lib.baseboard_fab2(sch_1):page150_i39:\2\" )
			)
			( pin "C25W48.1"
				( objectStatus "@baseboard_fab2_lib.baseboard_fab2(sch_1):page150_i38:a" )
			)
			( pin "C25W48.2"
				( objectStatus "@baseboard_fab2_lib.baseboard_fab2(sch_1):page150_i38:b" )
			)
			( pin "C25W49.1"
				( objectStatus "@baseboard_fab2_lib.baseboard_fab2(sch_1):page150_i36:\1\" )
			)
			( pin "C25W49.2"
				( objectStatus "@baseboard_fab2_lib.baseboard_fab2(sch_1):page150_i36:\2\" )
			)
			( pin "C25W37.1"
				( objectStatus "@baseboard_fab2_lib.baseboard_fab2(sch_1):page150_i35:a" )
			)
			( pin "C25W37.2"
				( objectStatus "@baseboard_fab2_lib.baseboard_fab2(sch_1):page150_i35:b" )
			)
			( pin "C25W66.1"
				( objectStatus "@baseboard_fab2_lib.baseboard_fab2(sch_1):page150_i33:a" )
			)
			( pin "C25W66.2"
				( objectStatus "@baseboard_fab2_lib.baseboard_fab2(sch_1):page150_i33:b" )
			)
			( pin "FB2T1.1"
				( objectStatus "@baseboard_fab2_lib.baseboard_fab2(sch_1):page150_i32:\1\" )
			)
			( pin "FB2T1.2"
				( objectStatus "@baseboard_fab2_lib.baseboard_fab2(sch_1):page150_i32:\2\" )
			)
			( pin "R25W94.1"
				( objectStatus "@baseboard_fab2_lib.baseboard_fab2(sch_1):page151_i9:a" )
			)
			( pin "R25W94.2"
				( objectStatus "@baseboard_fab2_lib.baseboard_fab2(sch_1):page151_i9:b" )
			)
			( pin "C25W67.1"
				( objectStatus "@baseboard_fab2_lib.baseboard_fab2(sch_1):page150_i31:a" )
			)
			( pin "C25W67.2"
				( objectStatus "@baseboard_fab2_lib.baseboard_fab2(sch_1):page150_i31:b" )
			)
			( pin "C25W68.1"
				( objectStatus "@baseboard_fab2_lib.baseboard_fab2(sch_1):page150_i30:\1\" )
			)
			( pin "C25W68.2"
				( objectStatus "@baseboard_fab2_lib.baseboard_fab2(sch_1):page150_i30:\2\" )
			)
			( pin "R25W96.1"
				( objectStatus "@baseboard_fab2_lib.baseboard_fab2(sch_1):page151_i10:a" )
			)
			( pin "R25W96.2"
				( objectStatus "@baseboard_fab2_lib.baseboard_fab2(sch_1):page151_i10:b" )
			)
			( pin "C25W69.1"
				( objectStatus "@baseboard_fab2_lib.baseboard_fab2(sch_1):page150_i28:\1\" )
			)
			( pin "C25W69.2"
				( objectStatus "@baseboard_fab2_lib.baseboard_fab2(sch_1):page150_i28:\2\" )
			)
			( pin "FB2T6.1"
				( objectStatus "@baseboard_fab2_lib.baseboard_fab2(sch_1):page150_i26:\1\" )
			)
			( pin "FB2T6.2"
				( objectStatus "@baseboard_fab2_lib.baseboard_fab2(sch_1):page150_i26:\2\" )
			)
			( pin "C25W63.1"
				( objectStatus "@baseboard_fab2_lib.baseboard_fab2(sch_1):page150_i25:a" )
			)
			( pin "C25W63.2"
				( objectStatus "@baseboard_fab2_lib.baseboard_fab2(sch_1):page150_i25:b" )
			)
			( pin "C25W64.1"
				( objectStatus "@baseboard_fab2_lib.baseboard_fab2(sch_1):page150_i24:\1\" )
			)
			( pin "C25W64.2"
				( objectStatus "@baseboard_fab2_lib.baseboard_fab2(sch_1):page150_i24:\2\" )
			)
			( pin "C25W50.1"
				( objectStatus "@baseboard_fab2_lib.baseboard_fab2(sch_1):page150_i21:\1\" )
			)
			( pin "C25W50.2"
				( objectStatus "@baseboard_fab2_lib.baseboard_fab2(sch_1):page150_i21:\2\" )
			)
			( pin "C25W51.1"
				( objectStatus "@baseboard_fab2_lib.baseboard_fab2(sch_1):page150_i19:a" )
			)
			( pin "C25W51.2"
				( objectStatus "@baseboard_fab2_lib.baseboard_fab2(sch_1):page150_i19:b" )
			)
			( pin "C25W38.1"
				( objectStatus "@baseboard_fab2_lib.baseboard_fab2(sch_1):page150_i18:\1\" )
			)
			( pin "C25W38.2"
				( objectStatus "@baseboard_fab2_lib.baseboard_fab2(sch_1):page150_i18:\2\" )
			)
			( pin "C25W39.1"
				( objectStatus "@baseboard_fab2_lib.baseboard_fab2(sch_1):page150_i17:\1\" )
			)
			( pin "C25W39.2"
				( objectStatus "@baseboard_fab2_lib.baseboard_fab2(sch_1):page150_i17:\2\" )
			)
			( pin "C25W52.1"
				( objectStatus "@baseboard_fab2_lib.baseboard_fab2(sch_1):page150_i14:a" )
			)
			( pin "C25W52.2"
				( objectStatus "@baseboard_fab2_lib.baseboard_fab2(sch_1):page150_i14:b" )
			)
			( pin "C25W53.1"
				( objectStatus "@baseboard_fab2_lib.baseboard_fab2(sch_1):page150_i13:a" )
			)
			( pin "C25W53.2"
				( objectStatus "@baseboard_fab2_lib.baseboard_fab2(sch_1):page150_i13:b" )
			)
			( pin "C25W54.1"
				( objectStatus "@baseboard_fab2_lib.baseboard_fab2(sch_1):page150_i12:a" )
			)
			( pin "C25W54.2"
				( objectStatus "@baseboard_fab2_lib.baseboard_fab2(sch_1):page150_i12:b" )
			)
			( pin "C25W55.1"
				( objectStatus "@baseboard_fab2_lib.baseboard_fab2(sch_1):page150_i10:\1\" )
			)
			( pin "C25W55.2"
				( objectStatus "@baseboard_fab2_lib.baseboard_fab2(sch_1):page150_i10:\2\" )
			)
			( pin "R25W120.1"
				( objectStatus "@baseboard_fab2_lib.baseboard_fab2(sch_1):page150_i7:\1\" )
			)
			( pin "R25W120.2"
				( objectStatus "@baseboard_fab2_lib.baseboard_fab2(sch_1):page150_i7:\2\" )
			)
			( pin "C25W70.1"
				( objectStatus "@baseboard_fab2_lib.baseboard_fab2(sch_1):page150_i6:\1\" )
			)
			( pin "C25W70.2"
				( objectStatus "@baseboard_fab2_lib.baseboard_fab2(sch_1):page150_i6:\2\" )
			)
			( pin "R25W116.1"
				( objectStatus "@baseboard_fab2_lib.baseboard_fab2(sch_1):page151_i48:a" )
			)
			( pin "R25W116.2"
				( objectStatus "@baseboard_fab2_lib.baseboard_fab2(sch_1):page151_i48:b" )
			)
			( pin "R25W115.1"
				( objectStatus "@baseboard_fab2_lib.baseboard_fab2(sch_1):page151_i47:a" )
			)
			( pin "R25W115.2"
				( objectStatus "@baseboard_fab2_lib.baseboard_fab2(sch_1):page151_i47:b" )
			)
			( pin "R25W114.1"
				( objectStatus "@baseboard_fab2_lib.baseboard_fab2(sch_1):page151_i46:a" )
			)
			( pin "R25W114.2"
				( objectStatus "@baseboard_fab2_lib.baseboard_fab2(sch_1):page151_i46:b" )
			)
			( pin "R25W113.1"
				( objectStatus "@baseboard_fab2_lib.baseboard_fab2(sch_1):page151_i45:a" )
			)
			( pin "R25W113.2"
				( objectStatus "@baseboard_fab2_lib.baseboard_fab2(sch_1):page151_i45:b" )
			)
			( pin "R25W112.1"
				( objectStatus "@baseboard_fab2_lib.baseboard_fab2(sch_1):page151_i44:a" )
			)
			( pin "R25W112.2"
				( objectStatus "@baseboard_fab2_lib.baseboard_fab2(sch_1):page151_i44:b" )
			)
			( pin "R25W111.1"
				( objectStatus "@baseboard_fab2_lib.baseboard_fab2(sch_1):page151_i43:a" )
			)
			( pin "R25W111.2"
				( objectStatus "@baseboard_fab2_lib.baseboard_fab2(sch_1):page151_i43:b" )
			)
			( pin "R25W110.1"
				( objectStatus "@baseboard_fab2_lib.baseboard_fab2(sch_1):page151_i36:a" )
			)
			( pin "R25W110.2"
				( objectStatus "@baseboard_fab2_lib.baseboard_fab2(sch_1):page151_i36:b" )
			)
			( pin "R25W109.1"
				( objectStatus "@baseboard_fab2_lib.baseboard_fab2(sch_1):page151_i35:a" )
			)
			( pin "R25W109.2"
				( objectStatus "@baseboard_fab2_lib.baseboard_fab2(sch_1):page151_i35:b" )
			)
			( pin "R25W108.1"
				( objectStatus "@baseboard_fab2_lib.baseboard_fab2(sch_1):page151_i34:a" )
			)
			( pin "R25W108.2"
				( objectStatus "@baseboard_fab2_lib.baseboard_fab2(sch_1):page151_i34:b" )
			)
			( pin "R25W107.1"
				( objectStatus "@baseboard_fab2_lib.baseboard_fab2(sch_1):page151_i33:a" )
			)
			( pin "R25W107.2"
				( objectStatus "@baseboard_fab2_lib.baseboard_fab2(sch_1):page151_i33:b" )
			)
			( pin "R25W106.1"
				( objectStatus "@baseboard_fab2_lib.baseboard_fab2(sch_1):page151_i32:a" )
			)
			( pin "R25W106.2"
				( objectStatus "@baseboard_fab2_lib.baseboard_fab2(sch_1):page151_i32:b" )
			)
			( pin "R25W105.1"
				( objectStatus "@baseboard_fab2_lib.baseboard_fab2(sch_1):page151_i31:a" )
			)
			( pin "R25W105.2"
				( objectStatus "@baseboard_fab2_lib.baseboard_fab2(sch_1):page151_i31:b" )
			)
			( pin "R25W104.1"
				( objectStatus "@baseboard_fab2_lib.baseboard_fab2(sch_1):page151_i30:a" )
			)
			( pin "R25W104.2"
				( objectStatus "@baseboard_fab2_lib.baseboard_fab2(sch_1):page151_i30:b" )
			)
			( pin "R25W103.1"
				( objectStatus "@baseboard_fab2_lib.baseboard_fab2(sch_1):page151_i29:a" )
			)
			( pin "R25W103.2"
				( objectStatus "@baseboard_fab2_lib.baseboard_fab2(sch_1):page151_i29:b" )
			)
			( pin "R25W102.1"
				( objectStatus "@baseboard_fab2_lib.baseboard_fab2(sch_1):page151_i28:a" )
			)
			( pin "R25W102.2"
				( objectStatus "@baseboard_fab2_lib.baseboard_fab2(sch_1):page151_i28:b" )
			)
			( pin "R25W101.1"
				( objectStatus "@baseboard_fab2_lib.baseboard_fab2(sch_1):page151_i27:a" )
			)
			( pin "R25W101.2"
				( objectStatus "@baseboard_fab2_lib.baseboard_fab2(sch_1):page151_i27:b" )
			)
			( pin "R25W99.1"
				( objectStatus "@baseboard_fab2_lib.baseboard_fab2(sch_1):page151_i14:a" )
			)
			( pin "R25W99.2"
				( objectStatus "@baseboard_fab2_lib.baseboard_fab2(sch_1):page151_i14:b" )
			)
			( pin "FB2T5.1"
				( objectStatus "@baseboard_fab2_lib.baseboard_fab2(sch_1):page150_i89:\1\" )
			)
			( pin "FB2T5.2"
				( objectStatus "@baseboard_fab2_lib.baseboard_fab2(sch_1):page150_i89:\2\" )
			)
			( pin "C25W56.1"
				( objectStatus "@baseboard_fab2_lib.baseboard_fab2(sch_1):page150_i87:a" )
			)
			( pin "C25W56.2"
				( objectStatus "@baseboard_fab2_lib.baseboard_fab2(sch_1):page150_i87:b" )
			)
			( pin "C25W57.1"
				( objectStatus "@baseboard_fab2_lib.baseboard_fab2(sch_1):page150_i86:a" )
			)
			( pin "C25W57.2"
				( objectStatus "@baseboard_fab2_lib.baseboard_fab2(sch_1):page150_i86:b" )
			)
			( pin "C25W58.1"
				( objectStatus "@baseboard_fab2_lib.baseboard_fab2(sch_1):page150_i85:\1\" )
			)
			( pin "C25W58.2"
				( objectStatus "@baseboard_fab2_lib.baseboard_fab2(sch_1):page150_i85:\2\" )
			)
			( pin "FB2T4.1"
				( objectStatus "@baseboard_fab2_lib.baseboard_fab2(sch_1):page150_i84:\1\" )
			)
			( pin "FB2T4.2"
				( objectStatus "@baseboard_fab2_lib.baseboard_fab2(sch_1):page150_i84:\2\" )
			)
			( pin "R6W19.1"
				( objectStatus "@baseboard_fab2_lib.baseboard_fab2(sch_1):page155_i196:a" )
			)
			( pin "R6W19.2"
				( objectStatus "@baseboard_fab2_lib.baseboard_fab2(sch_1):page155_i196:b" )
			)
			( pin "R25W82.1"
				( objectStatus "@baseboard_fab2_lib.baseboard_fab2(sch_1):page146_i68:a" )
			)
			( pin "R25W82.2"
				( objectStatus "@baseboard_fab2_lib.baseboard_fab2(sch_1):page146_i68:b" )
			)
			( pin "U25W5.P3"
				( objectStatus "@baseboard_fab2_lib.baseboard_fab2(sch_1):page149_i1:a0" )
			)
			( pin "U25W5.P7"
				( objectStatus "@baseboard_fab2_lib.baseboard_fab2(sch_1):page149_i1:a1" )
			)
			( pin "U25W5.R3"
				( objectStatus "@baseboard_fab2_lib.baseboard_fab2(sch_1):page149_i1:a2" )
			)
			( pin "U25W5.N7"
				( objectStatus "@baseboard_fab2_lib.baseboard_fab2(sch_1):page149_i1:a3" )
			)
			( pin "U25W5.N3"
				( objectStatus "@baseboard_fab2_lib.baseboard_fab2(sch_1):page149_i1:a4" )
			)
			( pin "U25W5.P8"
				( objectStatus "@baseboard_fab2_lib.baseboard_fab2(sch_1):page149_i1:a5" )
			)
			( pin "U25W5.P2"
				( objectStatus "@baseboard_fab2_lib.baseboard_fab2(sch_1):page149_i1:a6" )
			)
			( pin "U25W5.R8"
				( objectStatus "@baseboard_fab2_lib.baseboard_fab2(sch_1):page149_i1:a7" )
			)
			( pin "U25W5.R2"
				( objectStatus "@baseboard_fab2_lib.baseboard_fab2(sch_1):page149_i1:a8" )
			)
			( pin "U25W5.R7"
				( objectStatus "@baseboard_fab2_lib.baseboard_fab2(sch_1):page149_i1:a9" )
			)
			( pin "U25W5.M3"
				( objectStatus "@baseboard_fab2_lib.baseboard_fab2(sch_1):page149_i1:\a10/ap\" )
			)
			( pin "U25W5.T2"
				( objectStatus "@baseboard_fab2_lib.baseboard_fab2(sch_1):page149_i1:a11" )
			)
			( pin "U25W5.M7"
				( objectStatus "@baseboard_fab2_lib.baseboard_fab2(sch_1):page149_i1:\a12/bc#\" )
			)
			( pin "U25W5.T8"
				( objectStatus "@baseboard_fab2_lib.baseboard_fab2(sch_1):page149_i1:a13" )
			)
			( pin "U25W5.L3"
				( objectStatus "@baseboard_fab2_lib.baseboard_fab2(sch_1):page149_i1:\act#\" )
			)
			( pin "U25W5.P9"
				( objectStatus "@baseboard_fab2_lib.baseboard_fab2(sch_1):page149_i1:\alert#\" )
			)
			( pin "U25W5.N2"
				( objectStatus "@baseboard_fab2_lib.baseboard_fab2(sch_1):page149_i1:ba0" )
			)
			( pin "U25W5.N8"
				( objectStatus "@baseboard_fab2_lib.baseboard_fab2(sch_1):page149_i1:ba1" )
			)
			( pin "U25W5.M2"
				( objectStatus "@baseboard_fab2_lib.baseboard_fab2(sch_1):page149_i1:bg0" )
			)
			( pin "U25W5.M8"
				( objectStatus "@baseboard_fab2_lib.baseboard_fab2(sch_1):page149_i1:\cas#/a15\" )
			)
			( pin "U25W5.K8"
				( objectStatus "@baseboard_fab2_lib.baseboard_fab2(sch_1):page149_i1:ck_c" )
			)
			( pin "U25W5.K7"
				( objectStatus "@baseboard_fab2_lib.baseboard_fab2(sch_1):page149_i1:ck_t" )
			)
			( pin "U25W5.K2"
				( objectStatus "@baseboard_fab2_lib.baseboard_fab2(sch_1):page149_i1:cke" )
			)
			( pin "U25W5.L7"
				( objectStatus "@baseboard_fab2_lib.baseboard_fab2(sch_1):page149_i1:\cs#\" )
			)
			( pin "U25W5.E7"
				( objectStatus "@baseboard_fab2_lib.baseboard_fab2(sch_1):page149_i1:\dml#/dbil#\" )
			)
			( pin "U25W5.E2"
				( objectStatus "@baseboard_fab2_lib.baseboard_fab2(sch_1):page149_i1:\dmu#/dbiu#\" )
			)
			( pin "U25W5.G2"
				( objectStatus "@baseboard_fab2_lib.baseboard_fab2(sch_1):page149_i1:dql0" )
			)
			( pin "U25W5.F7"
				( objectStatus "@baseboard_fab2_lib.baseboard_fab2(sch_1):page149_i1:dql1" )
			)
			( pin "U25W5.H3"
				( objectStatus "@baseboard_fab2_lib.baseboard_fab2(sch_1):page149_i1:dql2" )
			)
			( pin "U25W5.H7"
				( objectStatus "@baseboard_fab2_lib.baseboard_fab2(sch_1):page149_i1:dql3" )
			)
			( pin "U25W5.H2"
				( objectStatus "@baseboard_fab2_lib.baseboard_fab2(sch_1):page149_i1:dql4" )
			)
			( pin "U25W5.H8"
				( objectStatus "@baseboard_fab2_lib.baseboard_fab2(sch_1):page149_i1:dql5" )
			)
			( pin "U25W5.J3"
				( objectStatus "@baseboard_fab2_lib.baseboard_fab2(sch_1):page149_i1:dql6" )
			)
			( pin "U25W5.J7"
				( objectStatus "@baseboard_fab2_lib.baseboard_fab2(sch_1):page149_i1:dql7" )
			)
			( pin "U25W5.F3"
				( objectStatus "@baseboard_fab2_lib.baseboard_fab2(sch_1):page149_i1:dqsl_c" )
			)
			( pin "U25W5.G3"
				( objectStatus "@baseboard_fab2_lib.baseboard_fab2(sch_1):page149_i1:dqsl_t" )
			)
			( pin "U25W5.A7"
				( objectStatus "@baseboard_fab2_lib.baseboard_fab2(sch_1):page149_i1:dqsu_c" )
			)
			( pin "U25W5.B7"
				( objectStatus "@baseboard_fab2_lib.baseboard_fab2(sch_1):page149_i1:dqsu_t" )
			)
			( pin "U25W5.A3"
				( objectStatus "@baseboard_fab2_lib.baseboard_fab2(sch_1):page149_i1:dqu0" )
			)
			( pin "U25W5.B8"
				( objectStatus "@baseboard_fab2_lib.baseboard_fab2(sch_1):page149_i1:dqu1" )
			)
			( pin "U25W5.C3"
				( objectStatus "@baseboard_fab2_lib.baseboard_fab2(sch_1):page149_i1:dqu2" )
			)
			( pin "U25W5.C7"
				( objectStatus "@baseboard_fab2_lib.baseboard_fab2(sch_1):page149_i1:dqu3" )
			)
			( pin "U25W5.C2"
				( objectStatus "@baseboard_fab2_lib.baseboard_fab2(sch_1):page149_i1:dqu4" )
			)
			( pin "U25W5.C8"
				( objectStatus "@baseboard_fab2_lib.baseboard_fab2(sch_1):page149_i1:dqu5" )
			)
			( pin "U25W5.D3"
				( objectStatus "@baseboard_fab2_lib.baseboard_fab2(sch_1):page149_i1:dqu6" )
			)
			( pin "U25W5.D7"
				( objectStatus "@baseboard_fab2_lib.baseboard_fab2(sch_1):page149_i1:dqu7" )
			)
			( pin "U25W5.T7"
				( objectStatus "@baseboard_fab2_lib.baseboard_fab2(sch_1):page149_i1:\nc#t7\" )
			)
			( pin "U25W5.K3"
				( objectStatus "@baseboard_fab2_lib.baseboard_fab2(sch_1):page149_i1:odt" )
			)
			( pin "U25W5.T3"
				( objectStatus "@baseboard_fab2_lib.baseboard_fab2(sch_1):page149_i1:par" )
			)
			( pin "U25W5.L8"
				( objectStatus "@baseboard_fab2_lib.baseboard_fab2(sch_1):page149_i1:\ras#/a16\" )
			)
			( pin "U25W5.P1"
				( objectStatus "@baseboard_fab2_lib.baseboard_fab2(sch_1):page149_i1:\reset#\" )
			)
			( pin "U25W5.N9"
				( objectStatus "@baseboard_fab2_lib.baseboard_fab2(sch_1):page149_i1:ten" )
			)
			( pin "U25W5.B3"
				( objectStatus "@baseboard_fab2_lib.baseboard_fab2(sch_1):page149_i1:vdd(0)" )
			)
			( pin "U25W5.B9"
				( objectStatus "@baseboard_fab2_lib.baseboard_fab2(sch_1):page149_i1:vdd(1)" )
			)
			( pin "U25W5.D1"
				( objectStatus "@baseboard_fab2_lib.baseboard_fab2(sch_1):page149_i1:vdd(2)" )
			)
			( pin "U25W5.G7"
				( objectStatus "@baseboard_fab2_lib.baseboard_fab2(sch_1):page149_i1:vdd(3)" )
			)
			( pin "U25W5.J1"
				( objectStatus "@baseboard_fab2_lib.baseboard_fab2(sch_1):page149_i1:vdd(4)" )
			)
			( pin "U25W5.J9"
				( objectStatus "@baseboard_fab2_lib.baseboard_fab2(sch_1):page149_i1:vdd(5)" )
			)
			( pin "U25W5.L1"
				( objectStatus "@baseboard_fab2_lib.baseboard_fab2(sch_1):page149_i1:vdd(6)" )
			)
			( pin "U25W5.L9"
				( objectStatus "@baseboard_fab2_lib.baseboard_fab2(sch_1):page149_i1:vdd(7)" )
			)
			( pin "U25W5.R1"
				( objectStatus "@baseboard_fab2_lib.baseboard_fab2(sch_1):page149_i1:vdd(8)" )
			)
			( pin "U25W5.T9"
				( objectStatus "@baseboard_fab2_lib.baseboard_fab2(sch_1):page149_i1:vdd(9)" )
			)
			( pin "U25W5.A1"
				( objectStatus "@baseboard_fab2_lib.baseboard_fab2(sch_1):page149_i1:vddq(0)" )
			)
			( pin "U25W5.A9"
				( objectStatus "@baseboard_fab2_lib.baseboard_fab2(sch_1):page149_i1:vddq(1)" )
			)
			( pin "U25W5.C1"
				( objectStatus "@baseboard_fab2_lib.baseboard_fab2(sch_1):page149_i1:vddq(2)" )
			)
			( pin "U25W5.D9"
				( objectStatus "@baseboard_fab2_lib.baseboard_fab2(sch_1):page149_i1:vddq(3)" )
			)
			( pin "U25W5.F2"
				( objectStatus "@baseboard_fab2_lib.baseboard_fab2(sch_1):page149_i1:vddq(4)" )
			)
			( pin "U25W5.F8"
				( objectStatus "@baseboard_fab2_lib.baseboard_fab2(sch_1):page149_i1:vddq(5)" )
			)
			( pin "U25W5.G1"
				( objectStatus "@baseboard_fab2_lib.baseboard_fab2(sch_1):page149_i1:vddq(6)" )
			)
			( pin "U25W5.G9"
				( objectStatus "@baseboard_fab2_lib.baseboard_fab2(sch_1):page149_i1:vddq(7)" )
			)
			( pin "U25W5.J2"
				( objectStatus "@baseboard_fab2_lib.baseboard_fab2(sch_1):page149_i1:vddq(8)" )
			)
			( pin "U25W5.J8"
				( objectStatus "@baseboard_fab2_lib.baseboard_fab2(sch_1):page149_i1:vddq(9)" )
			)
			( pin "U25W5.B1"
				( objectStatus "@baseboard_fab2_lib.baseboard_fab2(sch_1):page149_i1:vpp(0)" )
			)
			( pin "U25W5.R9"
				( objectStatus "@baseboard_fab2_lib.baseboard_fab2(sch_1):page149_i1:vpp(1)" )
			)
			( pin "U25W5.M1"
				( objectStatus "@baseboard_fab2_lib.baseboard_fab2(sch_1):page149_i1:vrefca" )
			)
			( pin "U25W5.B2"
				( objectStatus "@baseboard_fab2_lib.baseboard_fab2(sch_1):page149_i1:vss(0)" )
			)
			( pin "U25W5.E1"
				( objectStatus "@baseboard_fab2_lib.baseboard_fab2(sch_1):page149_i1:vss(1)" )
			)
			( pin "U25W5.E9"
				( objectStatus "@baseboard_fab2_lib.baseboard_fab2(sch_1):page149_i1:vss(2)" )
			)
			( pin "U25W5.G8"
				( objectStatus "@baseboard_fab2_lib.baseboard_fab2(sch_1):page149_i1:vss(3)" )
			)
			( pin "U25W5.K1"
				( objectStatus "@baseboard_fab2_lib.baseboard_fab2(sch_1):page149_i1:vss(4)" )
			)
			( pin "U25W5.K9"
				( objectStatus "@baseboard_fab2_lib.baseboard_fab2(sch_1):page149_i1:vss(5)" )
			)
			( pin "U25W5.M9"
				( objectStatus "@baseboard_fab2_lib.baseboard_fab2(sch_1):page149_i1:vss(6)" )
			)
			( pin "U25W5.N1"
				( objectStatus "@baseboard_fab2_lib.baseboard_fab2(sch_1):page149_i1:vss(7)" )
			)
			( pin "U25W5.T1"
				( objectStatus "@baseboard_fab2_lib.baseboard_fab2(sch_1):page149_i1:vss(8)" )
			)
			( pin "U25W5.A2"
				( objectStatus "@baseboard_fab2_lib.baseboard_fab2(sch_1):page149_i1:vssq(0)" )
			)
			( pin "U25W5.A8"
				( objectStatus "@baseboard_fab2_lib.baseboard_fab2(sch_1):page149_i1:vssq(1)" )
			)
			( pin "U25W5.C9"
				( objectStatus "@baseboard_fab2_lib.baseboard_fab2(sch_1):page149_i1:vssq(2)" )
			)
			( pin "U25W5.D2"
				( objectStatus "@baseboard_fab2_lib.baseboard_fab2(sch_1):page149_i1:vssq(3)" )
			)
			( pin "U25W5.D8"
				( objectStatus "@baseboard_fab2_lib.baseboard_fab2(sch_1):page149_i1:vssq(4)" )
			)
			( pin "U25W5.E3"
				( objectStatus "@baseboard_fab2_lib.baseboard_fab2(sch_1):page149_i1:vssq(5)" )
			)
			( pin "U25W5.E8"
				( objectStatus "@baseboard_fab2_lib.baseboard_fab2(sch_1):page149_i1:vssq(6)" )
			)
			( pin "U25W5.F1"
				( objectStatus "@baseboard_fab2_lib.baseboard_fab2(sch_1):page149_i1:vssq(7)" )
			)
			( pin "U25W5.H1"
				( objectStatus "@baseboard_fab2_lib.baseboard_fab2(sch_1):page149_i1:vssq(8)" )
			)
			( pin "U25W5.H9"
				( objectStatus "@baseboard_fab2_lib.baseboard_fab2(sch_1):page149_i1:vssq(9)" )
			)
			( pin "U25W5.L2"
				( objectStatus "@baseboard_fab2_lib.baseboard_fab2(sch_1):page149_i1:\we#/a14\" )
			)
			( pin "U25W5.F9"
				( objectStatus "@baseboard_fab2_lib.baseboard_fab2(sch_1):page149_i1:zq" )
			)
			( pin "EU25F2.4"
				( objectStatus "@baseboard_fab2_lib.baseboard_fab2(sch_1):page239_i73:adj_nc" )
			)
			( pin "EU25F2.6"
				( objectStatus "@baseboard_fab2_lib.baseboard_fab2(sch_1):page239_i73:en" )
			)
			( pin "EU25F2.11"
				( objectStatus "@baseboard_fab2_lib.baseboard_fab2(sch_1):page239_i73:gnd" )
			)
			( pin "EU25F2.5"
				( objectStatus "@baseboard_fab2_lib.baseboard_fab2(sch_1):page239_i73:pgood" )
			)
			( pin "EU25F2.10"
				( objectStatus "@baseboard_fab2_lib.baseboard_fab2(sch_1):page239_i73:vdd" )
			)
			( pin "EU25F2.7"
				( objectStatus "@baseboard_fab2_lib.baseboard_fab2(sch_1):page239_i73:vin(0)" )
			)
			( pin "EU25F2.8"
				( objectStatus "@baseboard_fab2_lib.baseboard_fab2(sch_1):page239_i73:vin(1)" )
			)
			( pin "EU25F2.9"
				( objectStatus "@baseboard_fab2_lib.baseboard_fab2(sch_1):page239_i73:vin(2)" )
			)
			( pin "EU25F2.1"
				( objectStatus "@baseboard_fab2_lib.baseboard_fab2(sch_1):page239_i73:vout(0)" )
			)
			( pin "EU25F2.2"
				( objectStatus "@baseboard_fab2_lib.baseboard_fab2(sch_1):page239_i73:vout(1)" )
			)
			( pin "EU25F2.3"
				( objectStatus "@baseboard_fab2_lib.baseboard_fab2(sch_1):page239_i73:vout(2)" )
			)
			( pin "R1W9.1"
				( objectStatus "@baseboard_fab2_lib.baseboard_fab2(sch_1):page239_i77:a" )
			)
			( pin "R1W9.2"
				( objectStatus "@baseboard_fab2_lib.baseboard_fab2(sch_1):page239_i77:b" )
			)
			( pin "R9W12.1"
				( objectStatus "@baseboard_fab2_lib.baseboard_fab2(sch_1):page239_i79:a" )
			)
			( pin "R9W12.2"
				( objectStatus "@baseboard_fab2_lib.baseboard_fab2(sch_1):page239_i79:b" )
			)
			( pin "C9W13.1"
				( objectStatus "@baseboard_fab2_lib.baseboard_fab2(sch_1):page239_i81:a" )
			)
			( pin "C9W13.2"
				( objectStatus "@baseboard_fab2_lib.baseboard_fab2(sch_1):page239_i81:b" )
			)
			( pin "C1W15.1"
				( objectStatus "@baseboard_fab2_lib.baseboard_fab2(sch_1):page239_i83:a" )
			)
			( pin "C1W15.2"
				( objectStatus "@baseboard_fab2_lib.baseboard_fab2(sch_1):page239_i83:b" )
			)
			( pin "C9W10.1"
				( objectStatus "@baseboard_fab2_lib.baseboard_fab2(sch_1):page239_i84:a" )
			)
			( pin "C9W10.2"
				( objectStatus "@baseboard_fab2_lib.baseboard_fab2(sch_1):page239_i84:b" )
			)
			( pin "R9W32.1"
				( objectStatus "@baseboard_fab2_lib.baseboard_fab2(sch_1):page239_i87:a" )
			)
			( pin "R9W32.2"
				( objectStatus "@baseboard_fab2_lib.baseboard_fab2(sch_1):page239_i87:b" )
			)
			( pin "C9W5.1"
				( objectStatus "@baseboard_fab2_lib.baseboard_fab2(sch_1):page239_i90:a" )
			)
			( pin "C9W5.2"
				( objectStatus "@baseboard_fab2_lib.baseboard_fab2(sch_1):page239_i90:b" )
			)
			( pin "C9W6.1"
				( objectStatus "@baseboard_fab2_lib.baseboard_fab2(sch_1):page239_i91:a" )
			)
			( pin "C9W6.2"
				( objectStatus "@baseboard_fab2_lib.baseboard_fab2(sch_1):page239_i91:b" )
			)
			( pin "C1W7.1"
				( objectStatus "@baseboard_fab2_lib.baseboard_fab2(sch_1):page239_i92:a" )
			)
			( pin "C1W7.2"
				( objectStatus "@baseboard_fab2_lib.baseboard_fab2(sch_1):page239_i92:b" )
			)
			( pin "C25W22.1"
				( objectStatus "@baseboard_fab2_lib.baseboard_fab2(sch_1):page143_i55:a" )
			)
			( pin "C25W22.2"
				( objectStatus "@baseboard_fab2_lib.baseboard_fab2(sch_1):page143_i55:b" )
			)
			( pin "U25W4.J2"
				( objectStatus "@baseboard_fab2_lib.baseboard_fab2(sch_1):page144_i95:dacb" )
			)
			( pin "U25W4.J3"
				( objectStatus "@baseboard_fab2_lib.baseboard_fab2(sch_1):page144_i95:dacg" )
			)
			( pin "U25W4.J4"
				( objectStatus "@baseboard_fab2_lib.baseboard_fab2(sch_1):page144_i95:dacr" )
			)
			( pin "U25W4.K4"
				( objectStatus "@baseboard_fab2_lib.baseboard_fab2(sch_1):page144_i95:dacrset" )
			)
			( pin "U25W4.C14"
				( objectStatus "@baseboard_fab2_lib.baseboard_fab2(sch_1):page144_i95:gpioa4_timer5_scl9" )
			)
			( pin "U25W4.A13"
				( objectStatus "@baseboard_fab2_lib.baseboard_fab2(sch_1):page144_i95:gpioa5_timer6_sda9" )
			)
			( pin "U25W4.K19"
				( objectStatus "@baseboard_fab2_lib.baseboard_fab2(sch_1):page144_i95:gpiob0" )
			)
			( pin "U25W4.L19"
				( objectStatus "@baseboard_fab2_lib.baseboard_fab2(sch_1):page144_i95:gpiob1" )
			)
			( pin "U25W4.L18"
				( objectStatus "@baseboard_fab2_lib.baseboard_fab2(sch_1):page144_i95:gpiob2" )
			)
			( pin "U25W4.K18"
				( objectStatus "@baseboard_fab2_lib.baseboard_fab2(sch_1):page144_i95:gpiob3" )
			)
			( pin "U25W4.J20"
				( objectStatus "@baseboard_fab2_lib.baseboard_fab2(sch_1):page144_i95:gpiob4_usbcki" )
			)
			( pin "U25W4.H21"
				( objectStatus "@baseboard_fab2_lib.baseboard_fab2(sch_1):page144_i95:\gpiob5_lpcpd#_lpcsmi#\" )
			)
			( pin "U25W4.H22"
				( objectStatus "@baseboard_fab2_lib.baseboard_fab2(sch_1):page144_i95:\gpiob6_lpcpme#\" )
			)
			( pin "U25W4.H20"
				( objectStatus "@baseboard_fab2_lib.baseboard_fab2(sch_1):page144_i95:gpiob7" )
			)
			( pin "U25W4.A19"
				( objectStatus "@baseboard_fab2_lib.baseboard_fab2(sch_1):page144_i95:gpiog0_sgps1ck" )
			)
			( pin "U25W4.E19"
				( objectStatus "@baseboard_fab2_lib.baseboard_fab2(sch_1):page144_i95:gpiog1_sgps1ld" )
			)
			( pin "U25W4.C19"
				( objectStatus "@baseboard_fab2_lib.baseboard_fab2(sch_1):page144_i95:gpiog2_sgps1i0" )
			)
			( pin "U25W4.E16"
				( objectStatus "@baseboard_fab2_lib.baseboard_fab2(sch_1):page144_i95:gpiog3_sgps1i1" )
			)
			( pin "U25W4.C18"
				( objectStatus "@baseboard_fab2_lib.baseboard_fab2(sch_1):page144_i95:\gpioi0_syscs#\" )
			)
			( pin "U25W4.E15"
				( objectStatus "@baseboard_fab2_lib.baseboard_fab2(sch_1):page144_i95:gpioi1_sysck" )
			)
			( pin "U25W4.B16"
				( objectStatus "@baseboard_fab2_lib.baseboard_fab2(sch_1):page144_i95:gpioi2_sysmosi" )
			)
			( pin "U25W4.C16"
				( objectStatus "@baseboard_fab2_lib.baseboard_fab2(sch_1):page144_i95:gpioi3_sysmiso" )
			)
			( pin "U25W4.B15"
				( objectStatus "@baseboard_fab2_lib.baseboard_fab2(sch_1):page144_i95:\gpioi4_spi1cs0#_vbcs#\" )
			)
			( pin "U25W4.C15"
				( objectStatus "@baseboard_fab2_lib.baseboard_fab2(sch_1):page144_i95:gpioi5_spi1ck_vbck" )
			)
			( pin "U25W4.A14"
				( objectStatus "@baseboard_fab2_lib.baseboard_fab2(sch_1):page144_i95:gpioi6_spi1mosi_vbmosi" )
			)
			( pin "U25W4.A15"
				( objectStatus "@baseboard_fab2_lib.baseboard_fab2(sch_1):page144_i95:gpioi7_spi1miso_vbmiso" )
			)
			( pin "U25W4.R2"
				( objectStatus "@baseboard_fab2_lib.baseboard_fab2(sch_1):page144_i95:gpioj0_sgpmck" )
			)
			( pin "U25W4.L2"
				( objectStatus "@baseboard_fab2_lib.baseboard_fab2(sch_1):page144_i95:gpioj1_sgpmld" )
			)
			( pin "U25W4.N3"
				( objectStatus "@baseboard_fab2_lib.baseboard_fab2(sch_1):page144_i95:gpioj2_sgpmo" )
			)
			( pin "U25W4.N4"
				( objectStatus "@baseboard_fab2_lib.baseboard_fab2(sch_1):page144_i95:gpioj3_sgpmi" )
			)
			( pin "U25W4.L3"
				( objectStatus "@baseboard_fab2_lib.baseboard_fab2(sch_1):page144_i95:gpiok0_scl5" )
			)
			( pin "U25W4.L4"
				( objectStatus "@baseboard_fab2_lib.baseboard_fab2(sch_1):page144_i95:gpiok1_sda5" )
			)
			( pin "U25W4.L1"
				( objectStatus "@baseboard_fab2_lib.baseboard_fab2(sch_1):page144_i95:gpiok2_scl6" )
			)
			( pin "U25W4.N2"
				( objectStatus "@baseboard_fab2_lib.baseboard_fab2(sch_1):page144_i95:gpiok3_sda6" )
			)
			( pin "U25W4.N1"
				( objectStatus "@baseboard_fab2_lib.baseboard_fab2(sch_1):page144_i95:gpiok4_scl7" )
			)
			( pin "U25W4.P1"
				( objectStatus "@baseboard_fab2_lib.baseboard_fab2(sch_1):page144_i95:gpiok5_sda7" )
			)
			( pin "U25W4.P2"
				( objectStatus "@baseboard_fab2_lib.baseboard_fab2(sch_1):page144_i95:gpiok6_scl8" )
			)
			( pin "U25W4.R1"
				( objectStatus "@baseboard_fab2_lib.baseboard_fab2(sch_1):page144_i95:gpiok7_sda8" )
			)
			( pin "U25W4.A11"
				( objectStatus "@baseboard_fab2_lib.baseboard_fab2(sch_1):page144_i95:gpioq0_scl3" )
			)
			( pin "U25W4.A10"
				( objectStatus "@baseboard_fab2_lib.baseboard_fab2(sch_1):page144_i95:gpioq1_sda3" )
			)
			( pin "U25W4.A9"
				( objectStatus "@baseboard_fab2_lib.baseboard_fab2(sch_1):page144_i95:gpioq2_scl4" )
			)
			( pin "U25W4.B9"
				( objectStatus "@baseboard_fab2_lib.baseboard_fab2(sch_1):page144_i95:gpioq3_sda4" )
			)
			( pin "U25W4.N21"
				( objectStatus "@baseboard_fab2_lib.baseboard_fab2(sch_1):page144_i95:gpioq4_scl14" )
			)
			( pin "U25W4.N22"
				( objectStatus "@baseboard_fab2_lib.baseboard_fab2(sch_1):page144_i95:gpioq5_sda14" )
			)
			( pin "U25W4.M18"
				( objectStatus "@baseboard_fab2_lib.baseboard_fab2(sch_1):page144_i95:gpioy4_scl1" )
			)
			( pin "U25W4.M19"
				( objectStatus "@baseboard_fab2_lib.baseboard_fab2(sch_1):page144_i95:gpioy5_sda1" )
			)
			( pin "U25W4.M20"
				( objectStatus "@baseboard_fab2_lib.baseboard_fab2(sch_1):page144_i95:gpioy6_scl2" )
			)
			( pin "U25W4.P20"
				( objectStatus "@baseboard_fab2_lib.baseboard_fab2(sch_1):page144_i95:gpioy7_sda2" )
			)
			( pin "U25W4.E11"
				( objectStatus "@baseboard_fab2_lib.baseboard_fab2(sch_1):page144_i95:ntrst" )
			)
			( pin "U25W4.C9"
				( objectStatus "@baseboard_fab2_lib.baseboard_fab2(sch_1):page144_i95:rtck" )
			)
			( pin "U25W4.C10"
				( objectStatus "@baseboard_fab2_lib.baseboard_fab2(sch_1):page144_i95:tck" )
			)
			( pin "U25W4.D12"
				( objectStatus "@baseboard_fab2_lib.baseboard_fab2(sch_1):page144_i95:tdi" )
			)
			( pin "U25W4.D11"
				( objectStatus "@baseboard_fab2_lib.baseboard_fab2(sch_1):page144_i95:tdo" )
			)
			( pin "U25W4.C8"
				( objectStatus "@baseboard_fab2_lib.baseboard_fab2(sch_1):page144_i95:tms" )
			)
			( pin "Q9W1.3"
				( objectStatus "@baseboard_fab2_lib.baseboard_fab2(sch_1):page249_i30:drn" )
			)
			( pin "Q9W1.1"
				( objectStatus "@baseboard_fab2_lib.baseboard_fab2(sch_1):page249_i30:gate" )
			)
			( pin "Q9W1.2"
				( objectStatus "@baseboard_fab2_lib.baseboard_fab2(sch_1):page249_i30:src" )
			)
			( pin "R25W93.1"
				( objectStatus "@baseboard_fab2_lib.baseboard_fab2(sch_1):page150_i57:\1\" )
			)
			( pin "R25W93.2"
				( objectStatus "@baseboard_fab2_lib.baseboard_fab2(sch_1):page150_i57:\2\" )
			)
			( pin "C25W33.1"
				( objectStatus "@baseboard_fab2_lib.baseboard_fab2(sch_1):page150_i59:a" )
			)
			( pin "C25W33.2"
				( objectStatus "@baseboard_fab2_lib.baseboard_fab2(sch_1):page150_i59:b" )
			)
			( pin "C25W45.1"
				( objectStatus "@baseboard_fab2_lib.baseboard_fab2(sch_1):page150_i61:\1\" )
			)
			( pin "C25W45.2"
				( objectStatus "@baseboard_fab2_lib.baseboard_fab2(sch_1):page150_i61:\2\" )
			)
			( pin "U25W4.Y21"
				( objectStatus "@baseboard_fab2_lib.baseboard_fab2(sch_1):page146_i104:gpioaa0_vpor2_nord0_salt7" )
			)
			( pin "U25W4.V21"
				( objectStatus "@baseboard_fab2_lib.baseboard_fab2(sch_1):page146_i104:gpioaa1_vpor3_nord1_salt8" )
			)
			( pin "U25W4.Y22"
				( objectStatus "@baseboard_fab2_lib.baseboard_fab2(sch_1):page146_i104:gpioaa2_vpor4_nord2_salt9" )
			)
			( pin "U25W4.AA22"
				( objectStatus "@baseboard_fab2_lib.baseboard_fab2(sch_1):page146_i104:gpioaa3_vpor5_nord3_salt10" )
			)
			( pin "U25W4.U22"
				( objectStatus "@baseboard_fab2_lib.baseboard_fab2(sch_1):page146_i104:gpioaa4_vpor6_nord4_salt11" )
			)
			( pin "U25W4.T20"
				( objectStatus "@baseboard_fab2_lib.baseboard_fab2(sch_1):page146_i104:gpioaa5_vpor7_nord5_salt12" )
			)
			( pin "U25W4.N18"
				( objectStatus "@baseboard_fab2_lib.baseboard_fab2(sch_1):page146_i104:gpioaa6_vpor8_nord6_salt13" )
			)
			( pin "U25W4.P19"
				( objectStatus "@baseboard_fab2_lib.baseboard_fab2(sch_1):page146_i104:gpioaa7_vpor9_nord7_salt14" )
			)
			( pin "U25W4.A18"
				( objectStatus "@baseboard_fab2_lib.baseboard_fab2(sch_1):page146_i104:gpioh0_ncts6" )
			)
			( pin "U25W4.B18"
				( objectStatus "@baseboard_fab2_lib.baseboard_fab2(sch_1):page146_i104:gpioh1_ndcd6" )
			)
			( pin "U25W4.D17"
				( objectStatus "@baseboard_fab2_lib.baseboard_fab2(sch_1):page146_i104:gpioh2_ndsr6" )
			)
			( pin "U25W4.C17"
				( objectStatus "@baseboard_fab2_lib.baseboard_fab2(sch_1):page146_i104:gpioh3_nri6" )
			)
			( pin "U25W4.A17"
				( objectStatus "@baseboard_fab2_lib.baseboard_fab2(sch_1):page146_i104:gpioh4_ndtr6" )
			)
			( pin "U25W4.B17"
				( objectStatus "@baseboard_fab2_lib.baseboard_fab2(sch_1):page146_i104:gpioh5_nrts6" )
			)
			( pin "U25W4.A16"
				( objectStatus "@baseboard_fab2_lib.baseboard_fab2(sch_1):page146_i104:gpioh6_txd6" )
			)
			( pin "U25W4.D18"
				( objectStatus "@baseboard_fab2_lib.baseboard_fab2(sch_1):page146_i104:gpioh7_rxd6" )
			)
			( pin "U25W4.V20"
				( objectStatus "@baseboard_fab2_lib.baseboard_fab2(sch_1):page146_i104:\gpios0_vpob2_spi2cs1#\" )
			)
			( pin "U25W4.U19"
				( objectStatus "@baseboard_fab2_lib.baseboard_fab2(sch_1):page146_i104:gpios1_vpob3_bmcint" )
			)
			( pin "U25W4.R18"
				( objectStatus "@baseboard_fab2_lib.baseboard_fab2(sch_1):page146_i104:gpios2_vpob4_salt5" )
			)
			( pin "U25W4.P18"
				( objectStatus "@baseboard_fab2_lib.baseboard_fab2(sch_1):page146_i104:gpios3_vpob5_salt6" )
			)
			( pin "U25W4.R19"
				( objectStatus "@baseboard_fab2_lib.baseboard_fab2(sch_1):page146_i104:gpios4_vpob6" )
			)
			( pin "U25W4.W20"
				( objectStatus "@baseboard_fab2_lib.baseboard_fab2(sch_1):page146_i104:gpios5_vpob7" )
			)
			( pin "U25W4.U20"
				( objectStatus "@baseboard_fab2_lib.baseboard_fab2(sch_1):page146_i104:gpios6_vpob8" )
			)
			( pin "U25W4.AA20"
				( objectStatus "@baseboard_fab2_lib.baseboard_fab2(sch_1):page146_i104:gpios7_vpob9" )
			)
			( pin "U25W4.Y20"
				( objectStatus "@baseboard_fab2_lib.baseboard_fab2(sch_1):page146_i104:\gpioz0_vpog2_nora0_siopbi#\" )
			)
			( pin "U25W4.AB20"
				( objectStatus "@baseboard_fab2_lib.baseboard_fab2(sch_1):page146_i104:gpioz1_vpog3_nora1_siopwrgd" )
			)
			( pin "U25W4.AB21"
				( objectStatus "@baseboard_fab2_lib.baseboard_fab2(sch_1):page146_i104:\gpioz2_vpog4_nora2_siopbo#\" )
			)
			( pin "U25W4.AA21"
				( objectStatus "@baseboard_fab2_lib.baseboard_fab2(sch_1):page146_i104:\gpioz3_vpog5_nora3_siosci#\" )
			)
			( pin "U25W4.U21"
				( objectStatus "@baseboard_fab2_lib.baseboard_fab2(sch_1):page146_i104:gpioz4_vpog6_nora4" )
			)
			( pin "U25W4.W22"
				( objectStatus "@baseboard_fab2_lib.baseboard_fab2(sch_1):page146_i104:gpioz5_vpog7_nora5" )
			)
			( pin "U25W4.V22"
				( objectStatus "@baseboard_fab2_lib.baseboard_fab2(sch_1):page146_i104:gpioz6_vpog8_nora6" )
			)
			( pin "U25W4.W21"
				( objectStatus "@baseboard_fab2_lib.baseboard_fab2(sch_1):page146_i104:gpioz7_vpog9_nora7" )
			)
			( pin "U25W4.A8"
				( objectStatus "@baseboard_fab2_lib.baseboard_fab2(sch_1):page146_i104:usb2a_dn" )
			)
			( pin "U25W4.A7"
				( objectStatus "@baseboard_fab2_lib.baseboard_fab2(sch_1):page146_i104:usb2a_dp" )
			)
			( pin "U25W4.B8"
				( objectStatus "@baseboard_fab2_lib.baseboard_fab2(sch_1):page146_i104:usb2avres" )
			)
			( pin "U25W4.A6"
				( objectStatus "@baseboard_fab2_lib.baseboard_fab2(sch_1):page146_i104:usb2b_dn" )
			)
			( pin "U25W4.B6"
				( objectStatus "@baseboard_fab2_lib.baseboard_fab2(sch_1):page146_i104:usb2b_dp" )
			)
			( pin "U25W4.B7"
				( objectStatus "@baseboard_fab2_lib.baseboard_fab2(sch_1):page146_i104:usb2bvres" )
			)
			( pin "C25W44.1"
				( objectStatus "@baseboard_fab2_lib.baseboard_fab2(sch_1):page150_i62:a" )
			)
			( pin "C25W44.2"
				( objectStatus "@baseboard_fab2_lib.baseboard_fab2(sch_1):page150_i62:b" )
			)
			( pin "C25W43.1"
				( objectStatus "@baseboard_fab2_lib.baseboard_fab2(sch_1):page150_i63:a" )
			)
			( pin "C25W43.2"
				( objectStatus "@baseboard_fab2_lib.baseboard_fab2(sch_1):page150_i63:b" )
			)
			( pin "C25W62.1"
				( objectStatus "@baseboard_fab2_lib.baseboard_fab2(sch_1):page150_i65:\1\" )
			)
			( pin "C25W62.2"
				( objectStatus "@baseboard_fab2_lib.baseboard_fab2(sch_1):page150_i65:\2\" )
			)
			( pin "C9W1.1"
				( objectStatus "@baseboard_fab2_lib.baseboard_fab2(sch_1):page200_i235:\1\" )
			)
			( pin "C9W1.2"
				( objectStatus "@baseboard_fab2_lib.baseboard_fab2(sch_1):page200_i235:\2\" )
			)
			( pin "C9W2.1"
				( objectStatus "@baseboard_fab2_lib.baseboard_fab2(sch_1):page200_i236:\1\" )
			)
			( pin "C9W2.2"
				( objectStatus "@baseboard_fab2_lib.baseboard_fab2(sch_1):page200_i236:\2\" )
			)
			( pin "R1L45.1"
				( objectStatus "@baseboard_fab2_lib.baseboard_fab2(sch_1):page175_i89:\1\" )
			)
			( pin "R1L45.2"
				( objectStatus "@baseboard_fab2_lib.baseboard_fab2(sch_1):page175_i89:\2\" )
			)
			( pin "R9T8.1"
				( objectStatus "@baseboard_fab2_lib.baseboard_fab2(sch_1):page181_i278:a" )
			)
			( pin "R9T8.2"
				( objectStatus "@baseboard_fab2_lib.baseboard_fab2(sch_1):page181_i278:b" )
			)
			( pin "R25W81.1"
				( objectStatus "@baseboard_fab2_lib.baseboard_fab2(sch_1):page146_i67:a" )
			)
			( pin "R25W81.2"
				( objectStatus "@baseboard_fab2_lib.baseboard_fab2(sch_1):page146_i67:b" )
			)
			( pin "R25W100.1"
				( objectStatus "@baseboard_fab2_lib.baseboard_fab2(sch_1):page151_i13:a" )
			)
			( pin "R25W100.2"
				( objectStatus "@baseboard_fab2_lib.baseboard_fab2(sch_1):page151_i13:b" )
			)
			( pin "R25W98.1"
				( objectStatus "@baseboard_fab2_lib.baseboard_fab2(sch_1):page151_i12:a" )
			)
			( pin "R25W98.2"
				( objectStatus "@baseboard_fab2_lib.baseboard_fab2(sch_1):page151_i12:b" )
			)
			( pin "R25W97.1"
				( objectStatus "@baseboard_fab2_lib.baseboard_fab2(sch_1):page151_i11:a" )
			)
			( pin "R25W97.2"
				( objectStatus "@baseboard_fab2_lib.baseboard_fab2(sch_1):page151_i11:b" )
			)
			( pin "R25W95.1"
				( objectStatus "@baseboard_fab2_lib.baseboard_fab2(sch_1):page151_i2:a" )
			)
			( pin "R25W95.2"
				( objectStatus "@baseboard_fab2_lib.baseboard_fab2(sch_1):page151_i2:b" )
			)
			( pin "RT1.1"
				( objectStatus "@baseboard_fab2_lib.baseboard_fab2(sch_1):page202_i88:a" )
			)
			( pin "RT1.2"
				( objectStatus "@baseboard_fab2_lib.baseboard_fab2(sch_1):page202_i88:b" )
			)
			( pin "RT5.1"
				( objectStatus "@baseboard_fab2_lib.baseboard_fab2(sch_1):page227_i126:a" )
			)
			( pin "RT5.2"
				( objectStatus "@baseboard_fab2_lib.baseboard_fab2(sch_1):page227_i126:b" )
			)
			( pin "RT8.1"
				( objectStatus "@baseboard_fab2_lib.baseboard_fab2(sch_1):page227_i127:a" )
			)
			( pin "RT8.2"
				( objectStatus "@baseboard_fab2_lib.baseboard_fab2(sch_1):page227_i127:b" )
			)
			( pin "RT9.1"
				( objectStatus "@baseboard_fab2_lib.baseboard_fab2(sch_1):page209_i69:a" )
			)
			( pin "RT9.2"
				( objectStatus "@baseboard_fab2_lib.baseboard_fab2(sch_1):page209_i69:b" )
			)
			( pin "RT14.1"
				( objectStatus "@baseboard_fab2_lib.baseboard_fab2(sch_1):page208_i97:a" )
			)
			( pin "RT14.2"
				( objectStatus "@baseboard_fab2_lib.baseboard_fab2(sch_1):page208_i97:b" )
			)
			( pin "RT15.1"
				( objectStatus "@baseboard_fab2_lib.baseboard_fab2(sch_1):page207_i87:a" )
			)
			( pin "RT15.2"
				( objectStatus "@baseboard_fab2_lib.baseboard_fab2(sch_1):page207_i87:b" )
			)
			( pin "RT17.1"
				( objectStatus "@baseboard_fab2_lib.baseboard_fab2(sch_1):page207_i88:a" )
			)
			( pin "RT17.2"
				( objectStatus "@baseboard_fab2_lib.baseboard_fab2(sch_1):page207_i88:b" )
			)
			( pin "RT19.1"
				( objectStatus "@baseboard_fab2_lib.baseboard_fab2(sch_1):page224_i132:a" )
			)
			( pin "RT19.2"
				( objectStatus "@baseboard_fab2_lib.baseboard_fab2(sch_1):page224_i132:b" )
			)
			( pin "RT21.1"
				( objectStatus "@baseboard_fab2_lib.baseboard_fab2(sch_1):page224_i133:a" )
			)
			( pin "RT21.2"
				( objectStatus "@baseboard_fab2_lib.baseboard_fab2(sch_1):page224_i133:b" )
			)
			( pin "RT23.1"
				( objectStatus "@baseboard_fab2_lib.baseboard_fab2(sch_1):page204_i93:a" )
			)
			( pin "RT23.2"
				( objectStatus "@baseboard_fab2_lib.baseboard_fab2(sch_1):page204_i93:b" )
			)
			( pin "RT28.1"
				( objectStatus "@baseboard_fab2_lib.baseboard_fab2(sch_1):page203_i111:a" )
			)
			( pin "RT28.2"
				( objectStatus "@baseboard_fab2_lib.baseboard_fab2(sch_1):page203_i111:b" )
			)
			( pin "R9F64.1"
				( objectStatus "@baseboard_fab2_lib.baseboard_fab2(sch_1):page181_i281:a" )
			)
			( pin "R9F64.2"
				( objectStatus "@baseboard_fab2_lib.baseboard_fab2(sch_1):page181_i281:b" )
			)
			( pin "R9F63.1"
				( objectStatus "@baseboard_fab2_lib.baseboard_fab2(sch_1):page181_i282:a" )
			)
			( pin "R9F63.2"
				( objectStatus "@baseboard_fab2_lib.baseboard_fab2(sch_1):page181_i282:b" )
			)
			( pin "R9F66.1"
				( objectStatus "@baseboard_fab2_lib.baseboard_fab2(sch_1):page158_i152:a" )
			)
			( pin "R9F66.2"
				( objectStatus "@baseboard_fab2_lib.baseboard_fab2(sch_1):page158_i152:b" )
			)
			( pin "C25W2.1"
				( objectStatus "@baseboard_fab2_lib.baseboard_fab2(sch_1):page149_i72:a" )
			)
			( pin "C25W2.2"
				( objectStatus "@baseboard_fab2_lib.baseboard_fab2(sch_1):page149_i72:b" )
			)
			( pin "R1U13.1"
				( objectStatus "@baseboard_fab2_lib.baseboard_fab2(sch_1):page144_i58:a" )
			)
			( pin "R1U13.2"
				( objectStatus "@baseboard_fab2_lib.baseboard_fab2(sch_1):page144_i58:b" )
			)
			( pin "R1U14.1"
				( objectStatus "@baseboard_fab2_lib.baseboard_fab2(sch_1):page144_i57:a" )
			)
			( pin "R1U14.2"
				( objectStatus "@baseboard_fab2_lib.baseboard_fab2(sch_1):page144_i57:b" )
			)
			( pin "U25W4.J6"
				( objectStatus "@baseboard_fab2_lib.baseboard_fab2(sch_1):page148_i28:adcav33" )
			)
			( pin "U25W4.E4"
				( objectStatus "@baseboard_fab2_lib.baseboard_fab2(sch_1):page148_i28:batvdd" )
			)
			( pin "U25W4.K6"
				( objectStatus "@baseboard_fab2_lib.baseboard_fab2(sch_1):page148_i28:dacav33" )
			)
			( pin "U25W4.K5"
				( objectStatus "@baseboard_fab2_lib.baseboard_fab2(sch_1):page148_i28:dacdv33" )
			)
			( pin "U25W4.A1"
				( objectStatus "@baseboard_fab2_lib.baseboard_fab2(sch_1):page148_i28:gnd0" )
			)
			( pin "U25W4.A22"
				( objectStatus "@baseboard_fab2_lib.baseboard_fab2(sch_1):page148_i28:gnd1" )
			)
			( pin "U25W4.AA11"
				( objectStatus "@baseboard_fab2_lib.baseboard_fab2(sch_1):page148_i28:gnd2" )
			)
			( pin "U25W4.AA13"
				( objectStatus "@baseboard_fab2_lib.baseboard_fab2(sch_1):page148_i28:gnd3" )
			)
			( pin "U25W4.AA15"
				( objectStatus "@baseboard_fab2_lib.baseboard_fab2(sch_1):page148_i28:gnd4" )
			)
			( pin "U25W4.AA7"
				( objectStatus "@baseboard_fab2_lib.baseboard_fab2(sch_1):page148_i28:gnd5" )
			)
			( pin "U25W4.AA9"
				( objectStatus "@baseboard_fab2_lib.baseboard_fab2(sch_1):page148_i28:gnd6" )
			)
			( pin "U25W4.AB1"
				( objectStatus "@baseboard_fab2_lib.baseboard_fab2(sch_1):page148_i28:gnd7" )
			)
			( pin "U25W4.AB22"
				( objectStatus "@baseboard_fab2_lib.baseboard_fab2(sch_1):page148_i28:gnd8" )
			)
			( pin "U25W4.C6"
				( objectStatus "@baseboard_fab2_lib.baseboard_fab2(sch_1):page148_i28:gnd9" )
			)
			( pin "U25W4.E8"
				( objectStatus "@baseboard_fab2_lib.baseboard_fab2(sch_1):page148_i28:gnd10" )
			)
			( pin "U25W4.F16"
				( objectStatus "@baseboard_fab2_lib.baseboard_fab2(sch_1):page148_i28:gnd11" )
			)
			( pin "U25W4.G19"
				( objectStatus "@baseboard_fab2_lib.baseboard_fab2(sch_1):page148_i28:gnd12" )
			)
			( pin "U25W4.G6"
				( objectStatus "@baseboard_fab2_lib.baseboard_fab2(sch_1):page148_i28:gnd13" )
			)
			( pin "U25W4.H6"
				( objectStatus "@baseboard_fab2_lib.baseboard_fab2(sch_1):page148_i28:gnd14" )
			)
			( pin "U25W4.J10"
				( objectStatus "@baseboard_fab2_lib.baseboard_fab2(sch_1):page148_i28:gnd15" )
			)
			( pin "U25W4.J11"
				( objectStatus "@baseboard_fab2_lib.baseboard_fab2(sch_1):page148_i28:gnd16" )
			)
			( pin "U25W4.J12"
				( objectStatus "@baseboard_fab2_lib.baseboard_fab2(sch_1):page148_i28:gnd17" )
			)
			( pin "U25W4.J13"
				( objectStatus "@baseboard_fab2_lib.baseboard_fab2(sch_1):page148_i28:gnd18" )
			)
			( pin "U25W4.J14"
				( objectStatus "@baseboard_fab2_lib.baseboard_fab2(sch_1):page148_i28:gnd19" )
			)
			( pin "U25W4.J21"
				( objectStatus "@baseboard_fab2_lib.baseboard_fab2(sch_1):page148_i28:gnd20" )
			)
			( pin "U25W4.J22"
				( objectStatus "@baseboard_fab2_lib.baseboard_fab2(sch_1):page148_i28:gnd21" )
			)
			( pin "U25W4.J5"
				( objectStatus "@baseboard_fab2_lib.baseboard_fab2(sch_1):page148_i28:gnd22" )
			)
			( pin "U25W4.J9"
				( objectStatus "@baseboard_fab2_lib.baseboard_fab2(sch_1):page148_i28:gnd23" )
			)
			( pin "U25W4.K10"
				( objectStatus "@baseboard_fab2_lib.baseboard_fab2(sch_1):page148_i28:gnd24" )
			)
			( pin "U25W4.K11"
				( objectStatus "@baseboard_fab2_lib.baseboard_fab2(sch_1):page148_i28:gnd25" )
			)
			( pin "U25W4.K12"
				( objectStatus "@baseboard_fab2_lib.baseboard_fab2(sch_1):page148_i28:gnd26" )
			)
			( pin "U25W4.K13"
				( objectStatus "@baseboard_fab2_lib.baseboard_fab2(sch_1):page148_i28:gnd27" )
			)
			( pin "U25W4.K14"
				( objectStatus "@baseboard_fab2_lib.baseboard_fab2(sch_1):page148_i28:gnd28" )
			)
			( pin "U25W4.K16"
				( objectStatus "@baseboard_fab2_lib.baseboard_fab2(sch_1):page148_i28:gnd29" )
			)
			( pin "U25W4.K9"
				( objectStatus "@baseboard_fab2_lib.baseboard_fab2(sch_1):page148_i28:gnd30" )
			)
			( pin "U25W4.L10"
				( objectStatus "@baseboard_fab2_lib.baseboard_fab2(sch_1):page148_i28:gnd31" )
			)
			( pin "U25W4.L11"
				( objectStatus "@baseboard_fab2_lib.baseboard_fab2(sch_1):page148_i28:gnd32" )
			)
			( pin "U25W4.L12"
				( objectStatus "@baseboard_fab2_lib.baseboard_fab2(sch_1):page148_i28:gnd33" )
			)
			( pin "U25W4.L13"
				( objectStatus "@baseboard_fab2_lib.baseboard_fab2(sch_1):page148_i28:gnd34" )
			)
			( pin "U25W4.L14"
				( objectStatus "@baseboard_fab2_lib.baseboard_fab2(sch_1):page148_i28:gnd35" )
			)
			( pin "U25W4.L9"
				( objectStatus "@baseboard_fab2_lib.baseboard_fab2(sch_1):page148_i28:gnd36" )
			)
			( pin "U25W4.M1"
				( objectStatus "@baseboard_fab2_lib.baseboard_fab2(sch_1):page148_i28:gnd37" )
			)
			( pin "U25W4.M10"
				( objectStatus "@baseboard_fab2_lib.baseboard_fab2(sch_1):page148_i28:gnd38" )
			)
			( pin "U25W4.M11"
				( objectStatus "@baseboard_fab2_lib.baseboard_fab2(sch_1):page148_i28:gnd39" )
			)
			( pin "U25W4.M12"
				( objectStatus "@baseboard_fab2_lib.baseboard_fab2(sch_1):page148_i28:gnd40" )
			)
			( pin "U25W4.M13"
				( objectStatus "@baseboard_fab2_lib.baseboard_fab2(sch_1):page148_i28:gnd41" )
			)
			( pin "U25W4.M14"
				( objectStatus "@baseboard_fab2_lib.baseboard_fab2(sch_1):page148_i28:gnd42" )
			)
			( pin "U25W4.M16"
				( objectStatus "@baseboard_fab2_lib.baseboard_fab2(sch_1):page148_i28:gnd43" )
			)
			( pin "U25W4.M17"
				( objectStatus "@baseboard_fab2_lib.baseboard_fab2(sch_1):page148_i28:gnd44" )
			)
			( pin "U25W4.M2"
				( objectStatus "@baseboard_fab2_lib.baseboard_fab2(sch_1):page148_i28:gnd45" )
			)
			( pin "U25W4.M3"
				( objectStatus "@baseboard_fab2_lib.baseboard_fab2(sch_1):page148_i28:gnd46" )
			)
			( pin "U25W4.M4"
				( objectStatus "@baseboard_fab2_lib.baseboard_fab2(sch_1):page148_i28:gnd47" )
			)
			( pin "U25W4.M5"
				( objectStatus "@baseboard_fab2_lib.baseboard_fab2(sch_1):page148_i28:gnd48" )
			)
			( pin "U25W4.M6"
				( objectStatus "@baseboard_fab2_lib.baseboard_fab2(sch_1):page148_i28:gnd49" )
			)
			( pin "U25W4.M7"
				( objectStatus "@baseboard_fab2_lib.baseboard_fab2(sch_1):page148_i28:gnd50" )
			)
			( pin "U25W4.M9"
				( objectStatus "@baseboard_fab2_lib.baseboard_fab2(sch_1):page148_i28:gnd51" )
			)
			( pin "U25W4.N10"
				( objectStatus "@baseboard_fab2_lib.baseboard_fab2(sch_1):page148_i28:gnd52" )
			)
			( pin "U25W4.N11"
				( objectStatus "@baseboard_fab2_lib.baseboard_fab2(sch_1):page148_i28:gnd53" )
			)
			( pin "U25W4.N12"
				( objectStatus "@baseboard_fab2_lib.baseboard_fab2(sch_1):page148_i28:gnd54" )
			)
			( pin "U25W4.N13"
				( objectStatus "@baseboard_fab2_lib.baseboard_fab2(sch_1):page148_i28:gnd55" )
			)
			( pin "U25W4.N14"
				( objectStatus "@baseboard_fab2_lib.baseboard_fab2(sch_1):page148_i28:gnd56" )
			)
			( pin "U25W4.N9"
				( objectStatus "@baseboard_fab2_lib.baseboard_fab2(sch_1):page148_i28:gnd57" )
			)
			( pin "U25W4.T16"
				( objectStatus "@baseboard_fab2_lib.baseboard_fab2(sch_1):page148_i28:gnd58" )
			)
			( pin "U25W4.T6"
				( objectStatus "@baseboard_fab2_lib.baseboard_fab2(sch_1):page148_i28:gnd59" )
			)
			( pin "U25W4.T7"
				( objectStatus "@baseboard_fab2_lib.baseboard_fab2(sch_1):page148_i28:gnd60" )
			)
			( pin "U25W4.U11"
				( objectStatus "@baseboard_fab2_lib.baseboard_fab2(sch_1):page148_i28:gnd61" )
			)
			( pin "U25W4.U6"
				( objectStatus "@baseboard_fab2_lib.baseboard_fab2(sch_1):page148_i28:gnd62" )
			)
			( pin "U25W4.V10"
				( objectStatus "@baseboard_fab2_lib.baseboard_fab2(sch_1):page148_i28:gnd63" )
			)
			( pin "U25W4.V12"
				( objectStatus "@baseboard_fab2_lib.baseboard_fab2(sch_1):page148_i28:gnd64" )
			)
			( pin "U25W4.V14"
				( objectStatus "@baseboard_fab2_lib.baseboard_fab2(sch_1):page148_i28:gnd65" )
			)
			( pin "U25W4.V16"
				( objectStatus "@baseboard_fab2_lib.baseboard_fab2(sch_1):page148_i28:gnd66" )
			)
			( pin "U25W4.V8"
				( objectStatus "@baseboard_fab2_lib.baseboard_fab2(sch_1):page148_i28:gnd67" )
			)
			( pin "U25W4.E5"
				( objectStatus "@baseboard_fab2_lib.baseboard_fab2(sch_1):page148_i28:gnd68" )
			)
			( pin "U25W4.R22"
				( objectStatus "@baseboard_fab2_lib.baseboard_fab2(sch_1):page148_i28:\gpioy0_sios3#\" )
			)
			( pin "U25W4.R21"
				( objectStatus "@baseboard_fab2_lib.baseboard_fab2(sch_1):page148_i28:\gpioy1_sios5#\" )
			)
			( pin "U25W4.P22"
				( objectStatus "@baseboard_fab2_lib.baseboard_fab2(sch_1):page148_i28:\gpioy2_siopwreq#\" )
			)
			( pin "U25W4.F6"
				( objectStatus "@baseboard_fab2_lib.baseboard_fab2(sch_1):page148_i28:iv11d0" )
			)
			( pin "U25W4.G10"
				( objectStatus "@baseboard_fab2_lib.baseboard_fab2(sch_1):page148_i28:iv11d1" )
			)
			( pin "U25W4.G11"
				( objectStatus "@baseboard_fab2_lib.baseboard_fab2(sch_1):page148_i28:iv11d2" )
			)
			( pin "U25W4.G12"
				( objectStatus "@baseboard_fab2_lib.baseboard_fab2(sch_1):page148_i28:iv11d3" )
			)
			( pin "U25W4.G13"
				( objectStatus "@baseboard_fab2_lib.baseboard_fab2(sch_1):page148_i28:iv11d4" )
			)
			( pin "U25W4.G14"
				( objectStatus "@baseboard_fab2_lib.baseboard_fab2(sch_1):page148_i28:iv11d5" )
			)
			( pin "U25W4.G15"
				( objectStatus "@baseboard_fab2_lib.baseboard_fab2(sch_1):page148_i28:iv11d6" )
			)
			( pin "U25W4.G7"
				( objectStatus "@baseboard_fab2_lib.baseboard_fab2(sch_1):page148_i28:iv11d7" )
			)
			( pin "U25W4.G8"
				( objectStatus "@baseboard_fab2_lib.baseboard_fab2(sch_1):page148_i28:iv11d8" )
			)
			( pin "U25W4.G9"
				( objectStatus "@baseboard_fab2_lib.baseboard_fab2(sch_1):page148_i28:iv11d9" )
			)
			( pin "U25W4.H16"
				( objectStatus "@baseboard_fab2_lib.baseboard_fab2(sch_1):page148_i28:iv11d10" )
			)
			( pin "U25W4.J16"
				( objectStatus "@baseboard_fab2_lib.baseboard_fab2(sch_1):page148_i28:iv11d11" )
			)
			( pin "U25W4.L7"
				( objectStatus "@baseboard_fab2_lib.baseboard_fab2(sch_1):page148_i28:iv11d12" )
			)
			( pin "U25W4.N16"
				( objectStatus "@baseboard_fab2_lib.baseboard_fab2(sch_1):page148_i28:iv11d13" )
			)
			( pin "U25W4.N7"
				( objectStatus "@baseboard_fab2_lib.baseboard_fab2(sch_1):page148_i28:iv11d14" )
			)
			( pin "U25W4.P10"
				( objectStatus "@baseboard_fab2_lib.baseboard_fab2(sch_1):page148_i28:iv11d15" )
			)
			( pin "U25W4.P11"
				( objectStatus "@baseboard_fab2_lib.baseboard_fab2(sch_1):page148_i28:iv11d16" )
			)
			( pin "U25W4.P12"
				( objectStatus "@baseboard_fab2_lib.baseboard_fab2(sch_1):page148_i28:iv11d17" )
			)
			( pin "U25W4.P13"
				( objectStatus "@baseboard_fab2_lib.baseboard_fab2(sch_1):page148_i28:iv11d18" )
			)
			( pin "U25W4.P14"
				( objectStatus "@baseboard_fab2_lib.baseboard_fab2(sch_1):page148_i28:iv11d19" )
			)
			( pin "U25W4.P16"
				( objectStatus "@baseboard_fab2_lib.baseboard_fab2(sch_1):page148_i28:iv11d20" )
			)
			( pin "U25W4.P7"
				( objectStatus "@baseboard_fab2_lib.baseboard_fab2(sch_1):page148_i28:iv11d21" )
			)
			( pin "U25W4.P9"
				( objectStatus "@baseboard_fab2_lib.baseboard_fab2(sch_1):page148_i28:iv11d22" )
			)
			( pin "U25W4.R16"
				( objectStatus "@baseboard_fab2_lib.baseboard_fab2(sch_1):page148_i28:iv11d23" )
			)
			( pin "U25W4.R7"
				( objectStatus "@baseboard_fab2_lib.baseboard_fab2(sch_1):page148_i28:iv11d24" )
			)
			( pin "U25W4.J17"
				( objectStatus "@baseboard_fab2_lib.baseboard_fab2(sch_1):page148_i28:lpvdd0" )
			)
			( pin "U25W4.K17"
				( objectStatus "@baseboard_fab2_lib.baseboard_fab2(sch_1):page148_i28:lpvdd1" )
			)
			( pin "U25W4.T10"
				( objectStatus "@baseboard_fab2_lib.baseboard_fab2(sch_1):page148_i28:mvdd0" )
			)
			( pin "U25W4.T12"
				( objectStatus "@baseboard_fab2_lib.baseboard_fab2(sch_1):page148_i28:mvdd1" )
			)
			( pin "U25W4.T13"
				( objectStatus "@baseboard_fab2_lib.baseboard_fab2(sch_1):page148_i28:mvdd2" )
			)
			( pin "U25W4.T14"
				( objectStatus "@baseboard_fab2_lib.baseboard_fab2(sch_1):page148_i28:mvdd3" )
			)
			( pin "U25W4.T8"
				( objectStatus "@baseboard_fab2_lib.baseboard_fab2(sch_1):page148_i28:mvdd4" )
			)
			( pin "U25W4.L17"
				( objectStatus "@baseboard_fab2_lib.baseboard_fab2(sch_1):page148_i28:peav11" )
			)
			( pin "U25W4.L16"
				( objectStatus "@baseboard_fab2_lib.baseboard_fab2(sch_1):page148_i28:peav33" )
			)
			( pin "U25W4.AA17"
				( objectStatus "@baseboard_fab2_lib.baseboard_fab2(sch_1):page148_i28:pecivdd" )
			)
			( pin "U25W4.Y17"
				( objectStatus "@baseboard_fab2_lib.baseboard_fab2(sch_1):page148_i28:pllav330" )
			)
			( pin "U25W4.W17"
				( objectStatus "@baseboard_fab2_lib.baseboard_fab2(sch_1):page148_i28:pllav331" )
			)
			( pin "U25W4.V17"
				( objectStatus "@baseboard_fab2_lib.baseboard_fab2(sch_1):page148_i28:plldv11" )
			)
			( pin "U25W4.F12"
				( objectStatus "@baseboard_fab2_lib.baseboard_fab2(sch_1):page148_i28:pv33d0" )
			)
			( pin "U25W4.F13"
				( objectStatus "@baseboard_fab2_lib.baseboard_fab2(sch_1):page148_i28:pv33d1" )
			)
			( pin "U25W4.F14"
				( objectStatus "@baseboard_fab2_lib.baseboard_fab2(sch_1):page148_i28:pv33d2" )
			)
			( pin "U25W4.F15"
				( objectStatus "@baseboard_fab2_lib.baseboard_fab2(sch_1):page148_i28:pv33d3" )
			)
			( pin "U25W4.G16"
				( objectStatus "@baseboard_fab2_lib.baseboard_fab2(sch_1):page148_i28:pv33d4" )
			)
			( pin "U25W4.H17"
				( objectStatus "@baseboard_fab2_lib.baseboard_fab2(sch_1):page148_i28:pv33d5" )
			)
			( pin "U25W4.K7"
				( objectStatus "@baseboard_fab2_lib.baseboard_fab2(sch_1):page148_i28:pv33d6" )
			)
			( pin "U25W4.N17"
				( objectStatus "@baseboard_fab2_lib.baseboard_fab2(sch_1):page148_i28:pv33d7" )
			)
			( pin "U25W4.N6"
				( objectStatus "@baseboard_fab2_lib.baseboard_fab2(sch_1):page148_i28:pv33d8" )
			)
			( pin "U25W4.P17"
				( objectStatus "@baseboard_fab2_lib.baseboard_fab2(sch_1):page148_i28:pv33d9" )
			)
			( pin "U25W4.P6"
				( objectStatus "@baseboard_fab2_lib.baseboard_fab2(sch_1):page148_i28:pv33d10" )
			)
			( pin "U25W4.R17"
				( objectStatus "@baseboard_fab2_lib.baseboard_fab2(sch_1):page148_i28:pv33d11" )
			)
			( pin "U25W4.R6"
				( objectStatus "@baseboard_fab2_lib.baseboard_fab2(sch_1):page148_i28:pv33d12" )
			)
			( pin "U25W4.T11"
				( objectStatus "@baseboard_fab2_lib.baseboard_fab2(sch_1):page148_i28:pv33d13" )
			)
			( pin "U25W4.T15"
				( objectStatus "@baseboard_fab2_lib.baseboard_fab2(sch_1):page148_i28:pv33d14" )
			)
			( pin "U25W4.F10"
				( objectStatus "@baseboard_fab2_lib.baseboard_fab2(sch_1):page148_i28:r1vdd0" )
			)
			( pin "U25W4.F11"
				( objectStatus "@baseboard_fab2_lib.baseboard_fab2(sch_1):page148_i28:r1vdd1" )
			)
			( pin "U25W4.F7"
				( objectStatus "@baseboard_fab2_lib.baseboard_fab2(sch_1):page148_i28:r2vdd0" )
			)
			( pin "U25W4.F8"
				( objectStatus "@baseboard_fab2_lib.baseboard_fab2(sch_1):page148_i28:r2vdd1" )
			)
			( pin "U25W4.C7"
				( objectStatus "@baseboard_fab2_lib.baseboard_fab2(sch_1):page148_i28:usb2av33" )
			)
			( pin "U25W4.L5"
				( objectStatus "@baseboard_fab2_lib.baseboard_fab2(sch_1):page148_i28:vpllav110" )
			)
			( pin "U25W4.L6"
				( objectStatus "@baseboard_fab2_lib.baseboard_fab2(sch_1):page148_i28:vpllav111" )
			)
			( pin "U25W4.J7"
				( objectStatus "@baseboard_fab2_lib.baseboard_fab2(sch_1):page148_i28:vpllav330" )
			)
			( pin "U25W4.H7"
				( objectStatus "@baseboard_fab2_lib.baseboard_fab2(sch_1):page148_i28:vpllav331" )
			)
			( pin "C25W3.1"
				( objectStatus "@baseboard_fab2_lib.baseboard_fab2(sch_1):page149_i73:a" )
			)
			( pin "C25W3.2"
				( objectStatus "@baseboard_fab2_lib.baseboard_fab2(sch_1):page149_i73:b" )
			)
			( pin "C25W4.1"
				( objectStatus "@baseboard_fab2_lib.baseboard_fab2(sch_1):page149_i74:a" )
			)
			( pin "C25W4.2"
				( objectStatus "@baseboard_fab2_lib.baseboard_fab2(sch_1):page149_i74:b" )
			)
			( pin "C1T21.1"
				( objectStatus "@baseboard_fab2_lib.baseboard_fab2(sch_1):page148_i20:a" )
			)
			( pin "C1T21.2"
				( objectStatus "@baseboard_fab2_lib.baseboard_fab2(sch_1):page148_i20:b" )
			)
			( pin "R1U12.1"
				( objectStatus "@baseboard_fab2_lib.baseboard_fab2(sch_1):page144_i59:a" )
			)
			( pin "R1U12.2"
				( objectStatus "@baseboard_fab2_lib.baseboard_fab2(sch_1):page144_i59:b" )
			)
			( pin "R25W59.1"
				( objectStatus "@baseboard_fab2_lib.baseboard_fab2(sch_1):page148_i16:a" )
			)
			( pin "R25W59.2"
				( objectStatus "@baseboard_fab2_lib.baseboard_fab2(sch_1):page148_i16:b" )
			)
			( pin "R1U2.1"
				( objectStatus "@baseboard_fab2_lib.baseboard_fab2(sch_1):page147_i62:a" )
			)
			( pin "R1U2.2"
				( objectStatus "@baseboard_fab2_lib.baseboard_fab2(sch_1):page147_i62:b" )
			)
			( pin "R25W60.1"
				( objectStatus "@baseboard_fab2_lib.baseboard_fab2(sch_1):page145_i34:a" )
			)
			( pin "R25W60.2"
				( objectStatus "@baseboard_fab2_lib.baseboard_fab2(sch_1):page145_i34:b" )
			)
			( pin "U25W4.F4"
				( objectStatus "@baseboard_fab2_lib.baseboard_fab2(sch_1):page147_i106:adc0_gpiw0" )
			)
			( pin "U25W4.F5"
				( objectStatus "@baseboard_fab2_lib.baseboard_fab2(sch_1):page147_i106:adc1_gpiw1" )
			)
			( pin "U25W4.E2"
				( objectStatus "@baseboard_fab2_lib.baseboard_fab2(sch_1):page147_i106:adc2_gpiw2" )
			)
			( pin "U25W4.E1"
				( objectStatus "@baseboard_fab2_lib.baseboard_fab2(sch_1):page147_i106:adc3_gpiw3" )
			)
			( pin "U25W4.F3"
				( objectStatus "@baseboard_fab2_lib.baseboard_fab2(sch_1):page147_i106:adc4_gpiw4" )
			)
			( pin "U25W4.E3"
				( objectStatus "@baseboard_fab2_lib.baseboard_fab2(sch_1):page147_i106:adc5_gpiw5" )
			)
			( pin "U25W4.G5"
				( objectStatus "@baseboard_fab2_lib.baseboard_fab2(sch_1):page147_i106:adc6_gpiw6" )
			)
			( pin "U25W4.G4"
				( objectStatus "@baseboard_fab2_lib.baseboard_fab2(sch_1):page147_i106:adc7_gpiw7" )
			)
			( pin "U25W4.F2"
				( objectStatus "@baseboard_fab2_lib.baseboard_fab2(sch_1):page147_i106:adc8_gpix0" )
			)
			( pin "U25W4.G3"
				( objectStatus "@baseboard_fab2_lib.baseboard_fab2(sch_1):page147_i106:adc9_gpix1" )
			)
			( pin "U25W4.G2"
				( objectStatus "@baseboard_fab2_lib.baseboard_fab2(sch_1):page147_i106:adc10_gpix2" )
			)
			( pin "U25W4.F1"
				( objectStatus "@baseboard_fab2_lib.baseboard_fab2(sch_1):page147_i106:adc11_gpix3" )
			)
			( pin "U25W4.H5"
				( objectStatus "@baseboard_fab2_lib.baseboard_fab2(sch_1):page147_i106:adc12_gpix4" )
			)
			( pin "U25W4.G1"
				( objectStatus "@baseboard_fab2_lib.baseboard_fab2(sch_1):page147_i106:adc13_gpix5" )
			)
			( pin "U25W4.H3"
				( objectStatus "@baseboard_fab2_lib.baseboard_fab2(sch_1):page147_i106:adc14_gpix6" )
			)
			( pin "U25W4.H4"
				( objectStatus "@baseboard_fab2_lib.baseboard_fab2(sch_1):page147_i106:adc15_gpix7" )
			)
			( pin "U25W4.J1"
				( objectStatus "@baseboard_fab2_lib.baseboard_fab2(sch_1):page147_i106:adcrext" )
			)
			( pin "U25W4.H1"
				( objectStatus "@baseboard_fab2_lib.baseboard_fab2(sch_1):page147_i106:adcvrefn" )
			)
			( pin "U25W4.H2"
				( objectStatus "@baseboard_fab2_lib.baseboard_fab2(sch_1):page147_i106:adcvrefp" )
			)
			( pin "U25W4.C13"
				( objectStatus "@baseboard_fab2_lib.baseboard_fab2(sch_1):page147_i106:gpioa6_timer7_mdc2" )
			)
			( pin "U25W4.B13"
				( objectStatus "@baseboard_fab2_lib.baseboard_fab2(sch_1):page147_i106:gpioa7_timer8_mdio2" )
			)
			( pin "U25W4.V2"
				( objectStatus "@baseboard_fab2_lib.baseboard_fab2(sch_1):page147_i106:gpion0_pwm0" )
			)
			( pin "U25W4.W2"
				( objectStatus "@baseboard_fab2_lib.baseboard_fab2(sch_1):page147_i106:gpion1_pwm1" )
			)
			( pin "U25W4.V3"
				( objectStatus "@baseboard_fab2_lib.baseboard_fab2(sch_1):page147_i106:gpion2_pwm2_vpig2" )
			)
			( pin "U25W4.U3"
				( objectStatus "@baseboard_fab2_lib.baseboard_fab2(sch_1):page147_i106:gpion3_pwm3_vpig3" )
			)
			( pin "U25W4.W3"
				( objectStatus "@baseboard_fab2_lib.baseboard_fab2(sch_1):page147_i106:gpion4_pwm4_vpig4" )
			)
			( pin "U25W4.AA3"
				( objectStatus "@baseboard_fab2_lib.baseboard_fab2(sch_1):page147_i106:gpion5_pwm5_vpig5" )
			)
			( pin "U25W4.Y3"
				( objectStatus "@baseboard_fab2_lib.baseboard_fab2(sch_1):page147_i106:gpion6_pwm6_vpig6" )
			)
			( pin "U25W4.T4"
				( objectStatus "@baseboard_fab2_lib.baseboard_fab2(sch_1):page147_i106:gpion7_pwm7_vpig7" )
			)
			( pin "U25W4.U5"
				( objectStatus "@baseboard_fab2_lib.baseboard_fab2(sch_1):page147_i106:gpioo0_tach0_vpig8" )
			)
			( pin "U25W4.U4"
				( objectStatus "@baseboard_fab2_lib.baseboard_fab2(sch_1):page147_i106:gpioo1_tach1_vpig9" )
			)
			( pin "U25W4.V5"
				( objectStatus "@baseboard_fab2_lib.baseboard_fab2(sch_1):page147_i106:gpioo2_tach2" )
			)
			( pin "U25W4.AB4"
				( objectStatus "@baseboard_fab2_lib.baseboard_fab2(sch_1):page147_i106:gpioo3_tach3" )
			)
			( pin "U25W4.AB3"
				( objectStatus "@baseboard_fab2_lib.baseboard_fab2(sch_1):page147_i106:gpioo4_tach4_vpir2" )
			)
			( pin "U25W4.Y4"
				( objectStatus "@baseboard_fab2_lib.baseboard_fab2(sch_1):page147_i106:gpioo5_tach5_vpir3" )
			)
			( pin "U25W4.AA4"
				( objectStatus "@baseboard_fab2_lib.baseboard_fab2(sch_1):page147_i106:gpioo6_tach6_vpir4" )
			)
			( pin "U25W4.W4"
				( objectStatus "@baseboard_fab2_lib.baseboard_fab2(sch_1):page147_i106:gpioo7_tach7_vpir5" )
			)
			( pin "U25W4.V4"
				( objectStatus "@baseboard_fab2_lib.baseboard_fab2(sch_1):page147_i106:gpiop0_tach8_vpir6" )
			)
			( pin "U25W4.W5"
				( objectStatus "@baseboard_fab2_lib.baseboard_fab2(sch_1):page147_i106:gpiop1_tach9_vpir7" )
			)
			( pin "U25W4.AA5"
				( objectStatus "@baseboard_fab2_lib.baseboard_fab2(sch_1):page147_i106:gpiop2_tach10_vpir8" )
			)
			( pin "U25W4.AB5"
				( objectStatus "@baseboard_fab2_lib.baseboard_fab2(sch_1):page147_i106:gpiop3_tach11_vpir9" )
			)
			( pin "U25W4.Y6"
				( objectStatus "@baseboard_fab2_lib.baseboard_fab2(sch_1):page147_i106:gpiop4_tach12" )
			)
			( pin "U25W4.Y5"
				( objectStatus "@baseboard_fab2_lib.baseboard_fab2(sch_1):page147_i106:gpiop5_tach13" )
			)
			( pin "U25W4.W6"
				( objectStatus "@baseboard_fab2_lib.baseboard_fab2(sch_1):page147_i106:gpiop6_tach14" )
			)
			( pin "U25W4.V6"
				( objectStatus "@baseboard_fab2_lib.baseboard_fab2(sch_1):page147_i106:gpiop7_tach15" )
			)
			( pin "U25W4.D8"
				( objectStatus "@baseboard_fab2_lib.baseboard_fab2(sch_1):page147_i106:gpior6_mdc1" )
			)
			( pin "U25W4.E10"
				( objectStatus "@baseboard_fab2_lib.baseboard_fab2(sch_1):page147_i106:gpior7_mdio1" )
			)
			( pin "U25W4.B4"
				( objectStatus "@baseboard_fab2_lib.baseboard_fab2(sch_1):page147_i106:rgmii1rxck_rmii1rclki_gpiou4" )
			)
			( pin "U25W4.A4"
				( objectStatus "@baseboard_fab2_lib.baseboard_fab2(sch_1):page147_i106:rgmii1rxctl_gpiou5" )
			)
			( pin "U25W4.A3"
				( objectStatus "@baseboard_fab2_lib.baseboard_fab2(sch_1):page147_i106:rgmii1rxd0_rmii1rxd0_gpiou6" )
			)
			( pin "U25W4.D6"
				( objectStatus "@baseboard_fab2_lib.baseboard_fab2(sch_1):page147_i106:rgmii1rxd1_rmii1rxd1_gpiou7" )
			)
			( pin "U25W4.C5"
				( objectStatus "@baseboard_fab2_lib.baseboard_fab2(sch_1):page147_i106:rgmii1rxd2_rmii1crsdv_gpiov0" )
			)
			( pin "U25W4.C4"
				( objectStatus "@baseboard_fab2_lib.baseboard_fab2(sch_1):page147_i106:rgmii1rxd3_rmii1rxer_gpiov1" )
			)
			( pin "U25W4.B5"
				( objectStatus "@baseboard_fab2_lib.baseboard_fab2(sch_1):page147_i106:rgmii1txck_rmii1rclko_gpiot0" )
			)
			( pin "U25W4.E9"
				( objectStatus "@baseboard_fab2_lib.baseboard_fab2(sch_1):page147_i106:rgmii1txctl_rmii1txen_gpiot1" )
			)
			( pin "U25W4.F9"
				( objectStatus "@baseboard_fab2_lib.baseboard_fab2(sch_1):page147_i106:rgmii1txd0_rmii1txd0_gpiot2" )
			)
			( pin "U25W4.A5"
				( objectStatus "@baseboard_fab2_lib.baseboard_fab2(sch_1):page147_i106:rgmii1txd1_rmii1txd1_gpiot3" )
			)
			( pin "U25W4.E7"
				( objectStatus "@baseboard_fab2_lib.baseboard_fab2(sch_1):page147_i106:rgmii1txd2_gpiot4" )
			)
			( pin "U25W4.D7"
				( objectStatus "@baseboard_fab2_lib.baseboard_fab2(sch_1):page147_i106:rgmii1txd3_gpiot5" )
			)
			( pin "U25W4.C2"
				( objectStatus "@baseboard_fab2_lib.baseboard_fab2(sch_1):page147_i106:rgmii2rxck_rmii2rclki_gpiov2" )
			)
			( pin "U25W4.C1"
				( objectStatus "@baseboard_fab2_lib.baseboard_fab2(sch_1):page147_i106:rgmii2rxctl_gpiov3" )
			)
			( pin "U25W4.C3"
				( objectStatus "@baseboard_fab2_lib.baseboard_fab2(sch_1):page147_i106:rgmii2rxd0_rmii2rxd0_gpiov4" )
			)
			( pin "U25W4.D1"
				( objectStatus "@baseboard_fab2_lib.baseboard_fab2(sch_1):page147_i106:rgmii2rxd1_rmii2rxd1_gpiov5" )
			)
			( pin "U25W4.D2"
				( objectStatus "@baseboard_fab2_lib.baseboard_fab2(sch_1):page147_i106:rgmii2rxd2_rmii2crsdv_gpiov6" )
			)
			( pin "U25W4.E6"
				( objectStatus "@baseboard_fab2_lib.baseboard_fab2(sch_1):page147_i106:rgmii2rxd3_rmii2rxer_gpiov7" )
			)
			( pin "U25W4.B2"
				( objectStatus "@baseboard_fab2_lib.baseboard_fab2(sch_1):page147_i106:rgmii2txck_rmii2rclko_gpiot6" )
			)
			( pin "U25W4.B1"
				( objectStatus "@baseboard_fab2_lib.baseboard_fab2(sch_1):page147_i106:rgmii2txctl_rmii2txen_gpiot7" )
			)
			( pin "U25W4.A2"
				( objectStatus "@baseboard_fab2_lib.baseboard_fab2(sch_1):page147_i106:rgmii2txd0_rmii2txd0_gpiou0" )
			)
			( pin "U25W4.B3"
				( objectStatus "@baseboard_fab2_lib.baseboard_fab2(sch_1):page147_i106:rgmii2txd1_rmii2txd1_gpiou1" )
			)
			( pin "U25W4.D5"
				( objectStatus "@baseboard_fab2_lib.baseboard_fab2(sch_1):page147_i106:rgmii2txd2_gpiou2" )
			)
			( pin "U25W4.D4"
				( objectStatus "@baseboard_fab2_lib.baseboard_fab2(sch_1):page147_i106:rgmii2txd3_gpiou3" )
			)
			( pin "U25W4.D3"
				( objectStatus "@baseboard_fab2_lib.baseboard_fab2(sch_1):page147_i106:rgmiick" )
			)
			( pin "R1U1.1"
				( objectStatus "@baseboard_fab2_lib.baseboard_fab2(sch_1):page147_i61:a" )
			)
			( pin "R1U1.2"
				( objectStatus "@baseboard_fab2_lib.baseboard_fab2(sch_1):page147_i61:b" )
			)
			( pin "R1T26.1"
				( objectStatus "@baseboard_fab2_lib.baseboard_fab2(sch_1):page146_i37:a" )
			)
			( pin "R1T26.2"
				( objectStatus "@baseboard_fab2_lib.baseboard_fab2(sch_1):page146_i37:b" )
			)
			( pin "R1T25.1"
				( objectStatus "@baseboard_fab2_lib.baseboard_fab2(sch_1):page146_i35:a" )
			)
			( pin "R1T25.2"
				( objectStatus "@baseboard_fab2_lib.baseboard_fab2(sch_1):page146_i35:b" )
			)
			( pin "R25W84.1"
				( objectStatus "@baseboard_fab2_lib.baseboard_fab2(sch_1):page146_i27:a" )
			)
			( pin "R25W84.2"
				( objectStatus "@baseboard_fab2_lib.baseboard_fab2(sch_1):page146_i27:b" )
			)
			( pin "R25W83.1"
				( objectStatus "@baseboard_fab2_lib.baseboard_fab2(sch_1):page146_i26:a" )
			)
			( pin "R25W83.2"
				( objectStatus "@baseboard_fab2_lib.baseboard_fab2(sch_1):page146_i26:b" )
			)
			( pin "R25W75.1"
				( objectStatus "@baseboard_fab2_lib.baseboard_fab2(sch_1):page148_i23:a" )
			)
			( pin "R25W75.2"
				( objectStatus "@baseboard_fab2_lib.baseboard_fab2(sch_1):page148_i23:b" )
			)
			( pin "R25W90.1"
				( objectStatus "@baseboard_fab2_lib.baseboard_fab2(sch_1):page147_i21:a" )
			)
			( pin "R25W90.2"
				( objectStatus "@baseboard_fab2_lib.baseboard_fab2(sch_1):page147_i21:b" )
			)
			( pin "C25W26.1"
				( objectStatus "@baseboard_fab2_lib.baseboard_fab2(sch_1):page150_i71:a" )
			)
			( pin "C25W26.2"
				( objectStatus "@baseboard_fab2_lib.baseboard_fab2(sch_1):page150_i71:b" )
			)
			( pin "C25W59.1"
				( objectStatus "@baseboard_fab2_lib.baseboard_fab2(sch_1):page150_i69:\1\" )
			)
			( pin "C25W59.2"
				( objectStatus "@baseboard_fab2_lib.baseboard_fab2(sch_1):page150_i69:\2\" )
			)
			( pin "C25W61.1"
				( objectStatus "@baseboard_fab2_lib.baseboard_fab2(sch_1):page150_i67:\1\" )
			)
			( pin "C25W61.2"
				( objectStatus "@baseboard_fab2_lib.baseboard_fab2(sch_1):page150_i67:\2\" )
			)
			( pin "C25W60.1"
				( objectStatus "@baseboard_fab2_lib.baseboard_fab2(sch_1):page150_i1:a" )
			)
			( pin "C25W60.2"
				( objectStatus "@baseboard_fab2_lib.baseboard_fab2(sch_1):page150_i1:b" )
			)
			( pin "U9F3.2"
				( objectStatus "@baseboard_fab2_lib.baseboard_fab2(sch_1):page149_i34:a" )
			)
			( pin "U9F3.4"
				( objectStatus "@baseboard_fab2_lib.baseboard_fab2(sch_1):page149_i34:y" )
			)
			( pin "C25W16.1"
				( objectStatus "@baseboard_fab2_lib.baseboard_fab2(sch_1):page149_i37:a" )
			)
			( pin "C25W16.2"
				( objectStatus "@baseboard_fab2_lib.baseboard_fab2(sch_1):page149_i37:b" )
			)
			( pin "C25W17.1"
				( objectStatus "@baseboard_fab2_lib.baseboard_fab2(sch_1):page149_i38:\1\" )
			)
			( pin "C25W17.2"
				( objectStatus "@baseboard_fab2_lib.baseboard_fab2(sch_1):page149_i38:\2\" )
			)
			( pin "C25W15.1"
				( objectStatus "@baseboard_fab2_lib.baseboard_fab2(sch_1):page149_i39:\1\" )
			)
			( pin "C25W15.2"
				( objectStatus "@baseboard_fab2_lib.baseboard_fab2(sch_1):page149_i39:\2\" )
			)
			( pin "C25W65.1"
				( objectStatus "@baseboard_fab2_lib.baseboard_fab2(sch_1):page150_i2:\1\" )
			)
			( pin "C25W65.2"
				( objectStatus "@baseboard_fab2_lib.baseboard_fab2(sch_1):page150_i2:\2\" )
			)
			( pin "C25W71.1"
				( objectStatus "@baseboard_fab2_lib.baseboard_fab2(sch_1):page150_i4:a" )
			)
			( pin "C25W71.2"
				( objectStatus "@baseboard_fab2_lib.baseboard_fab2(sch_1):page150_i4:b" )
			)
			( pin "R9F61.1"
				( objectStatus "@baseboard_fab2_lib.baseboard_fab2(sch_1):page145_i14:a" )
			)
			( pin "R9F61.2"
				( objectStatus "@baseboard_fab2_lib.baseboard_fab2(sch_1):page145_i14:b" )
			)
			( pin "R9F62.1"
				( objectStatus "@baseboard_fab2_lib.baseboard_fab2(sch_1):page145_i11:a" )
			)
			( pin "R9F62.2"
				( objectStatus "@baseboard_fab2_lib.baseboard_fab2(sch_1):page145_i11:b" )
			)
			( pin "R9F60.1"
				( objectStatus "@baseboard_fab2_lib.baseboard_fab2(sch_1):page145_i10:a" )
			)
			( pin "R9F60.2"
				( objectStatus "@baseboard_fab2_lib.baseboard_fab2(sch_1):page145_i10:b" )
			)
			( pin "C25W25.1"
				( objectStatus "@baseboard_fab2_lib.baseboard_fab2(sch_1):page150_i72:a" )
			)
			( pin "C25W25.2"
				( objectStatus "@baseboard_fab2_lib.baseboard_fab2(sch_1):page150_i72:b" )
			)
			( pin "Y9F2.1"
				( objectStatus "@baseboard_fab2_lib.baseboard_fab2(sch_1):page145_i8:enable_control" )
			)
			( pin "Y9F2.2"
				( objectStatus "@baseboard_fab2_lib.baseboard_fab2(sch_1):page145_i8:gnd" )
			)
			( pin "Y9F2.3"
				( objectStatus "@baseboard_fab2_lib.baseboard_fab2(sch_1):page145_i8:\out\" )
			)
			( pin "Y9F2.4"
				( objectStatus "@baseboard_fab2_lib.baseboard_fab2(sch_1):page145_i8:vdd" )
			)
			( pin "R9F29.1"
				( objectStatus "@baseboard_fab2_lib.baseboard_fab2(sch_1):page149_i16:a" )
			)
			( pin "R9F29.2"
				( objectStatus "@baseboard_fab2_lib.baseboard_fab2(sch_1):page149_i16:b" )
			)
			( pin "R25W42.1"
				( objectStatus "@baseboard_fab2_lib.baseboard_fab2(sch_1):page149_i201:\1\" )
			)
			( pin "R25W42.2"
				( objectStatus "@baseboard_fab2_lib.baseboard_fab2(sch_1):page149_i201:\2\" )
			)
			( pin "R25W43.1"
				( objectStatus "@baseboard_fab2_lib.baseboard_fab2(sch_1):page149_i202:\1\" )
			)
			( pin "R25W43.2"
				( objectStatus "@baseboard_fab2_lib.baseboard_fab2(sch_1):page149_i202:\2\" )
			)
			( pin "R25W44.1"
				( objectStatus "@baseboard_fab2_lib.baseboard_fab2(sch_1):page149_i203:\1\" )
			)
			( pin "R25W44.2"
				( objectStatus "@baseboard_fab2_lib.baseboard_fab2(sch_1):page149_i203:\2\" )
			)
			( pin "R25W45.1"
				( objectStatus "@baseboard_fab2_lib.baseboard_fab2(sch_1):page149_i204:\1\" )
			)
			( pin "R25W45.2"
				( objectStatus "@baseboard_fab2_lib.baseboard_fab2(sch_1):page149_i204:\2\" )
			)
			( pin "R25W46.1"
				( objectStatus "@baseboard_fab2_lib.baseboard_fab2(sch_1):page149_i205:\1\" )
			)
			( pin "R25W46.2"
				( objectStatus "@baseboard_fab2_lib.baseboard_fab2(sch_1):page149_i205:\2\" )
			)
			( pin "R25W47.1"
				( objectStatus "@baseboard_fab2_lib.baseboard_fab2(sch_1):page149_i206:\1\" )
			)
			( pin "R25W47.2"
				( objectStatus "@baseboard_fab2_lib.baseboard_fab2(sch_1):page149_i206:\2\" )
			)
			( pin "R25W48.1"
				( objectStatus "@baseboard_fab2_lib.baseboard_fab2(sch_1):page149_i207:\1\" )
			)
			( pin "R25W48.2"
				( objectStatus "@baseboard_fab2_lib.baseboard_fab2(sch_1):page149_i207:\2\" )
			)
			( pin "R25W49.1"
				( objectStatus "@baseboard_fab2_lib.baseboard_fab2(sch_1):page149_i208:\1\" )
			)
			( pin "R25W49.2"
				( objectStatus "@baseboard_fab2_lib.baseboard_fab2(sch_1):page149_i208:\2\" )
			)
			( pin "R25W50.1"
				( objectStatus "@baseboard_fab2_lib.baseboard_fab2(sch_1):page149_i209:\1\" )
			)
			( pin "R25W50.2"
				( objectStatus "@baseboard_fab2_lib.baseboard_fab2(sch_1):page149_i209:\2\" )
			)
			( pin "R25W51.1"
				( objectStatus "@baseboard_fab2_lib.baseboard_fab2(sch_1):page149_i210:\1\" )
			)
			( pin "R25W51.2"
				( objectStatus "@baseboard_fab2_lib.baseboard_fab2(sch_1):page149_i210:\2\" )
			)
			( pin "R25W2.1"
				( objectStatus "@baseboard_fab2_lib.baseboard_fab2(sch_1):page149_i161:\1\" )
			)
			( pin "R25W2.2"
				( objectStatus "@baseboard_fab2_lib.baseboard_fab2(sch_1):page149_i161:\2\" )
			)
			( pin "C25W12.1"
				( objectStatus "@baseboard_fab2_lib.baseboard_fab2(sch_1):page149_i126:a" )
			)
			( pin "C25W12.2"
				( objectStatus "@baseboard_fab2_lib.baseboard_fab2(sch_1):page149_i126:b" )
			)
			( pin "R1T29.1"
				( objectStatus "@baseboard_fab2_lib.baseboard_fab2(sch_1):page149_i125:a" )
			)
			( pin "R1T29.2"
				( objectStatus "@baseboard_fab2_lib.baseboard_fab2(sch_1):page149_i125:b" )
			)
			( pin "R1T30.1"
				( objectStatus "@baseboard_fab2_lib.baseboard_fab2(sch_1):page149_i124:a" )
			)
			( pin "R1T30.2"
				( objectStatus "@baseboard_fab2_lib.baseboard_fab2(sch_1):page149_i124:b" )
			)
			( pin "R25W118.1"
				( objectStatus "@baseboard_fab2_lib.baseboard_fab2(sch_1):page149_i122:a" )
			)
			( pin "R25W118.2"
				( objectStatus "@baseboard_fab2_lib.baseboard_fab2(sch_1):page149_i122:b" )
			)
			( pin "R25W119.1"
				( objectStatus "@baseboard_fab2_lib.baseboard_fab2(sch_1):page149_i120:a" )
			)
			( pin "R25W119.2"
				( objectStatus "@baseboard_fab2_lib.baseboard_fab2(sch_1):page149_i120:b" )
			)
			( pin "Q9E1.6"
				( objectStatus "@baseboard_fab2_lib.baseboard_fab2(sch_1):page149_i113:drain(0)" )
			)
			( pin "Q9E1.2"
				( objectStatus "@baseboard_fab2_lib.baseboard_fab2(sch_1):page149_i113:gate(0)" )
			)
			( pin "Q9E1.1"
				( objectStatus "@baseboard_fab2_lib.baseboard_fab2(sch_1):page149_i113:source(0)" )
			)
			( pin "R9E21.1"
				( objectStatus "@baseboard_fab2_lib.baseboard_fab2(sch_1):page149_i111:a" )
			)
			( pin "R9E21.2"
				( objectStatus "@baseboard_fab2_lib.baseboard_fab2(sch_1):page149_i111:b" )
			)
			( pin "Q9E1.3"
				( objectStatus "@baseboard_fab2_lib.baseboard_fab2(sch_1):page149_i109:drain(0)" )
			)
			( pin "Q9E1.5"
				( objectStatus "@baseboard_fab2_lib.baseboard_fab2(sch_1):page149_i109:gate(0)" )
			)
			( pin "Q9E1.4"
				( objectStatus "@baseboard_fab2_lib.baseboard_fab2(sch_1):page149_i109:source(0)" )
			)
			( pin "R1T28.1"
				( objectStatus "@baseboard_fab2_lib.baseboard_fab2(sch_1):page149_i212:\1\" )
			)
			( pin "R1T28.2"
				( objectStatus "@baseboard_fab2_lib.baseboard_fab2(sch_1):page149_i212:\2\" )
			)
			( pin "R2T41.1"
				( objectStatus "@baseboard_fab2_lib.baseboard_fab2(sch_1):page146_i96:a" )
			)
			( pin "R2T41.2"
				( objectStatus "@baseboard_fab2_lib.baseboard_fab2(sch_1):page146_i96:b" )
			)
			( pin "DS9E1.1"
				( objectStatus "@baseboard_fab2_lib.baseboard_fab2(sch_1):page149_i98:a" )
			)
			( pin "DS9E1.2"
				( objectStatus "@baseboard_fab2_lib.baseboard_fab2(sch_1):page149_i98:c" )
			)
			( pin "C25W6.1"
				( objectStatus "@baseboard_fab2_lib.baseboard_fab2(sch_1):page149_i97:a" )
			)
			( pin "C25W6.2"
				( objectStatus "@baseboard_fab2_lib.baseboard_fab2(sch_1):page149_i97:b" )
			)
			( pin "C25W5.1"
				( objectStatus "@baseboard_fab2_lib.baseboard_fab2(sch_1):page149_i96:a" )
			)
			( pin "C25W5.2"
				( objectStatus "@baseboard_fab2_lib.baseboard_fab2(sch_1):page149_i96:b" )
			)
			( pin "R9E24.1"
				( objectStatus "@baseboard_fab2_lib.baseboard_fab2(sch_1):page149_i94:a" )
			)
			( pin "R9E24.2"
				( objectStatus "@baseboard_fab2_lib.baseboard_fab2(sch_1):page149_i94:b" )
			)
			( pin "R1U5.1"
				( objectStatus "@baseboard_fab2_lib.baseboard_fab2(sch_1):page147_i66:a" )
			)
			( pin "R1U5.2"
				( objectStatus "@baseboard_fab2_lib.baseboard_fab2(sch_1):page147_i66:b" )
			)
			( pin "R1U4.1"
				( objectStatus "@baseboard_fab2_lib.baseboard_fab2(sch_1):page147_i65:a" )
			)
			( pin "R1U4.2"
				( objectStatus "@baseboard_fab2_lib.baseboard_fab2(sch_1):page147_i65:b" )
			)
			( pin "R25W80.1"
				( objectStatus "@baseboard_fab2_lib.baseboard_fab2(sch_1):page147_i43:a" )
			)
			( pin "R25W80.2"
				( objectStatus "@baseboard_fab2_lib.baseboard_fab2(sch_1):page147_i43:b" )
			)
			( pin "R25W79.1"
				( objectStatus "@baseboard_fab2_lib.baseboard_fab2(sch_1):page147_i42:a" )
			)
			( pin "R25W79.2"
				( objectStatus "@baseboard_fab2_lib.baseboard_fab2(sch_1):page147_i42:b" )
			)
			( pin "R25W57.1"
				( objectStatus "@baseboard_fab2_lib.baseboard_fab2(sch_1):page147_i40:a" )
			)
			( pin "R25W57.2"
				( objectStatus "@baseboard_fab2_lib.baseboard_fab2(sch_1):page147_i40:b" )
			)
			( pin "C25W9.1"
				( objectStatus "@baseboard_fab2_lib.baseboard_fab2(sch_1):page147_i39:a" )
			)
			( pin "C25W9.2"
				( objectStatus "@baseboard_fab2_lib.baseboard_fab2(sch_1):page147_i39:b" )
			)
			( pin "C25W8.1"
				( objectStatus "@baseboard_fab2_lib.baseboard_fab2(sch_1):page147_i38:a" )
			)
			( pin "C25W8.2"
				( objectStatus "@baseboard_fab2_lib.baseboard_fab2(sch_1):page147_i38:b" )
			)
			( pin "R25W87.1"
				( objectStatus "@baseboard_fab2_lib.baseboard_fab2(sch_1):page147_i25:a" )
			)
			( pin "R25W87.2"
				( objectStatus "@baseboard_fab2_lib.baseboard_fab2(sch_1):page147_i25:b" )
			)
			( pin "R25W86.1"
				( objectStatus "@baseboard_fab2_lib.baseboard_fab2(sch_1):page147_i24:a" )
			)
			( pin "R25W86.2"
				( objectStatus "@baseboard_fab2_lib.baseboard_fab2(sch_1):page147_i24:b" )
			)
			( pin "R25W85.1"
				( objectStatus "@baseboard_fab2_lib.baseboard_fab2(sch_1):page147_i23:a" )
			)
			( pin "R25W85.2"
				( objectStatus "@baseboard_fab2_lib.baseboard_fab2(sch_1):page147_i23:b" )
			)
			( pin "R25W89.1"
				( objectStatus "@baseboard_fab2_lib.baseboard_fab2(sch_1):page147_i22:a" )
			)
			( pin "R25W89.2"
				( objectStatus "@baseboard_fab2_lib.baseboard_fab2(sch_1):page147_i22:b" )
			)
			( pin "R25W88.1"
				( objectStatus "@baseboard_fab2_lib.baseboard_fab2(sch_1):page147_i8:a" )
			)
			( pin "R25W88.2"
				( objectStatus "@baseboard_fab2_lib.baseboard_fab2(sch_1):page147_i8:b" )
			)
			( pin "R25W91.1"
				( objectStatus "@baseboard_fab2_lib.baseboard_fab2(sch_1):page147_i4:a" )
			)
			( pin "R25W91.2"
				( objectStatus "@baseboard_fab2_lib.baseboard_fab2(sch_1):page147_i4:b" )
			)
			( pin "R25W92.1"
				( objectStatus "@baseboard_fab2_lib.baseboard_fab2(sch_1):page147_i3:a" )
			)
			( pin "R25W92.2"
				( objectStatus "@baseboard_fab2_lib.baseboard_fab2(sch_1):page147_i3:b" )
			)
			( pin "R25W69.1"
				( objectStatus "@baseboard_fab2_lib.baseboard_fab2(sch_1):page146_i85:a" )
			)
			( pin "R25W69.2"
				( objectStatus "@baseboard_fab2_lib.baseboard_fab2(sch_1):page146_i85:b" )
			)
			( pin "R25W68.1"
				( objectStatus "@baseboard_fab2_lib.baseboard_fab2(sch_1):page146_i84:a" )
			)
			( pin "R25W68.2"
				( objectStatus "@baseboard_fab2_lib.baseboard_fab2(sch_1):page146_i84:b" )
			)
			( pin "R1U7.1"
				( objectStatus "@baseboard_fab2_lib.baseboard_fab2(sch_1):page146_i78:a" )
			)
			( pin "R1U7.2"
				( objectStatus "@baseboard_fab2_lib.baseboard_fab2(sch_1):page146_i78:b" )
			)
			( pin "R25W66.1"
				( objectStatus "@baseboard_fab2_lib.baseboard_fab2(sch_1):page146_i76:a" )
			)
			( pin "R25W66.2"
				( objectStatus "@baseboard_fab2_lib.baseboard_fab2(sch_1):page146_i76:b" )
			)
			( pin "R3N26.1"
				( objectStatus "@baseboard_fab2_lib.baseboard_fab2(sch_1):page146_i75:a" )
			)
			( pin "R3N26.2"
				( objectStatus "@baseboard_fab2_lib.baseboard_fab2(sch_1):page146_i75:b" )
			)
			( pin "R3N24.1"
				( objectStatus "@baseboard_fab2_lib.baseboard_fab2(sch_1):page146_i74:a" )
			)
			( pin "R3N24.2"
				( objectStatus "@baseboard_fab2_lib.baseboard_fab2(sch_1):page146_i74:b" )
			)
			( pin "R25W73.1"
				( objectStatus "@baseboard_fab2_lib.baseboard_fab2(sch_1):page146_i73:a" )
			)
			( pin "R25W73.2"
				( objectStatus "@baseboard_fab2_lib.baseboard_fab2(sch_1):page146_i73:b" )
			)
			( pin "R25W71.1"
				( objectStatus "@baseboard_fab2_lib.baseboard_fab2(sch_1):page146_i72:a" )
			)
			( pin "R25W71.2"
				( objectStatus "@baseboard_fab2_lib.baseboard_fab2(sch_1):page146_i72:b" )
			)
			( pin "R25W72.1"
				( objectStatus "@baseboard_fab2_lib.baseboard_fab2(sch_1):page146_i71:a" )
			)
			( pin "R25W72.2"
				( objectStatus "@baseboard_fab2_lib.baseboard_fab2(sch_1):page146_i71:b" )
			)
			( pin "R25W74.1"
				( objectStatus "@baseboard_fab2_lib.baseboard_fab2(sch_1):page146_i70:a" )
			)
			( pin "R25W74.2"
				( objectStatus "@baseboard_fab2_lib.baseboard_fab2(sch_1):page146_i70:b" )
			)
			( pin "R25W78.1"
				( objectStatus "@baseboard_fab2_lib.baseboard_fab2(sch_1):page146_i69:a" )
			)
			( pin "R25W78.2"
				( objectStatus "@baseboard_fab2_lib.baseboard_fab2(sch_1):page146_i69:b" )
			)
			( pin "R25W1.1"
				( objectStatus "@baseboard_fab2_lib.baseboard_fab2(sch_1):page149_i160:\1\" )
			)
			( pin "R25W1.2"
				( objectStatus "@baseboard_fab2_lib.baseboard_fab2(sch_1):page149_i160:\2\" )
			)
			( pin "R25W4.1"
				( objectStatus "@baseboard_fab2_lib.baseboard_fab2(sch_1):page149_i162:\1\" )
			)
			( pin "R25W4.2"
				( objectStatus "@baseboard_fab2_lib.baseboard_fab2(sch_1):page149_i162:\2\" )
			)
			( pin "R25W3.1"
				( objectStatus "@baseboard_fab2_lib.baseboard_fab2(sch_1):page149_i163:\1\" )
			)
			( pin "R25W3.2"
				( objectStatus "@baseboard_fab2_lib.baseboard_fab2(sch_1):page149_i163:\2\" )
			)
			( pin "R25W5.1"
				( objectStatus "@baseboard_fab2_lib.baseboard_fab2(sch_1):page149_i164:\1\" )
			)
			( pin "R25W5.2"
				( objectStatus "@baseboard_fab2_lib.baseboard_fab2(sch_1):page149_i164:\2\" )
			)
			( pin "R25W6.1"
				( objectStatus "@baseboard_fab2_lib.baseboard_fab2(sch_1):page149_i165:\1\" )
			)
			( pin "R25W6.2"
				( objectStatus "@baseboard_fab2_lib.baseboard_fab2(sch_1):page149_i165:\2\" )
			)
			( pin "R25W7.1"
				( objectStatus "@baseboard_fab2_lib.baseboard_fab2(sch_1):page149_i166:\1\" )
			)
			( pin "R25W7.2"
				( objectStatus "@baseboard_fab2_lib.baseboard_fab2(sch_1):page149_i166:\2\" )
			)
			( pin "R25W8.1"
				( objectStatus "@baseboard_fab2_lib.baseboard_fab2(sch_1):page149_i167:\1\" )
			)
			( pin "R25W8.2"
				( objectStatus "@baseboard_fab2_lib.baseboard_fab2(sch_1):page149_i167:\2\" )
			)
			( pin "R25W9.1"
				( objectStatus "@baseboard_fab2_lib.baseboard_fab2(sch_1):page149_i168:\1\" )
			)
			( pin "R25W9.2"
				( objectStatus "@baseboard_fab2_lib.baseboard_fab2(sch_1):page149_i168:\2\" )
			)
			( pin "R25W10.1"
				( objectStatus "@baseboard_fab2_lib.baseboard_fab2(sch_1):page149_i169:\1\" )
			)
			( pin "R25W10.2"
				( objectStatus "@baseboard_fab2_lib.baseboard_fab2(sch_1):page149_i169:\2\" )
			)
			( pin "R25W12.1"
				( objectStatus "@baseboard_fab2_lib.baseboard_fab2(sch_1):page149_i170:\1\" )
			)
			( pin "R25W12.2"
				( objectStatus "@baseboard_fab2_lib.baseboard_fab2(sch_1):page149_i170:\2\" )
			)
			( pin "R25W11.1"
				( objectStatus "@baseboard_fab2_lib.baseboard_fab2(sch_1):page149_i171:\1\" )
			)
			( pin "R25W11.2"
				( objectStatus "@baseboard_fab2_lib.baseboard_fab2(sch_1):page149_i171:\2\" )
			)
			( pin "R25W13.1"
				( objectStatus "@baseboard_fab2_lib.baseboard_fab2(sch_1):page149_i172:\1\" )
			)
			( pin "R25W13.2"
				( objectStatus "@baseboard_fab2_lib.baseboard_fab2(sch_1):page149_i172:\2\" )
			)
			( pin "R25W16.1"
				( objectStatus "@baseboard_fab2_lib.baseboard_fab2(sch_1):page149_i173:\1\" )
			)
			( pin "R25W16.2"
				( objectStatus "@baseboard_fab2_lib.baseboard_fab2(sch_1):page149_i173:\2\" )
			)
			( pin "R25W15.1"
				( objectStatus "@baseboard_fab2_lib.baseboard_fab2(sch_1):page149_i174:\1\" )
			)
			( pin "R25W15.2"
				( objectStatus "@baseboard_fab2_lib.baseboard_fab2(sch_1):page149_i174:\2\" )
			)
			( pin "R25W14.1"
				( objectStatus "@baseboard_fab2_lib.baseboard_fab2(sch_1):page149_i175:\1\" )
			)
			( pin "R25W14.2"
				( objectStatus "@baseboard_fab2_lib.baseboard_fab2(sch_1):page149_i175:\2\" )
			)
			( pin "R25W22.1"
				( objectStatus "@baseboard_fab2_lib.baseboard_fab2(sch_1):page149_i176:\1\" )
			)
			( pin "R25W22.2"
				( objectStatus "@baseboard_fab2_lib.baseboard_fab2(sch_1):page149_i176:\2\" )
			)
			( pin "R25W23.1"
				( objectStatus "@baseboard_fab2_lib.baseboard_fab2(sch_1):page149_i177:\1\" )
			)
			( pin "R25W23.2"
				( objectStatus "@baseboard_fab2_lib.baseboard_fab2(sch_1):page149_i177:\2\" )
			)
			( pin "R25W24.1"
				( objectStatus "@baseboard_fab2_lib.baseboard_fab2(sch_1):page149_i178:\1\" )
			)
			( pin "R25W24.2"
				( objectStatus "@baseboard_fab2_lib.baseboard_fab2(sch_1):page149_i178:\2\" )
			)
			( pin "R25W25.1"
				( objectStatus "@baseboard_fab2_lib.baseboard_fab2(sch_1):page149_i179:\1\" )
			)
			( pin "R25W25.2"
				( objectStatus "@baseboard_fab2_lib.baseboard_fab2(sch_1):page149_i179:\2\" )
			)
			( pin "R25W26.1"
				( objectStatus "@baseboard_fab2_lib.baseboard_fab2(sch_1):page149_i180:\1\" )
			)
			( pin "R25W26.2"
				( objectStatus "@baseboard_fab2_lib.baseboard_fab2(sch_1):page149_i180:\2\" )
			)
			( pin "R25W17.1"
				( objectStatus "@baseboard_fab2_lib.baseboard_fab2(sch_1):page149_i181:\1\" )
			)
			( pin "R25W17.2"
				( objectStatus "@baseboard_fab2_lib.baseboard_fab2(sch_1):page149_i181:\2\" )
			)
			( pin "R25W18.1"
				( objectStatus "@baseboard_fab2_lib.baseboard_fab2(sch_1):page149_i182:\1\" )
			)
			( pin "R25W18.2"
				( objectStatus "@baseboard_fab2_lib.baseboard_fab2(sch_1):page149_i182:\2\" )
			)
			( pin "R25W19.1"
				( objectStatus "@baseboard_fab2_lib.baseboard_fab2(sch_1):page149_i183:\1\" )
			)
			( pin "R25W19.2"
				( objectStatus "@baseboard_fab2_lib.baseboard_fab2(sch_1):page149_i183:\2\" )
			)
			( pin "R25W20.1"
				( objectStatus "@baseboard_fab2_lib.baseboard_fab2(sch_1):page149_i184:\1\" )
			)
			( pin "R25W20.2"
				( objectStatus "@baseboard_fab2_lib.baseboard_fab2(sch_1):page149_i184:\2\" )
			)
			( pin "R25W21.1"
				( objectStatus "@baseboard_fab2_lib.baseboard_fab2(sch_1):page149_i185:\1\" )
			)
			( pin "R25W21.2"
				( objectStatus "@baseboard_fab2_lib.baseboard_fab2(sch_1):page149_i185:\2\" )
			)
			( pin "R25W52.1"
				( objectStatus "@baseboard_fab2_lib.baseboard_fab2(sch_1):page149_i211:\1\" )
			)
			( pin "R25W52.2"
				( objectStatus "@baseboard_fab2_lib.baseboard_fab2(sch_1):page149_i211:\2\" )
			)
			( pin "R2N13.1"
				( objectStatus "@baseboard_fab2_lib.baseboard_fab2(sch_1):page147_i75:a" )
			)
			( pin "R2N13.2"
				( objectStatus "@baseboard_fab2_lib.baseboard_fab2(sch_1):page147_i75:b" )
			)
			( pin "R1T24.1"
				( objectStatus "@baseboard_fab2_lib.baseboard_fab2(sch_1):page144_i82:a" )
			)
			( pin "R1T24.2"
				( objectStatus "@baseboard_fab2_lib.baseboard_fab2(sch_1):page144_i82:b" )
			)
			( pin "R1T15.1"
				( objectStatus "@baseboard_fab2_lib.baseboard_fab2(sch_1):page145_i100:a" )
			)
			( pin "R1T15.2"
				( objectStatus "@baseboard_fab2_lib.baseboard_fab2(sch_1):page145_i100:b" )
			)
			( pin "R1T23.1"
				( objectStatus "@baseboard_fab2_lib.baseboard_fab2(sch_1):page145_i101:a" )
			)
			( pin "R1T23.2"
				( objectStatus "@baseboard_fab2_lib.baseboard_fab2(sch_1):page145_i101:b" )
			)
			( pin "C6W2.1"
				( objectStatus "@baseboard_fab2_lib.baseboard_fab2(sch_1):page247_i81:a" )
			)
			( pin "C6W2.2"
				( objectStatus "@baseboard_fab2_lib.baseboard_fab2(sch_1):page247_i81:b" )
			)
			( pin "U6W2.5"
				( objectStatus "@baseboard_fab2_lib.baseboard_fab2(sch_1):page247_i77:en" )
			)
			( pin "U6W2.4"
				( objectStatus "@baseboard_fab2_lib.baseboard_fab2(sch_1):page247_i77:gnd" )
			)
			( pin "U6W2.1"
				( objectStatus "@baseboard_fab2_lib.baseboard_fab2(sch_1):page247_i77:\nc#1\" )
			)
			( pin "U6W2.2"
				( objectStatus "@baseboard_fab2_lib.baseboard_fab2(sch_1):page247_i77:scl0" )
			)
			( pin "U6W2.7"
				( objectStatus "@baseboard_fab2_lib.baseboard_fab2(sch_1):page247_i77:scl1" )
			)
			( pin "U6W2.3"
				( objectStatus "@baseboard_fab2_lib.baseboard_fab2(sch_1):page247_i77:sda0" )
			)
			( pin "U6W2.6"
				( objectStatus "@baseboard_fab2_lib.baseboard_fab2(sch_1):page247_i77:sda1" )
			)
			( pin "U6W2.8"
				( objectStatus "@baseboard_fab2_lib.baseboard_fab2(sch_1):page247_i77:vcc" )
			)
			( pin "C6W3.1"
				( objectStatus "@baseboard_fab2_lib.baseboard_fab2(sch_1):page247_i85:a" )
			)
			( pin "C6W3.2"
				( objectStatus "@baseboard_fab2_lib.baseboard_fab2(sch_1):page247_i85:b" )
			)
			( pin "R6W20.1"
				( objectStatus "@baseboard_fab2_lib.baseboard_fab2(sch_1):page247_i87:a" )
			)
			( pin "R6W20.2"
				( objectStatus "@baseboard_fab2_lib.baseboard_fab2(sch_1):page247_i87:b" )
			)
			( pin "U6W3.1"
				( objectStatus "@baseboard_fab2_lib.baseboard_fab2(sch_1):page247_i89:a0" )
			)
			( pin "U6W3.2"
				( objectStatus "@baseboard_fab2_lib.baseboard_fab2(sch_1):page247_i89:a1" )
			)
			( pin "U6W3.3"
				( objectStatus "@baseboard_fab2_lib.baseboard_fab2(sch_1):page247_i89:a2" )
			)
			( pin "U6W3.6"
				( objectStatus "@baseboard_fab2_lib.baseboard_fab2(sch_1):page247_i89:scl" )
			)
			( pin "U6W3.5"
				( objectStatus "@baseboard_fab2_lib.baseboard_fab2(sch_1):page247_i89:sda" )
			)
			( pin "U6W3.7"
				( objectStatus "@baseboard_fab2_lib.baseboard_fab2(sch_1):page247_i89:wp" )
			)
			( pin "R6W21.1"
				( objectStatus "@baseboard_fab2_lib.baseboard_fab2(sch_1):page247_i90:a" )
			)
			( pin "R6W21.2"
				( objectStatus "@baseboard_fab2_lib.baseboard_fab2(sch_1):page247_i90:b" )
			)
			( pin "R6W23.1"
				( objectStatus "@baseboard_fab2_lib.baseboard_fab2(sch_1):page247_i92:a" )
			)
			( pin "R6W23.2"
				( objectStatus "@baseboard_fab2_lib.baseboard_fab2(sch_1):page247_i92:b" )
			)
			( pin "R6W22.1"
				( objectStatus "@baseboard_fab2_lib.baseboard_fab2(sch_1):page247_i94:a" )
			)
			( pin "R6W22.2"
				( objectStatus "@baseboard_fab2_lib.baseboard_fab2(sch_1):page247_i94:b" )
			)
			( pin "U25W4.V13"
				( objectStatus "@baseboard_fab2_lib.baseboard_fab2(sch_1):page143_i63:ma0" )
			)
			( pin "U25W4.AB14"
				( objectStatus "@baseboard_fab2_lib.baseboard_fab2(sch_1):page143_i63:ma1" )
			)
			( pin "U25W4.W14"
				( objectStatus "@baseboard_fab2_lib.baseboard_fab2(sch_1):page143_i63:ma2" )
			)
			( pin "U25W4.U14"
				( objectStatus "@baseboard_fab2_lib.baseboard_fab2(sch_1):page143_i63:ma3" )
			)
			( pin "U25W4.W15"
				( objectStatus "@baseboard_fab2_lib.baseboard_fab2(sch_1):page143_i63:ma4" )
			)
			( pin "U25W4.V15"
				( objectStatus "@baseboard_fab2_lib.baseboard_fab2(sch_1):page143_i63:ma5" )
			)
			( pin "U25W4.AB16"
				( objectStatus "@baseboard_fab2_lib.baseboard_fab2(sch_1):page143_i63:ma6" )
			)
			( pin "U25W4.AA16"
				( objectStatus "@baseboard_fab2_lib.baseboard_fab2(sch_1):page143_i63:ma7" )
			)
			( pin "U25W4.W16"
				( objectStatus "@baseboard_fab2_lib.baseboard_fab2(sch_1):page143_i63:ma8" )
			)
			( pin "U25W4.Y16"
				( objectStatus "@baseboard_fab2_lib.baseboard_fab2(sch_1):page143_i63:ma9" )
			)
			( pin "U25W4.U13"
				( objectStatus "@baseboard_fab2_lib.baseboard_fab2(sch_1):page143_i63:ma10" )
			)
			( pin "U25W4.AA14"
				( objectStatus "@baseboard_fab2_lib.baseboard_fab2(sch_1):page143_i63:ma11" )
			)
			( pin "U25W4.Y14"
				( objectStatus "@baseboard_fab2_lib.baseboard_fab2(sch_1):page143_i63:ma12" )
			)
			( pin "U25W4.AB15"
				( objectStatus "@baseboard_fab2_lib.baseboard_fab2(sch_1):page143_i63:ma13" )
			)
			( pin "U25W4.Y15"
				( objectStatus "@baseboard_fab2_lib.baseboard_fab2(sch_1):page143_i63:\ma14_mact#\" )
			)
			( pin "U25W4.U15"
				( objectStatus "@baseboard_fab2_lib.baseboard_fab2(sch_1):page143_i63:ma15" )
			)
			( pin "U25W4.U12"
				( objectStatus "@baseboard_fab2_lib.baseboard_fab2(sch_1):page143_i63:mba0" )
			)
			( pin "U25W4.Y13"
				( objectStatus "@baseboard_fab2_lib.baseboard_fab2(sch_1):page143_i63:mba1" )
			)
			( pin "U25W4.W13"
				( objectStatus "@baseboard_fab2_lib.baseboard_fab2(sch_1):page143_i63:mba2_mbg0" )
			)
			( pin "U25W4.AB13"
				( objectStatus "@baseboard_fab2_lib.baseboard_fab2(sch_1):page143_i63:\mcas#\" )
			)
			( pin "U25W4.Y11"
				( objectStatus "@baseboard_fab2_lib.baseboard_fab2(sch_1):page143_i63:mcke" )
			)
			( pin "U25W4.AB12"
				( objectStatus "@baseboard_fab2_lib.baseboard_fab2(sch_1):page143_i63:mckn" )
			)
			( pin "U25W4.AB11"
				( objectStatus "@baseboard_fab2_lib.baseboard_fab2(sch_1):page143_i63:mckp" )
			)
			( pin "U25W4.AA12"
				( objectStatus "@baseboard_fab2_lib.baseboard_fab2(sch_1):page143_i63:\mcs#\" )
			)
			( pin "U25W4.U8"
				( objectStatus "@baseboard_fab2_lib.baseboard_fab2(sch_1):page143_i63:mdm0" )
			)
			( pin "U25W4.AB8"
				( objectStatus "@baseboard_fab2_lib.baseboard_fab2(sch_1):page143_i63:mdm1" )
			)
			( pin "U25W4.U10"
				( objectStatus "@baseboard_fab2_lib.baseboard_fab2(sch_1):page143_i63:mdq0" )
			)
			( pin "U25W4.W10"
				( objectStatus "@baseboard_fab2_lib.baseboard_fab2(sch_1):page143_i63:mdq1" )
			)
			( pin "U25W4.Y10"
				( objectStatus "@baseboard_fab2_lib.baseboard_fab2(sch_1):page143_i63:mdq2" )
			)
			( pin "U25W4.AA10"
				( objectStatus "@baseboard_fab2_lib.baseboard_fab2(sch_1):page143_i63:mdq3" )
			)
			( pin "U25W4.U9"
				( objectStatus "@baseboard_fab2_lib.baseboard_fab2(sch_1):page143_i63:mdq4" )
			)
			( pin "U25W4.Y9"
				( objectStatus "@baseboard_fab2_lib.baseboard_fab2(sch_1):page143_i63:mdq5" )
			)
			( pin "U25W4.W9"
				( objectStatus "@baseboard_fab2_lib.baseboard_fab2(sch_1):page143_i63:mdq6" )
			)
			( pin "U25W4.V9"
				( objectStatus "@baseboard_fab2_lib.baseboard_fab2(sch_1):page143_i63:mdq7" )
			)
			( pin "U25W4.AA8"
				( objectStatus "@baseboard_fab2_lib.baseboard_fab2(sch_1):page143_i63:mdq8" )
			)
			( pin "U25W4.Y8"
				( objectStatus "@baseboard_fab2_lib.baseboard_fab2(sch_1):page143_i63:mdq9" )
			)
			( pin "U25W4.Y7"
				( objectStatus "@baseboard_fab2_lib.baseboard_fab2(sch_1):page143_i63:mdq10" )
			)
			( pin "U25W4.W8"
				( objectStatus "@baseboard_fab2_lib.baseboard_fab2(sch_1):page143_i63:mdq11" )
			)
			( pin "U25W4.AA6"
				( objectStatus "@baseboard_fab2_lib.baseboard_fab2(sch_1):page143_i63:mdq12" )
			)
			( pin "U25W4.W7"
				( objectStatus "@baseboard_fab2_lib.baseboard_fab2(sch_1):page143_i63:mdq13" )
			)
			( pin "U25W4.V7"
				( objectStatus "@baseboard_fab2_lib.baseboard_fab2(sch_1):page143_i63:mdq14" )
			)
			( pin "U25W4.U7"
				( objectStatus "@baseboard_fab2_lib.baseboard_fab2(sch_1):page143_i63:mdq15" )
			)
			( pin "U25W4.AB10"
				( objectStatus "@baseboard_fab2_lib.baseboard_fab2(sch_1):page143_i63:mdqs0n" )
			)
			( pin "U25W4.AB9"
				( objectStatus "@baseboard_fab2_lib.baseboard_fab2(sch_1):page143_i63:mdqs0p" )
			)
			( pin "U25W4.AB6"
				( objectStatus "@baseboard_fab2_lib.baseboard_fab2(sch_1):page143_i63:mdqs1n" )
			)
			( pin "U25W4.AB7"
				( objectStatus "@baseboard_fab2_lib.baseboard_fab2(sch_1):page143_i63:mdqs1p" )
			)
			( pin "U25W4.W11"
				( objectStatus "@baseboard_fab2_lib.baseboard_fab2(sch_1):page143_i63:mioz" )
			)
			( pin "U25W4.V11"
				( objectStatus "@baseboard_fab2_lib.baseboard_fab2(sch_1):page143_i63:modt" )
			)
			( pin "U25W4.W12"
				( objectStatus "@baseboard_fab2_lib.baseboard_fab2(sch_1):page143_i63:\mras#\" )
			)
			( pin "U25W4.T9"
				( objectStatus "@baseboard_fab2_lib.baseboard_fab2(sch_1):page143_i63:mvref" )
			)
			( pin "U25W4.Y12"
				( objectStatus "@baseboard_fab2_lib.baseboard_fab2(sch_1):page143_i63:\mwe#\" )
			)
			( pin "U25W4.K3"
				( objectStatus "@baseboard_fab2_lib.baseboard_fab2(sch_1):page146_i105:entest" )
			)
			( pin "U25W4.V18"
				( objectStatus "@baseboard_fab2_lib.baseboard_fab2(sch_1):page146_i105:\extrst#\" )
			)
			( pin "U25W4.AA18"
				( objectStatus "@baseboard_fab2_lib.baseboard_fab2(sch_1):page146_i105:fwspick" )
			)
			( pin "U25W4.AB19"
				( objectStatus "@baseboard_fab2_lib.baseboard_fab2(sch_1):page146_i105:\fwspics0#\" )
			)
			( pin "U25W4.T18"
				( objectStatus "@baseboard_fab2_lib.baseboard_fab2(sch_1):page146_i105:fwspimiso" )
			)
			( pin "U25W4.U17"
				( objectStatus "@baseboard_fab2_lib.baseboard_fab2(sch_1):page146_i105:fwspimosi" )
			)
			( pin "U25W4.N19"
				( objectStatus "@baseboard_fab2_lib.baseboard_fab2(sch_1):page146_i105:\gpioab0_vpode_noroe#\" )
			)
			( pin "U25W4.T21"
				( objectStatus "@baseboard_fab2_lib.baseboard_fab2(sch_1):page146_i105:\gpioab1_vpohs_norwe#\" )
			)
			( pin "U25W4.T22"
				( objectStatus "@baseboard_fab2_lib.baseboard_fab2(sch_1):page146_i105:gpioab2_vpovs_wdtrst1" )
			)
			( pin "U25W4.R20"
				( objectStatus "@baseboard_fab2_lib.baseboard_fab2(sch_1):page146_i105:gpioab3_vpoclk_wdtrst2" )
			)
			( pin "U25W4.G21"
				( objectStatus "@baseboard_fab2_lib.baseboard_fab2(sch_1):page146_i105:gpioac0_espid0_lad0" )
			)
			( pin "U25W4.G20"
				( objectStatus "@baseboard_fab2_lib.baseboard_fab2(sch_1):page146_i105:gpioac1_espid1_lad1" )
			)
			( pin "U25W4.D22"
				( objectStatus "@baseboard_fab2_lib.baseboard_fab2(sch_1):page146_i105:gpioac2_espid2_lad2" )
			)
			( pin "U25W4.E22"
				( objectStatus "@baseboard_fab2_lib.baseboard_fab2(sch_1):page146_i105:gpioac3_espid3_lad3" )
			)
			( pin "U25W4.C22"
				( objectStatus "@baseboard_fab2_lib.baseboard_fab2(sch_1):page146_i105:gpioac4_espick_lclk" )
			)
			( pin "U25W4.F21"
				( objectStatus "@baseboard_fab2_lib.baseboard_fab2(sch_1):page146_i105:\gpioac5_espics#_lframe#\" )
			)
			( pin "U25W4.F22"
				( objectStatus "@baseboard_fab2_lib.baseboard_fab2(sch_1):page146_i105:\gpioac6_espialt#_lsirq#\" )
			)
			( pin "U25W4.G22"
				( objectStatus "@baseboard_fab2_lib.baseboard_fab2(sch_1):page146_i105:\gpioac7_espirst#_lpcrst#\" )
			)
			( pin "U25W4.N5"
				( objectStatus "@baseboard_fab2_lib.baseboard_fab2(sch_1):page146_i105:gpioj4_vgahs" )
			)
			( pin "U25W4.R4"
				( objectStatus "@baseboard_fab2_lib.baseboard_fab2(sch_1):page146_i105:gpioj5_vgavs" )
			)
			( pin "U25W4.R3"
				( objectStatus "@baseboard_fab2_lib.baseboard_fab2(sch_1):page146_i105:gpioj6_ddcclk" )
			)
			( pin "U25W4.T3"
				( objectStatus "@baseboard_fab2_lib.baseboard_fab2(sch_1):page146_i105:gpioj7_ddcdat" )
			)
			( pin "U25W4.B10"
				( objectStatus "@baseboard_fab2_lib.baseboard_fab2(sch_1):page146_i105:gpioq6_oscclk" )
			)
			( pin "U25W4.N20"
				( objectStatus "@baseboard_fab2_lib.baseboard_fab2(sch_1):page146_i105:\gpioq7_pewake#\" )
			)
			( pin "U25W4.AA19"
				( objectStatus "@baseboard_fab2_lib.baseboard_fab2(sch_1):page146_i105:\gpior0_fwspics1#\" )
			)
			( pin "U25W4.T19"
				( objectStatus "@baseboard_fab2_lib.baseboard_fab2(sch_1):page146_i105:\gpior1_fwspics2#\" )
			)
			( pin "U25W4.T17"
				( objectStatus "@baseboard_fab2_lib.baseboard_fab2(sch_1):page146_i105:\gpior2_spi2cs0#\" )
			)
			( pin "U25W4.Y19"
				( objectStatus "@baseboard_fab2_lib.baseboard_fab2(sch_1):page146_i105:gpior3_spi2ck" )
			)
			( pin "U25W4.W19"
				( objectStatus "@baseboard_fab2_lib.baseboard_fab2(sch_1):page146_i105:gpior4_spi2mosi" )
			)
			( pin "U25W4.V19"
				( objectStatus "@baseboard_fab2_lib.baseboard_fab2(sch_1):page146_i105:gpior5_spi2miso" )
			)
			( pin "U25W4.Y18"
				( objectStatus "@baseboard_fab2_lib.baseboard_fab2(sch_1):page146_i105:\hbled#\" )
			)
			( pin "U25W4.U16"
				( objectStatus "@baseboard_fab2_lib.baseboard_fab2(sch_1):page146_i105:\malert#\" )
			)
			( pin "U25W4.AB17"
				( objectStatus "@baseboard_fab2_lib.baseboard_fab2(sch_1):page146_i105:\mreset#\" )
			)
			( pin "U6W1.21"
				( objectStatus "@baseboard_fab2_lib.baseboard_fab2(sch_1):page247_i97:a0" )
			)
			( pin "U6W1.2"
				( objectStatus "@baseboard_fab2_lib.baseboard_fab2(sch_1):page247_i97:a1" )
			)
			( pin "U6W1.3"
				( objectStatus "@baseboard_fab2_lib.baseboard_fab2(sch_1):page247_i97:a2" )
			)
			( pin "U6W1.12"
				( objectStatus "@baseboard_fab2_lib.baseboard_fab2(sch_1):page247_i97:gnd" )
			)
			( pin "U6W1.1"
				( objectStatus "@baseboard_fab2_lib.baseboard_fab2(sch_1):page247_i97:\int#\" )
			)
			( pin "U6W1.4"
				( objectStatus "@baseboard_fab2_lib.baseboard_fab2(sch_1):page247_i97:p0" )
			)
			( pin "U6W1.5"
				( objectStatus "@baseboard_fab2_lib.baseboard_fab2(sch_1):page247_i97:p1" )
			)
			( pin "U6W1.6"
				( objectStatus "@baseboard_fab2_lib.baseboard_fab2(sch_1):page247_i97:p2" )
			)
			( pin "U6W1.7"
				( objectStatus "@baseboard_fab2_lib.baseboard_fab2(sch_1):page247_i97:p3" )
			)
			( pin "U6W1.8"
				( objectStatus "@baseboard_fab2_lib.baseboard_fab2(sch_1):page247_i97:p4" )
			)
			( pin "U6W1.9"
				( objectStatus "@baseboard_fab2_lib.baseboard_fab2(sch_1):page247_i97:p5" )
			)
			( pin "U6W1.10"
				( objectStatus "@baseboard_fab2_lib.baseboard_fab2(sch_1):page247_i97:p6" )
			)
			( pin "U6W1.11"
				( objectStatus "@baseboard_fab2_lib.baseboard_fab2(sch_1):page247_i97:p7" )
			)
			( pin "U6W1.13"
				( objectStatus "@baseboard_fab2_lib.baseboard_fab2(sch_1):page247_i97:p10" )
			)
			( pin "U6W1.14"
				( objectStatus "@baseboard_fab2_lib.baseboard_fab2(sch_1):page247_i97:p11" )
			)
			( pin "U6W1.15"
				( objectStatus "@baseboard_fab2_lib.baseboard_fab2(sch_1):page247_i97:p12" )
			)
			( pin "U6W1.16"
				( objectStatus "@baseboard_fab2_lib.baseboard_fab2(sch_1):page247_i97:p13" )
			)
			( pin "U6W1.17"
				( objectStatus "@baseboard_fab2_lib.baseboard_fab2(sch_1):page247_i97:p14" )
			)
			( pin "U6W1.18"
				( objectStatus "@baseboard_fab2_lib.baseboard_fab2(sch_1):page247_i97:p15" )
			)
			( pin "U6W1.19"
				( objectStatus "@baseboard_fab2_lib.baseboard_fab2(sch_1):page247_i97:p16" )
			)
			( pin "U6W1.20"
				( objectStatus "@baseboard_fab2_lib.baseboard_fab2(sch_1):page247_i97:p17" )
			)
			( pin "U6W1.22"
				( objectStatus "@baseboard_fab2_lib.baseboard_fab2(sch_1):page247_i97:scl" )
			)
			( pin "U6W1.23"
				( objectStatus "@baseboard_fab2_lib.baseboard_fab2(sch_1):page247_i97:sda" )
			)
			( pin "U6W1.24"
				( objectStatus "@baseboard_fab2_lib.baseboard_fab2(sch_1):page247_i97:vcc" )
			)
			( bus "M_A_BA"
				( memberType ( signal ) )
				( member ( signalRef "M_A_BA<0>") )
				( member ( signalRef "M_A_BA<1>") )
				( objectStatus "@baseboard_fab2_lib.baseboard_fab2(sch_1):m_a_ba" )
			)
			( bus "M_A_BG"
				( memberType ( signal ) )
				( member ( signalRef "M_A_BG<0>") )
				( member ( signalRef "M_A_BG<1>") )
				( objectStatus "@baseboard_fab2_lib.baseboard_fab2(sch_1):m_a_bg" )
			)
			( bus "M_A_C"
				( memberType ( signal ) )
				( member ( signalRef "M_A_C<2>") )
				( objectStatus "@baseboard_fab2_lib.baseboard_fab2(sch_1):m_a_c" )
			)
			( bus "M_A_CKE"
				( memberType ( signal ) )
				( member ( signalRef "M_A_CKE<0>") )
				( member ( signalRef "M_A_CKE<1>") )
				( member ( signalRef "M_A_CKE<2>") )
				( member ( signalRef "M_A_CKE<3>") )
				( objectStatus "@baseboard_fab2_lib.baseboard_fab2(sch_1):m_a_cke" )
			)
			( bus "M_A_CLK_DN"
				( memberType ( signal ) )
				( member ( signalRef "M_A_CLK_DN<0>") )
				( member ( signalRef "M_A_CLK_DN<1>") )
				( member ( signalRef "M_A_CLK_DN<2>") )
				( member ( signalRef "M_A_CLK_DN<3>") )
				( objectStatus "@baseboard_fab2_lib.baseboard_fab2(sch_1):m_a_clk_dn" )
			)
			( bus "M_A_CLK_DP"
				( memberType ( signal ) )
				( member ( signalRef "M_A_CLK_DP<0>") )
				( member ( signalRef "M_A_CLK_DP<1>") )
				( member ( signalRef "M_A_CLK_DP<2>") )
				( member ( signalRef "M_A_CLK_DP<3>") )
				( objectStatus "@baseboard_fab2_lib.baseboard_fab2(sch_1):m_a_clk_dp" )
			)
			( bus "M_A_CS_N"
				( memberType ( signal ) )
				( member ( signalRef "M_A_CS_N<0>") )
				( member ( signalRef "M_A_CS_N<1>") )
				( member ( signalRef "M_A_CS_N<2>") )
				( member ( signalRef "M_A_CS_N<3>") )
				( member ( signalRef "M_A_CS_N<4>") )
				( member ( signalRef "M_A_CS_N<5>") )
				( member ( signalRef "M_A_CS_N<6>") )
				( member ( signalRef "M_A_CS_N<7>") )
				( objectStatus "@baseboard_fab2_lib.baseboard_fab2(sch_1):m_a_cs_n" )
			)
			( bus "M_A_DQ"
				( memberType ( signal ) )
				( member ( signalRef "M_A_DQ<0>") )
				( member ( signalRef "M_A_DQ<1>") )
				( member ( signalRef "M_A_DQ<2>") )
				( member ( signalRef "M_A_DQ<3>") )
				( member ( signalRef "M_A_DQ<4>") )
				( member ( signalRef "M_A_DQ<5>") )
				( member ( signalRef "M_A_DQ<6>") )
				( member ( signalRef "M_A_DQ<7>") )
				( member ( signalRef "M_A_DQ<8>") )
				( member ( signalRef "M_A_DQ<9>") )
				( member ( signalRef "M_A_DQ<10>") )
				( member ( signalRef "M_A_DQ<11>") )
				( member ( signalRef "M_A_DQ<12>") )
				( member ( signalRef "M_A_DQ<13>") )
				( member ( signalRef "M_A_DQ<14>") )
				( member ( signalRef "M_A_DQ<15>") )
				( member ( signalRef "M_A_DQ<16>") )
				( member ( signalRef "M_A_DQ<17>") )
				( member ( signalRef "M_A_DQ<18>") )
				( member ( signalRef "M_A_DQ<19>") )
				( member ( signalRef "M_A_DQ<20>") )
				( member ( signalRef "M_A_DQ<21>") )
				( member ( signalRef "M_A_DQ<22>") )
				( member ( signalRef "M_A_DQ<23>") )
				( member ( signalRef "M_A_DQ<24>") )
				( member ( signalRef "M_A_DQ<25>") )
				( member ( signalRef "M_A_DQ<26>") )
				( member ( signalRef "M_A_DQ<27>") )
				( member ( signalRef "M_A_DQ<28>") )
				( member ( signalRef "M_A_DQ<29>") )
				( member ( signalRef "M_A_DQ<30>") )
				( member ( signalRef "M_A_DQ<31>") )
				( member ( signalRef "M_A_DQ<32>") )
				( member ( signalRef "M_A_DQ<33>") )
				( member ( signalRef "M_A_DQ<34>") )
				( member ( signalRef "M_A_DQ<35>") )
				( member ( signalRef "M_A_DQ<36>") )
				( member ( signalRef "M_A_DQ<37>") )
				( member ( signalRef "M_A_DQ<38>") )
				( member ( signalRef "M_A_DQ<39>") )
				( member ( signalRef "M_A_DQ<40>") )
				( member ( signalRef "M_A_DQ<41>") )
				( member ( signalRef "M_A_DQ<42>") )
				( member ( signalRef "M_A_DQ<43>") )
				( member ( signalRef "M_A_DQ<44>") )
				( member ( signalRef "M_A_DQ<45>") )
				( member ( signalRef "M_A_DQ<46>") )
				( member ( signalRef "M_A_DQ<47>") )
				( member ( signalRef "M_A_DQ<48>") )
				( member ( signalRef "M_A_DQ<49>") )
				( member ( signalRef "M_A_DQ<50>") )
				( member ( signalRef "M_A_DQ<51>") )
				( member ( signalRef "M_A_DQ<52>") )
				( member ( signalRef "M_A_DQ<53>") )
				( member ( signalRef "M_A_DQ<54>") )
				( member ( signalRef "M_A_DQ<55>") )
				( member ( signalRef "M_A_DQ<56>") )
				( member ( signalRef "M_A_DQ<57>") )
				( member ( signalRef "M_A_DQ<58>") )
				( member ( signalRef "M_A_DQ<59>") )
				( member ( signalRef "M_A_DQ<60>") )
				( member ( signalRef "M_A_DQ<61>") )
				( member ( signalRef "M_A_DQ<62>") )
				( member ( signalRef "M_A_DQ<63>") )
				( objectStatus "@baseboard_fab2_lib.baseboard_fab2(sch_1):m_a_dq" )
			)
			( bus "M_A_DQS_DN"
				( memberType ( signal ) )
				( member ( signalRef "M_A_DQS_DN<0>") )
				( member ( signalRef "M_A_DQS_DN<1>") )
				( member ( signalRef "M_A_DQS_DN<2>") )
				( member ( signalRef "M_A_DQS_DN<3>") )
				( member ( signalRef "M_A_DQS_DN<4>") )
				( member ( signalRef "M_A_DQS_DN<5>") )
				( member ( signalRef "M_A_DQS_DN<6>") )
				( member ( signalRef "M_A_DQS_DN<7>") )
				( member ( signalRef "M_A_DQS_DN<8>") )
				( member ( signalRef "M_A_DQS_DN<9>") )
				( member ( signalRef "M_A_DQS_DN<10>") )
				( member ( signalRef "M_A_DQS_DN<11>") )
				( member ( signalRef "M_A_DQS_DN<12>") )
				( member ( signalRef "M_A_DQS_DN<13>") )
				( member ( signalRef "M_A_DQS_DN<14>") )
				( member ( signalRef "M_A_DQS_DN<15>") )
				( member ( signalRef "M_A_DQS_DN<16>") )
				( member ( signalRef "M_A_DQS_DN<17>") )
				( objectStatus "@baseboard_fab2_lib.baseboard_fab2(sch_1):m_a_dqs_dn" )
			)
			( bus "M_A_DQS_DP"
				( memberType ( signal ) )
				( member ( signalRef "M_A_DQS_DP<0>") )
				( member ( signalRef "M_A_DQS_DP<1>") )
				( member ( signalRef "M_A_DQS_DP<2>") )
				( member ( signalRef "M_A_DQS_DP<3>") )
				( member ( signalRef "M_A_DQS_DP<4>") )
				( member ( signalRef "M_A_DQS_DP<5>") )
				( member ( signalRef "M_A_DQS_DP<6>") )
				( member ( signalRef "M_A_DQS_DP<7>") )
				( member ( signalRef "M_A_DQS_DP<8>") )
				( member ( signalRef "M_A_DQS_DP<9>") )
				( member ( signalRef "M_A_DQS_DP<10>") )
				( member ( signalRef "M_A_DQS_DP<11>") )
				( member ( signalRef "M_A_DQS_DP<12>") )
				( member ( signalRef "M_A_DQS_DP<13>") )
				( member ( signalRef "M_A_DQS_DP<14>") )
				( member ( signalRef "M_A_DQS_DP<15>") )
				( member ( signalRef "M_A_DQS_DP<16>") )
				( member ( signalRef "M_A_DQS_DP<17>") )
				( objectStatus "@baseboard_fab2_lib.baseboard_fab2(sch_1):m_a_dqs_dp" )
			)
			( bus "M_A_ECC"
				( memberType ( signal ) )
				( member ( signalRef "M_A_ECC<0>") )
				( member ( signalRef "M_A_ECC<1>") )
				( member ( signalRef "M_A_ECC<2>") )
				( member ( signalRef "M_A_ECC<3>") )
				( member ( signalRef "M_A_ECC<4>") )
				( member ( signalRef "M_A_ECC<5>") )
				( member ( signalRef "M_A_ECC<6>") )
				( member ( signalRef "M_A_ECC<7>") )
				( objectStatus "@baseboard_fab2_lib.baseboard_fab2(sch_1):m_a_ecc" )
			)
			( bus "M_A_MA"
				( memberType ( signal ) )
				( member ( signalRef "M_A_MA<0>") )
				( member ( signalRef "M_A_MA<1>") )
				( member ( signalRef "M_A_MA<2>") )
				( member ( signalRef "M_A_MA<3>") )
				( member ( signalRef "M_A_MA<4>") )
				( member ( signalRef "M_A_MA<5>") )
				( member ( signalRef "M_A_MA<6>") )
				( member ( signalRef "M_A_MA<7>") )
				( member ( signalRef "M_A_MA<8>") )
				( member ( signalRef "M_A_MA<9>") )
				( member ( signalRef "M_A_MA<10>") )
				( member ( signalRef "M_A_MA<11>") )
				( member ( signalRef "M_A_MA<12>") )
				( member ( signalRef "M_A_MA<13>") )
				( member ( signalRef "M_A_MA<14>") )
				( member ( signalRef "M_A_MA<15>") )
				( member ( signalRef "M_A_MA<16>") )
				( member ( signalRef "M_A_MA<17>") )
				( objectStatus "@baseboard_fab2_lib.baseboard_fab2(sch_1):m_a_ma" )
			)
			( bus "M_A_ODT"
				( memberType ( signal ) )
				( member ( signalRef "M_A_ODT<0>") )
				( member ( signalRef "M_A_ODT<1>") )
				( member ( signalRef "M_A_ODT<2>") )
				( member ( signalRef "M_A_ODT<3>") )
				( objectStatus "@baseboard_fab2_lib.baseboard_fab2(sch_1):m_a_odt" )
			)
			( bus "M_B_BA"
				( memberType ( signal ) )
				( member ( signalRef "M_B_BA<0>") )
				( member ( signalRef "M_B_BA<1>") )
				( objectStatus "@baseboard_fab2_lib.baseboard_fab2(sch_1):m_b_ba" )
			)
			( bus "M_B_BG"
				( memberType ( signal ) )
				( member ( signalRef "M_B_BG<0>") )
				( member ( signalRef "M_B_BG<1>") )
				( objectStatus "@baseboard_fab2_lib.baseboard_fab2(sch_1):m_b_bg" )
			)
			( bus "M_B_C"
				( memberType ( signal ) )
				( member ( signalRef "M_B_C<2>") )
				( objectStatus "@baseboard_fab2_lib.baseboard_fab2(sch_1):m_b_c" )
			)
			( bus "M_B_CKE"
				( memberType ( signal ) )
				( member ( signalRef "M_B_CKE<0>") )
				( member ( signalRef "M_B_CKE<1>") )
				( member ( signalRef "M_B_CKE<2>") )
				( member ( signalRef "M_B_CKE<3>") )
				( objectStatus "@baseboard_fab2_lib.baseboard_fab2(sch_1):m_b_cke" )
			)
			( bus "M_B_CLK_DN"
				( memberType ( signal ) )
				( member ( signalRef "M_B_CLK_DN<0>") )
				( member ( signalRef "M_B_CLK_DN<1>") )
				( member ( signalRef "M_B_CLK_DN<2>") )
				( member ( signalRef "M_B_CLK_DN<3>") )
				( objectStatus "@baseboard_fab2_lib.baseboard_fab2(sch_1):m_b_clk_dn" )
			)
			( bus "M_B_CLK_DP"
				( memberType ( signal ) )
				( member ( signalRef "M_B_CLK_DP<0>") )
				( member ( signalRef "M_B_CLK_DP<1>") )
				( member ( signalRef "M_B_CLK_DP<2>") )
				( member ( signalRef "M_B_CLK_DP<3>") )
				( objectStatus "@baseboard_fab2_lib.baseboard_fab2(sch_1):m_b_clk_dp" )
			)
			( bus "M_B_CS_N"
				( memberType ( signal ) )
				( member ( signalRef "M_B_CS_N<0>") )
				( member ( signalRef "M_B_CS_N<1>") )
				( member ( signalRef "M_B_CS_N<2>") )
				( member ( signalRef "M_B_CS_N<3>") )
				( member ( signalRef "M_B_CS_N<4>") )
				( member ( signalRef "M_B_CS_N<5>") )
				( member ( signalRef "M_B_CS_N<6>") )
				( member ( signalRef "M_B_CS_N<7>") )
				( objectStatus "@baseboard_fab2_lib.baseboard_fab2(sch_1):m_b_cs_n" )
			)
			( bus "M_B_DQ"
				( memberType ( signal ) )
				( member ( signalRef "M_B_DQ<0>") )
				( member ( signalRef "M_B_DQ<1>") )
				( member ( signalRef "M_B_DQ<2>") )
				( member ( signalRef "M_B_DQ<3>") )
				( member ( signalRef "M_B_DQ<4>") )
				( member ( signalRef "M_B_DQ<5>") )
				( member ( signalRef "M_B_DQ<6>") )
				( member ( signalRef "M_B_DQ<7>") )
				( member ( signalRef "M_B_DQ<8>") )
				( member ( signalRef "M_B_DQ<9>") )
				( member ( signalRef "M_B_DQ<10>") )
				( member ( signalRef "M_B_DQ<11>") )
				( member ( signalRef "M_B_DQ<12>") )
				( member ( signalRef "M_B_DQ<13>") )
				( member ( signalRef "M_B_DQ<14>") )
				( member ( signalRef "M_B_DQ<15>") )
				( member ( signalRef "M_B_DQ<16>") )
				( member ( signalRef "M_B_DQ<17>") )
				( member ( signalRef "M_B_DQ<18>") )
				( member ( signalRef "M_B_DQ<19>") )
				( member ( signalRef "M_B_DQ<20>") )
				( member ( signalRef "M_B_DQ<21>") )
				( member ( signalRef "M_B_DQ<22>") )
				( member ( signalRef "M_B_DQ<23>") )
				( member ( signalRef "M_B_DQ<24>") )
				( member ( signalRef "M_B_DQ<25>") )
				( member ( signalRef "M_B_DQ<26>") )
				( member ( signalRef "M_B_DQ<27>") )
				( member ( signalRef "M_B_DQ<28>") )
				( member ( signalRef "M_B_DQ<29>") )
				( member ( signalRef "M_B_DQ<30>") )
				( member ( signalRef "M_B_DQ<31>") )
				( member ( signalRef "M_B_DQ<32>") )
				( member ( signalRef "M_B_DQ<33>") )
				( member ( signalRef "M_B_DQ<34>") )
				( member ( signalRef "M_B_DQ<35>") )
				( member ( signalRef "M_B_DQ<36>") )
				( member ( signalRef "M_B_DQ<37>") )
				( member ( signalRef "M_B_DQ<38>") )
				( member ( signalRef "M_B_DQ<39>") )
				( member ( signalRef "M_B_DQ<40>") )
				( member ( signalRef "M_B_DQ<41>") )
				( member ( signalRef "M_B_DQ<42>") )
				( member ( signalRef "M_B_DQ<43>") )
				( member ( signalRef "M_B_DQ<44>") )
				( member ( signalRef "M_B_DQ<45>") )
				( member ( signalRef "M_B_DQ<46>") )
				( member ( signalRef "M_B_DQ<47>") )
				( member ( signalRef "M_B_DQ<48>") )
				( member ( signalRef "M_B_DQ<49>") )
				( member ( signalRef "M_B_DQ<50>") )
				( member ( signalRef "M_B_DQ<51>") )
				( member ( signalRef "M_B_DQ<52>") )
				( member ( signalRef "M_B_DQ<53>") )
				( member ( signalRef "M_B_DQ<54>") )
				( member ( signalRef "M_B_DQ<55>") )
				( member ( signalRef "M_B_DQ<56>") )
				( member ( signalRef "M_B_DQ<57>") )
				( member ( signalRef "M_B_DQ<58>") )
				( member ( signalRef "M_B_DQ<59>") )
				( member ( signalRef "M_B_DQ<60>") )
				( member ( signalRef "M_B_DQ<61>") )
				( member ( signalRef "M_B_DQ<62>") )
				( member ( signalRef "M_B_DQ<63>") )
				( objectStatus "@baseboard_fab2_lib.baseboard_fab2(sch_1):m_b_dq" )
			)
			( bus "M_B_DQS_DN"
				( memberType ( signal ) )
				( member ( signalRef "M_B_DQS_DN<0>") )
				( member ( signalRef "M_B_DQS_DN<1>") )
				( member ( signalRef "M_B_DQS_DN<2>") )
				( member ( signalRef "M_B_DQS_DN<3>") )
				( member ( signalRef "M_B_DQS_DN<4>") )
				( member ( signalRef "M_B_DQS_DN<5>") )
				( member ( signalRef "M_B_DQS_DN<6>") )
				( member ( signalRef "M_B_DQS_DN<7>") )
				( member ( signalRef "M_B_DQS_DN<8>") )
				( member ( signalRef "M_B_DQS_DN<9>") )
				( member ( signalRef "M_B_DQS_DN<10>") )
				( member ( signalRef "M_B_DQS_DN<11>") )
				( member ( signalRef "M_B_DQS_DN<12>") )
				( member ( signalRef "M_B_DQS_DN<13>") )
				( member ( signalRef "M_B_DQS_DN<14>") )
				( member ( signalRef "M_B_DQS_DN<15>") )
				( member ( signalRef "M_B_DQS_DN<16>") )
				( member ( signalRef "M_B_DQS_DN<17>") )
				( objectStatus "@baseboard_fab2_lib.baseboard_fab2(sch_1):m_b_dqs_dn" )
			)
			( bus "M_B_DQS_DP"
				( memberType ( signal ) )
				( member ( signalRef "M_B_DQS_DP<0>") )
				( member ( signalRef "M_B_DQS_DP<1>") )
				( member ( signalRef "M_B_DQS_DP<2>") )
				( member ( signalRef "M_B_DQS_DP<3>") )
				( member ( signalRef "M_B_DQS_DP<4>") )
				( member ( signalRef "M_B_DQS_DP<5>") )
				( member ( signalRef "M_B_DQS_DP<6>") )
				( member ( signalRef "M_B_DQS_DP<7>") )
				( member ( signalRef "M_B_DQS_DP<8>") )
				( member ( signalRef "M_B_DQS_DP<9>") )
				( member ( signalRef "M_B_DQS_DP<10>") )
				( member ( signalRef "M_B_DQS_DP<11>") )
				( member ( signalRef "M_B_DQS_DP<12>") )
				( member ( signalRef "M_B_DQS_DP<13>") )
				( member ( signalRef "M_B_DQS_DP<14>") )
				( member ( signalRef "M_B_DQS_DP<15>") )
				( member ( signalRef "M_B_DQS_DP<16>") )
				( member ( signalRef "M_B_DQS_DP<17>") )
				( objectStatus "@baseboard_fab2_lib.baseboard_fab2(sch_1):m_b_dqs_dp" )
			)
			( bus "M_B_ECC"
				( memberType ( signal ) )
				( member ( signalRef "M_B_ECC<0>") )
				( member ( signalRef "M_B_ECC<1>") )
				( member ( signalRef "M_B_ECC<2>") )
				( member ( signalRef "M_B_ECC<3>") )
				( member ( signalRef "M_B_ECC<4>") )
				( member ( signalRef "M_B_ECC<5>") )
				( member ( signalRef "M_B_ECC<6>") )
				( member ( signalRef "M_B_ECC<7>") )
				( objectStatus "@baseboard_fab2_lib.baseboard_fab2(sch_1):m_b_ecc" )
			)
			( bus "M_B_MA"
				( memberType ( signal ) )
				( member ( signalRef "M_B_MA<0>") )
				( member ( signalRef "M_B_MA<1>") )
				( member ( signalRef "M_B_MA<2>") )
				( member ( signalRef "M_B_MA<3>") )
				( member ( signalRef "M_B_MA<4>") )
				( member ( signalRef "M_B_MA<5>") )
				( member ( signalRef "M_B_MA<6>") )
				( member ( signalRef "M_B_MA<7>") )
				( member ( signalRef "M_B_MA<8>") )
				( member ( signalRef "M_B_MA<9>") )
				( member ( signalRef "M_B_MA<10>") )
				( member ( signalRef "M_B_MA<11>") )
				( member ( signalRef "M_B_MA<12>") )
				( member ( signalRef "M_B_MA<13>") )
				( member ( signalRef "M_B_MA<14>") )
				( member ( signalRef "M_B_MA<15>") )
				( member ( signalRef "M_B_MA<16>") )
				( member ( signalRef "M_B_MA<17>") )
				( objectStatus "@baseboard_fab2_lib.baseboard_fab2(sch_1):m_b_ma" )
			)
			( bus "M_B_ODT"
				( memberType ( signal ) )
				( member ( signalRef "M_B_ODT<0>") )
				( member ( signalRef "M_B_ODT<1>") )
				( member ( signalRef "M_B_ODT<2>") )
				( member ( signalRef "M_B_ODT<3>") )
				( objectStatus "@baseboard_fab2_lib.baseboard_fab2(sch_1):m_b_odt" )
			)
			( bus "M_C_BA"
				( memberType ( signal ) )
				( member ( signalRef "M_C_BA<0>") )
				( member ( signalRef "M_C_BA<1>") )
				( objectStatus "@baseboard_fab2_lib.baseboard_fab2(sch_1):m_c_ba" )
			)
			( bus "M_C_BG"
				( memberType ( signal ) )
				( member ( signalRef "M_C_BG<0>") )
				( member ( signalRef "M_C_BG<1>") )
				( objectStatus "@baseboard_fab2_lib.baseboard_fab2(sch_1):m_c_bg" )
			)
			( bus "M_C_C"
				( memberType ( signal ) )
				( member ( signalRef "M_C_C<2>") )
				( objectStatus "@baseboard_fab2_lib.baseboard_fab2(sch_1):m_c_c" )
			)
			( bus "M_C_CKE"
				( memberType ( signal ) )
				( member ( signalRef "M_C_CKE<0>") )
				( member ( signalRef "M_C_CKE<1>") )
				( member ( signalRef "M_C_CKE<2>") )
				( member ( signalRef "M_C_CKE<3>") )
				( objectStatus "@baseboard_fab2_lib.baseboard_fab2(sch_1):m_c_cke" )
			)
			( bus "M_C_CLK_DN"
				( memberType ( signal ) )
				( member ( signalRef "M_C_CLK_DN<0>") )
				( member ( signalRef "M_C_CLK_DN<1>") )
				( member ( signalRef "M_C_CLK_DN<2>") )
				( member ( signalRef "M_C_CLK_DN<3>") )
				( objectStatus "@baseboard_fab2_lib.baseboard_fab2(sch_1):m_c_clk_dn" )
			)
			( bus "M_C_CLK_DP"
				( memberType ( signal ) )
				( member ( signalRef "M_C_CLK_DP<0>") )
				( member ( signalRef "M_C_CLK_DP<1>") )
				( member ( signalRef "M_C_CLK_DP<2>") )
				( member ( signalRef "M_C_CLK_DP<3>") )
				( objectStatus "@baseboard_fab2_lib.baseboard_fab2(sch_1):m_c_clk_dp" )
			)
			( bus "M_C_CS_N"
				( memberType ( signal ) )
				( member ( signalRef "M_C_CS_N<0>") )
				( member ( signalRef "M_C_CS_N<1>") )
				( member ( signalRef "M_C_CS_N<2>") )
				( member ( signalRef "M_C_CS_N<3>") )
				( member ( signalRef "M_C_CS_N<4>") )
				( member ( signalRef "M_C_CS_N<5>") )
				( member ( signalRef "M_C_CS_N<6>") )
				( member ( signalRef "M_C_CS_N<7>") )
				( objectStatus "@baseboard_fab2_lib.baseboard_fab2(sch_1):m_c_cs_n" )
			)
			( bus "M_C_DQ"
				( memberType ( signal ) )
				( member ( signalRef "M_C_DQ<0>") )
				( member ( signalRef "M_C_DQ<1>") )
				( member ( signalRef "M_C_DQ<2>") )
				( member ( signalRef "M_C_DQ<3>") )
				( member ( signalRef "M_C_DQ<4>") )
				( member ( signalRef "M_C_DQ<5>") )
				( member ( signalRef "M_C_DQ<6>") )
				( member ( signalRef "M_C_DQ<7>") )
				( member ( signalRef "M_C_DQ<8>") )
				( member ( signalRef "M_C_DQ<9>") )
				( member ( signalRef "M_C_DQ<10>") )
				( member ( signalRef "M_C_DQ<11>") )
				( member ( signalRef "M_C_DQ<12>") )
				( member ( signalRef "M_C_DQ<13>") )
				( member ( signalRef "M_C_DQ<14>") )
				( member ( signalRef "M_C_DQ<15>") )
				( member ( signalRef "M_C_DQ<16>") )
				( member ( signalRef "M_C_DQ<17>") )
				( member ( signalRef "M_C_DQ<18>") )
				( member ( signalRef "M_C_DQ<19>") )
				( member ( signalRef "M_C_DQ<20>") )
				( member ( signalRef "M_C_DQ<21>") )
				( member ( signalRef "M_C_DQ<22>") )
				( member ( signalRef "M_C_DQ<23>") )
				( member ( signalRef "M_C_DQ<24>") )
				( member ( signalRef "M_C_DQ<25>") )
				( member ( signalRef "M_C_DQ<26>") )
				( member ( signalRef "M_C_DQ<27>") )
				( member ( signalRef "M_C_DQ<28>") )
				( member ( signalRef "M_C_DQ<29>") )
				( member ( signalRef "M_C_DQ<30>") )
				( member ( signalRef "M_C_DQ<31>") )
				( member ( signalRef "M_C_DQ<32>") )
				( member ( signalRef "M_C_DQ<33>") )
				( member ( signalRef "M_C_DQ<34>") )
				( member ( signalRef "M_C_DQ<35>") )
				( member ( signalRef "M_C_DQ<36>") )
				( member ( signalRef "M_C_DQ<37>") )
				( member ( signalRef "M_C_DQ<38>") )
				( member ( signalRef "M_C_DQ<39>") )
				( member ( signalRef "M_C_DQ<40>") )
				( member ( signalRef "M_C_DQ<41>") )
				( member ( signalRef "M_C_DQ<42>") )
				( member ( signalRef "M_C_DQ<43>") )
				( member ( signalRef "M_C_DQ<44>") )
				( member ( signalRef "M_C_DQ<45>") )
				( member ( signalRef "M_C_DQ<46>") )
				( member ( signalRef "M_C_DQ<47>") )
				( member ( signalRef "M_C_DQ<48>") )
				( member ( signalRef "M_C_DQ<49>") )
				( member ( signalRef "M_C_DQ<50>") )
				( member ( signalRef "M_C_DQ<51>") )
				( member ( signalRef "M_C_DQ<52>") )
				( member ( signalRef "M_C_DQ<53>") )
				( member ( signalRef "M_C_DQ<54>") )
				( member ( signalRef "M_C_DQ<55>") )
				( member ( signalRef "M_C_DQ<56>") )
				( member ( signalRef "M_C_DQ<57>") )
				( member ( signalRef "M_C_DQ<58>") )
				( member ( signalRef "M_C_DQ<59>") )
				( member ( signalRef "M_C_DQ<60>") )
				( member ( signalRef "M_C_DQ<61>") )
				( member ( signalRef "M_C_DQ<62>") )
				( member ( signalRef "M_C_DQ<63>") )
				( objectStatus "@baseboard_fab2_lib.baseboard_fab2(sch_1):m_c_dq" )
			)
			( bus "M_C_DQS_DN"
				( memberType ( signal ) )
				( member ( signalRef "M_C_DQS_DN<0>") )
				( member ( signalRef "M_C_DQS_DN<1>") )
				( member ( signalRef "M_C_DQS_DN<2>") )
				( member ( signalRef "M_C_DQS_DN<3>") )
				( member ( signalRef "M_C_DQS_DN<4>") )
				( member ( signalRef "M_C_DQS_DN<5>") )
				( member ( signalRef "M_C_DQS_DN<6>") )
				( member ( signalRef "M_C_DQS_DN<7>") )
				( member ( signalRef "M_C_DQS_DN<8>") )
				( member ( signalRef "M_C_DQS_DN<9>") )
				( member ( signalRef "M_C_DQS_DN<10>") )
				( member ( signalRef "M_C_DQS_DN<11>") )
				( member ( signalRef "M_C_DQS_DN<12>") )
				( member ( signalRef "M_C_DQS_DN<13>") )
				( member ( signalRef "M_C_DQS_DN<14>") )
				( member ( signalRef "M_C_DQS_DN<15>") )
				( member ( signalRef "M_C_DQS_DN<16>") )
				( member ( signalRef "M_C_DQS_DN<17>") )
				( objectStatus "@baseboard_fab2_lib.baseboard_fab2(sch_1):m_c_dqs_dn" )
			)
			( bus "M_C_DQS_DP"
				( memberType ( signal ) )
				( member ( signalRef "M_C_DQS_DP<0>") )
				( member ( signalRef "M_C_DQS_DP<1>") )
				( member ( signalRef "M_C_DQS_DP<2>") )
				( member ( signalRef "M_C_DQS_DP<3>") )
				( member ( signalRef "M_C_DQS_DP<4>") )
				( member ( signalRef "M_C_DQS_DP<5>") )
				( member ( signalRef "M_C_DQS_DP<6>") )
				( member ( signalRef "M_C_DQS_DP<7>") )
				( member ( signalRef "M_C_DQS_DP<8>") )
				( member ( signalRef "M_C_DQS_DP<9>") )
				( member ( signalRef "M_C_DQS_DP<10>") )
				( member ( signalRef "M_C_DQS_DP<11>") )
				( member ( signalRef "M_C_DQS_DP<12>") )
				( member ( signalRef "M_C_DQS_DP<13>") )
				( member ( signalRef "M_C_DQS_DP<14>") )
				( member ( signalRef "M_C_DQS_DP<15>") )
				( member ( signalRef "M_C_DQS_DP<16>") )
				( member ( signalRef "M_C_DQS_DP<17>") )
				( objectStatus "@baseboard_fab2_lib.baseboard_fab2(sch_1):m_c_dqs_dp" )
			)
			( bus "M_C_ECC"
				( memberType ( signal ) )
				( member ( signalRef "M_C_ECC<0>") )
				( member ( signalRef "M_C_ECC<1>") )
				( member ( signalRef "M_C_ECC<2>") )
				( member ( signalRef "M_C_ECC<3>") )
				( member ( signalRef "M_C_ECC<4>") )
				( member ( signalRef "M_C_ECC<5>") )
				( member ( signalRef "M_C_ECC<6>") )
				( member ( signalRef "M_C_ECC<7>") )
				( objectStatus "@baseboard_fab2_lib.baseboard_fab2(sch_1):m_c_ecc" )
			)
			( bus "M_C_MA"
				( memberType ( signal ) )
				( member ( signalRef "M_C_MA<0>") )
				( member ( signalRef "M_C_MA<1>") )
				( member ( signalRef "M_C_MA<2>") )
				( member ( signalRef "M_C_MA<3>") )
				( member ( signalRef "M_C_MA<4>") )
				( member ( signalRef "M_C_MA<5>") )
				( member ( signalRef "M_C_MA<6>") )
				( member ( signalRef "M_C_MA<7>") )
				( member ( signalRef "M_C_MA<8>") )
				( member ( signalRef "M_C_MA<9>") )
				( member ( signalRef "M_C_MA<10>") )
				( member ( signalRef "M_C_MA<11>") )
				( member ( signalRef "M_C_MA<12>") )
				( member ( signalRef "M_C_MA<13>") )
				( member ( signalRef "M_C_MA<14>") )
				( member ( signalRef "M_C_MA<15>") )
				( member ( signalRef "M_C_MA<16>") )
				( member ( signalRef "M_C_MA<17>") )
				( objectStatus "@baseboard_fab2_lib.baseboard_fab2(sch_1):m_c_ma" )
			)
			( bus "M_C_ODT"
				( memberType ( signal ) )
				( member ( signalRef "M_C_ODT<0>") )
				( member ( signalRef "M_C_ODT<1>") )
				( member ( signalRef "M_C_ODT<2>") )
				( member ( signalRef "M_C_ODT<3>") )
				( objectStatus "@baseboard_fab2_lib.baseboard_fab2(sch_1):m_c_odt" )
			)
			( bus "M_D_BA"
				( memberType ( signal ) )
				( member ( signalRef "M_D_BA<0>") )
				( member ( signalRef "M_D_BA<1>") )
				( objectStatus "@baseboard_fab2_lib.baseboard_fab2(sch_1):m_d_ba" )
			)
			( bus "M_D_BG"
				( memberType ( signal ) )
				( member ( signalRef "M_D_BG<0>") )
				( member ( signalRef "M_D_BG<1>") )
				( objectStatus "@baseboard_fab2_lib.baseboard_fab2(sch_1):m_d_bg" )
			)
			( bus "M_D_C"
				( memberType ( signal ) )
				( member ( signalRef "M_D_C<2>") )
				( objectStatus "@baseboard_fab2_lib.baseboard_fab2(sch_1):m_d_c" )
			)
			( bus "M_D_CKE"
				( memberType ( signal ) )
				( member ( signalRef "M_D_CKE<0>") )
				( member ( signalRef "M_D_CKE<1>") )
				( member ( signalRef "M_D_CKE<2>") )
				( member ( signalRef "M_D_CKE<3>") )
				( objectStatus "@baseboard_fab2_lib.baseboard_fab2(sch_1):m_d_cke" )
			)
			( bus "M_D_CLK_DN"
				( memberType ( signal ) )
				( member ( signalRef "M_D_CLK_DN<0>") )
				( member ( signalRef "M_D_CLK_DN<1>") )
				( member ( signalRef "M_D_CLK_DN<2>") )
				( member ( signalRef "M_D_CLK_DN<3>") )
				( objectStatus "@baseboard_fab2_lib.baseboard_fab2(sch_1):m_d_clk_dn" )
			)
			( bus "M_D_CLK_DP"
				( memberType ( signal ) )
				( member ( signalRef "M_D_CLK_DP<0>") )
				( member ( signalRef "M_D_CLK_DP<1>") )
				( member ( signalRef "M_D_CLK_DP<2>") )
				( member ( signalRef "M_D_CLK_DP<3>") )
				( objectStatus "@baseboard_fab2_lib.baseboard_fab2(sch_1):m_d_clk_dp" )
			)
			( bus "M_D_CS_N"
				( memberType ( signal ) )
				( member ( signalRef "M_D_CS_N<0>") )
				( member ( signalRef "M_D_CS_N<1>") )
				( member ( signalRef "M_D_CS_N<2>") )
				( member ( signalRef "M_D_CS_N<3>") )
				( member ( signalRef "M_D_CS_N<4>") )
				( member ( signalRef "M_D_CS_N<5>") )
				( member ( signalRef "M_D_CS_N<6>") )
				( member ( signalRef "M_D_CS_N<7>") )
				( objectStatus "@baseboard_fab2_lib.baseboard_fab2(sch_1):m_d_cs_n" )
			)
			( bus "M_D_DQ"
				( memberType ( signal ) )
				( member ( signalRef "M_D_DQ<0>") )
				( member ( signalRef "M_D_DQ<1>") )
				( member ( signalRef "M_D_DQ<2>") )
				( member ( signalRef "M_D_DQ<3>") )
				( member ( signalRef "M_D_DQ<4>") )
				( member ( signalRef "M_D_DQ<5>") )
				( member ( signalRef "M_D_DQ<6>") )
				( member ( signalRef "M_D_DQ<7>") )
				( member ( signalRef "M_D_DQ<8>") )
				( member ( signalRef "M_D_DQ<9>") )
				( member ( signalRef "M_D_DQ<10>") )
				( member ( signalRef "M_D_DQ<11>") )
				( member ( signalRef "M_D_DQ<12>") )
				( member ( signalRef "M_D_DQ<13>") )
				( member ( signalRef "M_D_DQ<14>") )
				( member ( signalRef "M_D_DQ<15>") )
				( member ( signalRef "M_D_DQ<16>") )
				( member ( signalRef "M_D_DQ<17>") )
				( member ( signalRef "M_D_DQ<18>") )
				( member ( signalRef "M_D_DQ<19>") )
				( member ( signalRef "M_D_DQ<20>") )
				( member ( signalRef "M_D_DQ<21>") )
				( member ( signalRef "M_D_DQ<22>") )
				( member ( signalRef "M_D_DQ<23>") )
				( member ( signalRef "M_D_DQ<24>") )
				( member ( signalRef "M_D_DQ<25>") )
				( member ( signalRef "M_D_DQ<26>") )
				( member ( signalRef "M_D_DQ<27>") )
				( member ( signalRef "M_D_DQ<28>") )
				( member ( signalRef "M_D_DQ<29>") )
				( member ( signalRef "M_D_DQ<30>") )
				( member ( signalRef "M_D_DQ<31>") )
				( member ( signalRef "M_D_DQ<32>") )
				( member ( signalRef "M_D_DQ<33>") )
				( member ( signalRef "M_D_DQ<34>") )
				( member ( signalRef "M_D_DQ<35>") )
				( member ( signalRef "M_D_DQ<36>") )
				( member ( signalRef "M_D_DQ<37>") )
				( member ( signalRef "M_D_DQ<38>") )
				( member ( signalRef "M_D_DQ<39>") )
				( member ( signalRef "M_D_DQ<40>") )
				( member ( signalRef "M_D_DQ<41>") )
				( member ( signalRef "M_D_DQ<42>") )
				( member ( signalRef "M_D_DQ<43>") )
				( member ( signalRef "M_D_DQ<44>") )
				( member ( signalRef "M_D_DQ<45>") )
				( member ( signalRef "M_D_DQ<46>") )
				( member ( signalRef "M_D_DQ<47>") )
				( member ( signalRef "M_D_DQ<48>") )
				( member ( signalRef "M_D_DQ<49>") )
				( member ( signalRef "M_D_DQ<50>") )
				( member ( signalRef "M_D_DQ<51>") )
				( member ( signalRef "M_D_DQ<52>") )
				( member ( signalRef "M_D_DQ<53>") )
				( member ( signalRef "M_D_DQ<54>") )
				( member ( signalRef "M_D_DQ<55>") )
				( member ( signalRef "M_D_DQ<56>") )
				( member ( signalRef "M_D_DQ<57>") )
				( member ( signalRef "M_D_DQ<58>") )
				( member ( signalRef "M_D_DQ<59>") )
				( member ( signalRef "M_D_DQ<60>") )
				( member ( signalRef "M_D_DQ<61>") )
				( member ( signalRef "M_D_DQ<62>") )
				( member ( signalRef "M_D_DQ<63>") )
				( objectStatus "@baseboard_fab2_lib.baseboard_fab2(sch_1):m_d_dq" )
			)
			( bus "M_D_DQS_DN"
				( memberType ( signal ) )
				( member ( signalRef "M_D_DQS_DN<0>") )
				( member ( signalRef "M_D_DQS_DN<1>") )
				( member ( signalRef "M_D_DQS_DN<2>") )
				( member ( signalRef "M_D_DQS_DN<3>") )
				( member ( signalRef "M_D_DQS_DN<4>") )
				( member ( signalRef "M_D_DQS_DN<5>") )
				( member ( signalRef "M_D_DQS_DN<6>") )
				( member ( signalRef "M_D_DQS_DN<7>") )
				( member ( signalRef "M_D_DQS_DN<8>") )
				( member ( signalRef "M_D_DQS_DN<9>") )
				( member ( signalRef "M_D_DQS_DN<10>") )
				( member ( signalRef "M_D_DQS_DN<11>") )
				( member ( signalRef "M_D_DQS_DN<12>") )
				( member ( signalRef "M_D_DQS_DN<13>") )
				( member ( signalRef "M_D_DQS_DN<14>") )
				( member ( signalRef "M_D_DQS_DN<15>") )
				( member ( signalRef "M_D_DQS_DN<16>") )
				( member ( signalRef "M_D_DQS_DN<17>") )
				( objectStatus "@baseboard_fab2_lib.baseboard_fab2(sch_1):m_d_dqs_dn" )
			)
			( bus "M_D_DQS_DP"
				( memberType ( signal ) )
				( member ( signalRef "M_D_DQS_DP<0>") )
				( member ( signalRef "M_D_DQS_DP<1>") )
				( member ( signalRef "M_D_DQS_DP<2>") )
				( member ( signalRef "M_D_DQS_DP<3>") )
				( member ( signalRef "M_D_DQS_DP<4>") )
				( member ( signalRef "M_D_DQS_DP<5>") )
				( member ( signalRef "M_D_DQS_DP<6>") )
				( member ( signalRef "M_D_DQS_DP<7>") )
				( member ( signalRef "M_D_DQS_DP<8>") )
				( member ( signalRef "M_D_DQS_DP<9>") )
				( member ( signalRef "M_D_DQS_DP<10>") )
				( member ( signalRef "M_D_DQS_DP<11>") )
				( member ( signalRef "M_D_DQS_DP<12>") )
				( member ( signalRef "M_D_DQS_DP<13>") )
				( member ( signalRef "M_D_DQS_DP<14>") )
				( member ( signalRef "M_D_DQS_DP<15>") )
				( member ( signalRef "M_D_DQS_DP<16>") )
				( member ( signalRef "M_D_DQS_DP<17>") )
				( objectStatus "@baseboard_fab2_lib.baseboard_fab2(sch_1):m_d_dqs_dp" )
			)
			( bus "M_D_ECC"
				( memberType ( signal ) )
				( member ( signalRef "M_D_ECC<0>") )
				( member ( signalRef "M_D_ECC<1>") )
				( member ( signalRef "M_D_ECC<2>") )
				( member ( signalRef "M_D_ECC<3>") )
				( member ( signalRef "M_D_ECC<4>") )
				( member ( signalRef "M_D_ECC<5>") )
				( member ( signalRef "M_D_ECC<6>") )
				( member ( signalRef "M_D_ECC<7>") )
				( objectStatus "@baseboard_fab2_lib.baseboard_fab2(sch_1):m_d_ecc" )
			)
			( bus "M_D_MA"
				( memberType ( signal ) )
				( member ( signalRef "M_D_MA<0>") )
				( member ( signalRef "M_D_MA<1>") )
				( member ( signalRef "M_D_MA<2>") )
				( member ( signalRef "M_D_MA<3>") )
				( member ( signalRef "M_D_MA<4>") )
				( member ( signalRef "M_D_MA<5>") )
				( member ( signalRef "M_D_MA<6>") )
				( member ( signalRef "M_D_MA<7>") )
				( member ( signalRef "M_D_MA<8>") )
				( member ( signalRef "M_D_MA<9>") )
				( member ( signalRef "M_D_MA<10>") )
				( member ( signalRef "M_D_MA<11>") )
				( member ( signalRef "M_D_MA<12>") )
				( member ( signalRef "M_D_MA<13>") )
				( member ( signalRef "M_D_MA<14>") )
				( member ( signalRef "M_D_MA<15>") )
				( member ( signalRef "M_D_MA<16>") )
				( member ( signalRef "M_D_MA<17>") )
				( objectStatus "@baseboard_fab2_lib.baseboard_fab2(sch_1):m_d_ma" )
			)
			( bus "M_D_ODT"
				( memberType ( signal ) )
				( member ( signalRef "M_D_ODT<0>") )
				( member ( signalRef "M_D_ODT<1>") )
				( member ( signalRef "M_D_ODT<2>") )
				( member ( signalRef "M_D_ODT<3>") )
				( objectStatus "@baseboard_fab2_lib.baseboard_fab2(sch_1):m_d_odt" )
			)
			( bus "M_E_BA"
				( memberType ( signal ) )
				( member ( signalRef "M_E_BA<0>") )
				( member ( signalRef "M_E_BA<1>") )
				( objectStatus "@baseboard_fab2_lib.baseboard_fab2(sch_1):m_e_ba" )
			)
			( bus "M_E_BG"
				( memberType ( signal ) )
				( member ( signalRef "M_E_BG<0>") )
				( member ( signalRef "M_E_BG<1>") )
				( objectStatus "@baseboard_fab2_lib.baseboard_fab2(sch_1):m_e_bg" )
			)
			( bus "M_E_C"
				( memberType ( signal ) )
				( member ( signalRef "M_E_C<2>") )
				( objectStatus "@baseboard_fab2_lib.baseboard_fab2(sch_1):m_e_c" )
			)
			( bus "M_E_CKE"
				( memberType ( signal ) )
				( member ( signalRef "M_E_CKE<0>") )
				( member ( signalRef "M_E_CKE<1>") )
				( member ( signalRef "M_E_CKE<2>") )
				( member ( signalRef "M_E_CKE<3>") )
				( objectStatus "@baseboard_fab2_lib.baseboard_fab2(sch_1):m_e_cke" )
			)
			( bus "M_E_CLK_DN"
				( memberType ( signal ) )
				( member ( signalRef "M_E_CLK_DN<0>") )
				( member ( signalRef "M_E_CLK_DN<1>") )
				( member ( signalRef "M_E_CLK_DN<2>") )
				( member ( signalRef "M_E_CLK_DN<3>") )
				( objectStatus "@baseboard_fab2_lib.baseboard_fab2(sch_1):m_e_clk_dn" )
			)
			( bus "M_E_CLK_DP"
				( memberType ( signal ) )
				( member ( signalRef "M_E_CLK_DP<0>") )
				( member ( signalRef "M_E_CLK_DP<1>") )
				( member ( signalRef "M_E_CLK_DP<2>") )
				( member ( signalRef "M_E_CLK_DP<3>") )
				( objectStatus "@baseboard_fab2_lib.baseboard_fab2(sch_1):m_e_clk_dp" )
			)
			( bus "M_E_CS_N"
				( memberType ( signal ) )
				( member ( signalRef "M_E_CS_N<0>") )
				( member ( signalRef "M_E_CS_N<1>") )
				( member ( signalRef "M_E_CS_N<2>") )
				( member ( signalRef "M_E_CS_N<3>") )
				( member ( signalRef "M_E_CS_N<4>") )
				( member ( signalRef "M_E_CS_N<5>") )
				( member ( signalRef "M_E_CS_N<6>") )
				( member ( signalRef "M_E_CS_N<7>") )
				( objectStatus "@baseboard_fab2_lib.baseboard_fab2(sch_1):m_e_cs_n" )
			)
			( bus "M_E_DQ"
				( memberType ( signal ) )
				( member ( signalRef "M_E_DQ<0>") )
				( member ( signalRef "M_E_DQ<1>") )
				( member ( signalRef "M_E_DQ<2>") )
				( member ( signalRef "M_E_DQ<3>") )
				( member ( signalRef "M_E_DQ<4>") )
				( member ( signalRef "M_E_DQ<5>") )
				( member ( signalRef "M_E_DQ<6>") )
				( member ( signalRef "M_E_DQ<7>") )
				( member ( signalRef "M_E_DQ<8>") )
				( member ( signalRef "M_E_DQ<9>") )
				( member ( signalRef "M_E_DQ<10>") )
				( member ( signalRef "M_E_DQ<11>") )
				( member ( signalRef "M_E_DQ<12>") )
				( member ( signalRef "M_E_DQ<13>") )
				( member ( signalRef "M_E_DQ<14>") )
				( member ( signalRef "M_E_DQ<15>") )
				( member ( signalRef "M_E_DQ<16>") )
				( member ( signalRef "M_E_DQ<17>") )
				( member ( signalRef "M_E_DQ<18>") )
				( member ( signalRef "M_E_DQ<19>") )
				( member ( signalRef "M_E_DQ<20>") )
				( member ( signalRef "M_E_DQ<21>") )
				( member ( signalRef "M_E_DQ<22>") )
				( member ( signalRef "M_E_DQ<23>") )
				( member ( signalRef "M_E_DQ<24>") )
				( member ( signalRef "M_E_DQ<25>") )
				( member ( signalRef "M_E_DQ<26>") )
				( member ( signalRef "M_E_DQ<27>") )
				( member ( signalRef "M_E_DQ<28>") )
				( member ( signalRef "M_E_DQ<29>") )
				( member ( signalRef "M_E_DQ<30>") )
				( member ( signalRef "M_E_DQ<31>") )
				( member ( signalRef "M_E_DQ<32>") )
				( member ( signalRef "M_E_DQ<33>") )
				( member ( signalRef "M_E_DQ<34>") )
				( member ( signalRef "M_E_DQ<35>") )
				( member ( signalRef "M_E_DQ<36>") )
				( member ( signalRef "M_E_DQ<37>") )
				( member ( signalRef "M_E_DQ<38>") )
				( member ( signalRef "M_E_DQ<39>") )
				( member ( signalRef "M_E_DQ<40>") )
				( member ( signalRef "M_E_DQ<41>") )
				( member ( signalRef "M_E_DQ<42>") )
				( member ( signalRef "M_E_DQ<43>") )
				( member ( signalRef "M_E_DQ<44>") )
				( member ( signalRef "M_E_DQ<45>") )
				( member ( signalRef "M_E_DQ<46>") )
				( member ( signalRef "M_E_DQ<47>") )
				( member ( signalRef "M_E_DQ<48>") )
				( member ( signalRef "M_E_DQ<49>") )
				( member ( signalRef "M_E_DQ<50>") )
				( member ( signalRef "M_E_DQ<51>") )
				( member ( signalRef "M_E_DQ<52>") )
				( member ( signalRef "M_E_DQ<53>") )
				( member ( signalRef "M_E_DQ<54>") )
				( member ( signalRef "M_E_DQ<55>") )
				( member ( signalRef "M_E_DQ<56>") )
				( member ( signalRef "M_E_DQ<57>") )
				( member ( signalRef "M_E_DQ<58>") )
				( member ( signalRef "M_E_DQ<59>") )
				( member ( signalRef "M_E_DQ<60>") )
				( member ( signalRef "M_E_DQ<61>") )
				( member ( signalRef "M_E_DQ<62>") )
				( member ( signalRef "M_E_DQ<63>") )
				( objectStatus "@baseboard_fab2_lib.baseboard_fab2(sch_1):m_e_dq" )
			)
			( bus "M_E_DQS_DN"
				( memberType ( signal ) )
				( member ( signalRef "M_E_DQS_DN<0>") )
				( member ( signalRef "M_E_DQS_DN<1>") )
				( member ( signalRef "M_E_DQS_DN<2>") )
				( member ( signalRef "M_E_DQS_DN<3>") )
				( member ( signalRef "M_E_DQS_DN<4>") )
				( member ( signalRef "M_E_DQS_DN<5>") )
				( member ( signalRef "M_E_DQS_DN<6>") )
				( member ( signalRef "M_E_DQS_DN<7>") )
				( member ( signalRef "M_E_DQS_DN<8>") )
				( member ( signalRef "M_E_DQS_DN<9>") )
				( member ( signalRef "M_E_DQS_DN<10>") )
				( member ( signalRef "M_E_DQS_DN<11>") )
				( member ( signalRef "M_E_DQS_DN<12>") )
				( member ( signalRef "M_E_DQS_DN<13>") )
				( member ( signalRef "M_E_DQS_DN<14>") )
				( member ( signalRef "M_E_DQS_DN<15>") )
				( member ( signalRef "M_E_DQS_DN<16>") )
				( member ( signalRef "M_E_DQS_DN<17>") )
				( objectStatus "@baseboard_fab2_lib.baseboard_fab2(sch_1):m_e_dqs_dn" )
			)
			( bus "M_E_DQS_DP"
				( memberType ( signal ) )
				( member ( signalRef "M_E_DQS_DP<0>") )
				( member ( signalRef "M_E_DQS_DP<1>") )
				( member ( signalRef "M_E_DQS_DP<2>") )
				( member ( signalRef "M_E_DQS_DP<3>") )
				( member ( signalRef "M_E_DQS_DP<4>") )
				( member ( signalRef "M_E_DQS_DP<5>") )
				( member ( signalRef "M_E_DQS_DP<6>") )
				( member ( signalRef "M_E_DQS_DP<7>") )
				( member ( signalRef "M_E_DQS_DP<8>") )
				( member ( signalRef "M_E_DQS_DP<9>") )
				( member ( signalRef "M_E_DQS_DP<10>") )
				( member ( signalRef "M_E_DQS_DP<11>") )
				( member ( signalRef "M_E_DQS_DP<12>") )
				( member ( signalRef "M_E_DQS_DP<13>") )
				( member ( signalRef "M_E_DQS_DP<14>") )
				( member ( signalRef "M_E_DQS_DP<15>") )
				( member ( signalRef "M_E_DQS_DP<16>") )
				( member ( signalRef "M_E_DQS_DP<17>") )
				( objectStatus "@baseboard_fab2_lib.baseboard_fab2(sch_1):m_e_dqs_dp" )
			)
			( bus "M_E_ECC"
				( memberType ( signal ) )
				( member ( signalRef "M_E_ECC<0>") )
				( member ( signalRef "M_E_ECC<1>") )
				( member ( signalRef "M_E_ECC<2>") )
				( member ( signalRef "M_E_ECC<3>") )
				( member ( signalRef "M_E_ECC<4>") )
				( member ( signalRef "M_E_ECC<5>") )
				( member ( signalRef "M_E_ECC<6>") )
				( member ( signalRef "M_E_ECC<7>") )
				( objectStatus "@baseboard_fab2_lib.baseboard_fab2(sch_1):m_e_ecc" )
			)
			( bus "M_E_MA"
				( memberType ( signal ) )
				( member ( signalRef "M_E_MA<0>") )
				( member ( signalRef "M_E_MA<1>") )
				( member ( signalRef "M_E_MA<2>") )
				( member ( signalRef "M_E_MA<3>") )
				( member ( signalRef "M_E_MA<4>") )
				( member ( signalRef "M_E_MA<5>") )
				( member ( signalRef "M_E_MA<6>") )
				( member ( signalRef "M_E_MA<7>") )
				( member ( signalRef "M_E_MA<8>") )
				( member ( signalRef "M_E_MA<9>") )
				( member ( signalRef "M_E_MA<10>") )
				( member ( signalRef "M_E_MA<11>") )
				( member ( signalRef "M_E_MA<12>") )
				( member ( signalRef "M_E_MA<13>") )
				( member ( signalRef "M_E_MA<14>") )
				( member ( signalRef "M_E_MA<15>") )
				( member ( signalRef "M_E_MA<16>") )
				( member ( signalRef "M_E_MA<17>") )
				( objectStatus "@baseboard_fab2_lib.baseboard_fab2(sch_1):m_e_ma" )
			)
			( bus "M_E_ODT"
				( memberType ( signal ) )
				( member ( signalRef "M_E_ODT<0>") )
				( member ( signalRef "M_E_ODT<1>") )
				( member ( signalRef "M_E_ODT<2>") )
				( member ( signalRef "M_E_ODT<3>") )
				( objectStatus "@baseboard_fab2_lib.baseboard_fab2(sch_1):m_e_odt" )
			)
			( bus "M_F_BA"
				( memberType ( signal ) )
				( member ( signalRef "M_F_BA<0>") )
				( member ( signalRef "M_F_BA<1>") )
				( objectStatus "@baseboard_fab2_lib.baseboard_fab2(sch_1):m_f_ba" )
			)
			( bus "M_F_BG"
				( memberType ( signal ) )
				( member ( signalRef "M_F_BG<0>") )
				( member ( signalRef "M_F_BG<1>") )
				( objectStatus "@baseboard_fab2_lib.baseboard_fab2(sch_1):m_f_bg" )
			)
			( bus "M_F_C"
				( memberType ( signal ) )
				( member ( signalRef "M_F_C<2>") )
				( objectStatus "@baseboard_fab2_lib.baseboard_fab2(sch_1):m_f_c" )
			)
			( bus "M_F_CKE"
				( memberType ( signal ) )
				( member ( signalRef "M_F_CKE<0>") )
				( member ( signalRef "M_F_CKE<1>") )
				( member ( signalRef "M_F_CKE<2>") )
				( member ( signalRef "M_F_CKE<3>") )
				( objectStatus "@baseboard_fab2_lib.baseboard_fab2(sch_1):m_f_cke" )
			)
			( bus "M_F_CLK_DN"
				( memberType ( signal ) )
				( member ( signalRef "M_F_CLK_DN<0>") )
				( member ( signalRef "M_F_CLK_DN<1>") )
				( member ( signalRef "M_F_CLK_DN<2>") )
				( member ( signalRef "M_F_CLK_DN<3>") )
				( objectStatus "@baseboard_fab2_lib.baseboard_fab2(sch_1):m_f_clk_dn" )
			)
			( bus "M_F_CLK_DP"
				( memberType ( signal ) )
				( member ( signalRef "M_F_CLK_DP<0>") )
				( member ( signalRef "M_F_CLK_DP<1>") )
				( member ( signalRef "M_F_CLK_DP<2>") )
				( member ( signalRef "M_F_CLK_DP<3>") )
				( objectStatus "@baseboard_fab2_lib.baseboard_fab2(sch_1):m_f_clk_dp" )
			)
			( bus "M_F_CS_N"
				( memberType ( signal ) )
				( member ( signalRef "M_F_CS_N<0>") )
				( member ( signalRef "M_F_CS_N<1>") )
				( member ( signalRef "M_F_CS_N<2>") )
				( member ( signalRef "M_F_CS_N<3>") )
				( member ( signalRef "M_F_CS_N<4>") )
				( member ( signalRef "M_F_CS_N<5>") )
				( member ( signalRef "M_F_CS_N<6>") )
				( member ( signalRef "M_F_CS_N<7>") )
				( objectStatus "@baseboard_fab2_lib.baseboard_fab2(sch_1):m_f_cs_n" )
			)
			( bus "M_F_DQ"
				( memberType ( signal ) )
				( member ( signalRef "M_F_DQ<0>") )
				( member ( signalRef "M_F_DQ<1>") )
				( member ( signalRef "M_F_DQ<2>") )
				( member ( signalRef "M_F_DQ<3>") )
				( member ( signalRef "M_F_DQ<4>") )
				( member ( signalRef "M_F_DQ<5>") )
				( member ( signalRef "M_F_DQ<6>") )
				( member ( signalRef "M_F_DQ<7>") )
				( member ( signalRef "M_F_DQ<8>") )
				( member ( signalRef "M_F_DQ<9>") )
				( member ( signalRef "M_F_DQ<10>") )
				( member ( signalRef "M_F_DQ<11>") )
				( member ( signalRef "M_F_DQ<12>") )
				( member ( signalRef "M_F_DQ<13>") )
				( member ( signalRef "M_F_DQ<14>") )
				( member ( signalRef "M_F_DQ<15>") )
				( member ( signalRef "M_F_DQ<16>") )
				( member ( signalRef "M_F_DQ<17>") )
				( member ( signalRef "M_F_DQ<18>") )
				( member ( signalRef "M_F_DQ<19>") )
				( member ( signalRef "M_F_DQ<20>") )
				( member ( signalRef "M_F_DQ<21>") )
				( member ( signalRef "M_F_DQ<22>") )
				( member ( signalRef "M_F_DQ<23>") )
				( member ( signalRef "M_F_DQ<24>") )
				( member ( signalRef "M_F_DQ<25>") )
				( member ( signalRef "M_F_DQ<26>") )
				( member ( signalRef "M_F_DQ<27>") )
				( member ( signalRef "M_F_DQ<28>") )
				( member ( signalRef "M_F_DQ<29>") )
				( member ( signalRef "M_F_DQ<30>") )
				( member ( signalRef "M_F_DQ<31>") )
				( member ( signalRef "M_F_DQ<32>") )
				( member ( signalRef "M_F_DQ<33>") )
				( member ( signalRef "M_F_DQ<34>") )
				( member ( signalRef "M_F_DQ<35>") )
				( member ( signalRef "M_F_DQ<36>") )
				( member ( signalRef "M_F_DQ<37>") )
				( member ( signalRef "M_F_DQ<38>") )
				( member ( signalRef "M_F_DQ<39>") )
				( member ( signalRef "M_F_DQ<40>") )
				( member ( signalRef "M_F_DQ<41>") )
				( member ( signalRef "M_F_DQ<42>") )
				( member ( signalRef "M_F_DQ<43>") )
				( member ( signalRef "M_F_DQ<44>") )
				( member ( signalRef "M_F_DQ<45>") )
				( member ( signalRef "M_F_DQ<46>") )
				( member ( signalRef "M_F_DQ<47>") )
				( member ( signalRef "M_F_DQ<48>") )
				( member ( signalRef "M_F_DQ<49>") )
				( member ( signalRef "M_F_DQ<50>") )
				( member ( signalRef "M_F_DQ<51>") )
				( member ( signalRef "M_F_DQ<52>") )
				( member ( signalRef "M_F_DQ<53>") )
				( member ( signalRef "M_F_DQ<54>") )
				( member ( signalRef "M_F_DQ<55>") )
				( member ( signalRef "M_F_DQ<56>") )
				( member ( signalRef "M_F_DQ<57>") )
				( member ( signalRef "M_F_DQ<58>") )
				( member ( signalRef "M_F_DQ<59>") )
				( member ( signalRef "M_F_DQ<60>") )
				( member ( signalRef "M_F_DQ<61>") )
				( member ( signalRef "M_F_DQ<62>") )
				( member ( signalRef "M_F_DQ<63>") )
				( objectStatus "@baseboard_fab2_lib.baseboard_fab2(sch_1):m_f_dq" )
			)
			( bus "M_F_DQS_DN"
				( memberType ( signal ) )
				( member ( signalRef "M_F_DQS_DN<0>") )
				( member ( signalRef "M_F_DQS_DN<1>") )
				( member ( signalRef "M_F_DQS_DN<2>") )
				( member ( signalRef "M_F_DQS_DN<3>") )
				( member ( signalRef "M_F_DQS_DN<4>") )
				( member ( signalRef "M_F_DQS_DN<5>") )
				( member ( signalRef "M_F_DQS_DN<6>") )
				( member ( signalRef "M_F_DQS_DN<7>") )
				( member ( signalRef "M_F_DQS_DN<8>") )
				( member ( signalRef "M_F_DQS_DN<9>") )
				( member ( signalRef "M_F_DQS_DN<10>") )
				( member ( signalRef "M_F_DQS_DN<11>") )
				( member ( signalRef "M_F_DQS_DN<12>") )
				( member ( signalRef "M_F_DQS_DN<13>") )
				( member ( signalRef "M_F_DQS_DN<14>") )
				( member ( signalRef "M_F_DQS_DN<15>") )
				( member ( signalRef "M_F_DQS_DN<16>") )
				( member ( signalRef "M_F_DQS_DN<17>") )
				( objectStatus "@baseboard_fab2_lib.baseboard_fab2(sch_1):m_f_dqs_dn" )
			)
			( bus "M_F_DQS_DP"
				( memberType ( signal ) )
				( member ( signalRef "M_F_DQS_DP<0>") )
				( member ( signalRef "M_F_DQS_DP<1>") )
				( member ( signalRef "M_F_DQS_DP<2>") )
				( member ( signalRef "M_F_DQS_DP<3>") )
				( member ( signalRef "M_F_DQS_DP<4>") )
				( member ( signalRef "M_F_DQS_DP<5>") )
				( member ( signalRef "M_F_DQS_DP<6>") )
				( member ( signalRef "M_F_DQS_DP<7>") )
				( member ( signalRef "M_F_DQS_DP<8>") )
				( member ( signalRef "M_F_DQS_DP<9>") )
				( member ( signalRef "M_F_DQS_DP<10>") )
				( member ( signalRef "M_F_DQS_DP<11>") )
				( member ( signalRef "M_F_DQS_DP<12>") )
				( member ( signalRef "M_F_DQS_DP<13>") )
				( member ( signalRef "M_F_DQS_DP<14>") )
				( member ( signalRef "M_F_DQS_DP<15>") )
				( member ( signalRef "M_F_DQS_DP<16>") )
				( member ( signalRef "M_F_DQS_DP<17>") )
				( objectStatus "@baseboard_fab2_lib.baseboard_fab2(sch_1):m_f_dqs_dp" )
			)
			( bus "M_F_ECC"
				( memberType ( signal ) )
				( member ( signalRef "M_F_ECC<0>") )
				( member ( signalRef "M_F_ECC<1>") )
				( member ( signalRef "M_F_ECC<2>") )
				( member ( signalRef "M_F_ECC<3>") )
				( member ( signalRef "M_F_ECC<4>") )
				( member ( signalRef "M_F_ECC<5>") )
				( member ( signalRef "M_F_ECC<6>") )
				( member ( signalRef "M_F_ECC<7>") )
				( objectStatus "@baseboard_fab2_lib.baseboard_fab2(sch_1):m_f_ecc" )
			)
			( bus "M_F_MA"
				( memberType ( signal ) )
				( member ( signalRef "M_F_MA<0>") )
				( member ( signalRef "M_F_MA<1>") )
				( member ( signalRef "M_F_MA<2>") )
				( member ( signalRef "M_F_MA<3>") )
				( member ( signalRef "M_F_MA<4>") )
				( member ( signalRef "M_F_MA<5>") )
				( member ( signalRef "M_F_MA<6>") )
				( member ( signalRef "M_F_MA<7>") )
				( member ( signalRef "M_F_MA<8>") )
				( member ( signalRef "M_F_MA<9>") )
				( member ( signalRef "M_F_MA<10>") )
				( member ( signalRef "M_F_MA<11>") )
				( member ( signalRef "M_F_MA<12>") )
				( member ( signalRef "M_F_MA<13>") )
				( member ( signalRef "M_F_MA<14>") )
				( member ( signalRef "M_F_MA<15>") )
				( member ( signalRef "M_F_MA<16>") )
				( member ( signalRef "M_F_MA<17>") )
				( objectStatus "@baseboard_fab2_lib.baseboard_fab2(sch_1):m_f_ma" )
			)
			( bus "M_F_ODT"
				( memberType ( signal ) )
				( member ( signalRef "M_F_ODT<0>") )
				( member ( signalRef "M_F_ODT<1>") )
				( member ( signalRef "M_F_ODT<2>") )
				( member ( signalRef "M_F_ODT<3>") )
				( objectStatus "@baseboard_fab2_lib.baseboard_fab2(sch_1):m_f_odt" )
			)
			( bus "DMI_CPU0_PCH_RX_C_DN"
				( memberType ( signal ) )
				( member ( signalRef "DMI_CPU0_PCH_RX_C_DN<0>") )
				( member ( signalRef "DMI_CPU0_PCH_RX_C_DN<1>") )
				( member ( signalRef "DMI_CPU0_PCH_RX_C_DN<2>") )
				( member ( signalRef "DMI_CPU0_PCH_RX_C_DN<3>") )
				( objectStatus "@baseboard_fab2_lib.baseboard_fab2(sch_1):dmi_cpu0_pch_rx_c_dn" )
			)
			( bus "DMI_CPU0_PCH_RX_C_DP"
				( memberType ( signal ) )
				( member ( signalRef "DMI_CPU0_PCH_RX_C_DP<0>") )
				( member ( signalRef "DMI_CPU0_PCH_RX_C_DP<1>") )
				( member ( signalRef "DMI_CPU0_PCH_RX_C_DP<2>") )
				( member ( signalRef "DMI_CPU0_PCH_RX_C_DP<3>") )
				( objectStatus "@baseboard_fab2_lib.baseboard_fab2(sch_1):dmi_cpu0_pch_rx_c_dp" )
			)
			( bus "DMI_CPU0_PCH_TX_DN"
				( memberType ( signal ) )
				( member ( signalRef "DMI_CPU0_PCH_TX_DN<0>") )
				( member ( signalRef "DMI_CPU0_PCH_TX_DN<1>") )
				( member ( signalRef "DMI_CPU0_PCH_TX_DN<2>") )
				( member ( signalRef "DMI_CPU0_PCH_TX_DN<3>") )
				( objectStatus "@baseboard_fab2_lib.baseboard_fab2(sch_1):dmi_cpu0_pch_tx_dn" )
			)
			( bus "DMI_CPU0_PCH_TX_DP"
				( memberType ( signal ) )
				( member ( signalRef "DMI_CPU0_PCH_TX_DP<0>") )
				( member ( signalRef "DMI_CPU0_PCH_TX_DP<1>") )
				( member ( signalRef "DMI_CPU0_PCH_TX_DP<2>") )
				( member ( signalRef "DMI_CPU0_PCH_TX_DP<3>") )
				( objectStatus "@baseboard_fab2_lib.baseboard_fab2(sch_1):dmi_cpu0_pch_tx_dp" )
			)
			( bus "P3E_CPU0_PE1_PCH_RXN"
				( memberType ( signal ) )
				( member ( signalRef "P3E_CPU0_PE1_PCH_RXN<8>") )
				( member ( signalRef "P3E_CPU0_PE1_PCH_RXN<9>") )
				( member ( signalRef "P3E_CPU0_PE1_PCH_RXN<10>") )
				( member ( signalRef "P3E_CPU0_PE1_PCH_RXN<11>") )
				( member ( signalRef "P3E_CPU0_PE1_PCH_RXN<12>") )
				( member ( signalRef "P3E_CPU0_PE1_PCH_RXN<13>") )
				( member ( signalRef "P3E_CPU0_PE1_PCH_RXN<14>") )
				( member ( signalRef "P3E_CPU0_PE1_PCH_RXN<15>") )
				( member ( signalRef "P3E_CPU0_PE1_PCH_RXN<0>") )
				( member ( signalRef "P3E_CPU0_PE1_PCH_RXN<1>") )
				( member ( signalRef "P3E_CPU0_PE1_PCH_RXN<2>") )
				( member ( signalRef "P3E_CPU0_PE1_PCH_RXN<3>") )
				( member ( signalRef "P3E_CPU0_PE1_PCH_RXN<4>") )
				( member ( signalRef "P3E_CPU0_PE1_PCH_RXN<5>") )
				( member ( signalRef "P3E_CPU0_PE1_PCH_RXN<6>") )
				( member ( signalRef "P3E_CPU0_PE1_PCH_RXN<7>") )
				( objectStatus "@baseboard_fab2_lib.baseboard_fab2(sch_1):p3e_cpu0_pe1_pch_rxn" )
			)
			( bus "P3E_CPU0_PE1_PCH_RXP"
				( memberType ( signal ) )
				( member ( signalRef "P3E_CPU0_PE1_PCH_RXP<8>") )
				( member ( signalRef "P3E_CPU0_PE1_PCH_RXP<9>") )
				( member ( signalRef "P3E_CPU0_PE1_PCH_RXP<10>") )
				( member ( signalRef "P3E_CPU0_PE1_PCH_RXP<11>") )
				( member ( signalRef "P3E_CPU0_PE1_PCH_RXP<12>") )
				( member ( signalRef "P3E_CPU0_PE1_PCH_RXP<13>") )
				( member ( signalRef "P3E_CPU0_PE1_PCH_RXP<14>") )
				( member ( signalRef "P3E_CPU0_PE1_PCH_RXP<15>") )
				( member ( signalRef "P3E_CPU0_PE1_PCH_RXP<0>") )
				( member ( signalRef "P3E_CPU0_PE1_PCH_RXP<1>") )
				( member ( signalRef "P3E_CPU0_PE1_PCH_RXP<2>") )
				( member ( signalRef "P3E_CPU0_PE1_PCH_RXP<3>") )
				( member ( signalRef "P3E_CPU0_PE1_PCH_RXP<4>") )
				( member ( signalRef "P3E_CPU0_PE1_PCH_RXP<5>") )
				( member ( signalRef "P3E_CPU0_PE1_PCH_RXP<6>") )
				( member ( signalRef "P3E_CPU0_PE1_PCH_RXP<7>") )
				( objectStatus "@baseboard_fab2_lib.baseboard_fab2(sch_1):p3e_cpu0_pe1_pch_rxp" )
			)
			( bus "P3E_CPU0_PE1_PCH_TXN"
				( memberType ( signal ) )
				( member ( signalRef "P3E_CPU0_PE1_PCH_TXN<8>") )
				( member ( signalRef "P3E_CPU0_PE1_PCH_TXN<9>") )
				( member ( signalRef "P3E_CPU0_PE1_PCH_TXN<10>") )
				( member ( signalRef "P3E_CPU0_PE1_PCH_TXN<11>") )
				( member ( signalRef "P3E_CPU0_PE1_PCH_TXN<12>") )
				( member ( signalRef "P3E_CPU0_PE1_PCH_TXN<13>") )
				( member ( signalRef "P3E_CPU0_PE1_PCH_TXN<14>") )
				( member ( signalRef "P3E_CPU0_PE1_PCH_TXN<15>") )
				( member ( signalRef "P3E_CPU0_PE1_PCH_TXN<0>") )
				( member ( signalRef "P3E_CPU0_PE1_PCH_TXN<1>") )
				( member ( signalRef "P3E_CPU0_PE1_PCH_TXN<2>") )
				( member ( signalRef "P3E_CPU0_PE1_PCH_TXN<3>") )
				( member ( signalRef "P3E_CPU0_PE1_PCH_TXN<4>") )
				( member ( signalRef "P3E_CPU0_PE1_PCH_TXN<5>") )
				( member ( signalRef "P3E_CPU0_PE1_PCH_TXN<6>") )
				( member ( signalRef "P3E_CPU0_PE1_PCH_TXN<7>") )
				( objectStatus "@baseboard_fab2_lib.baseboard_fab2(sch_1):p3e_cpu0_pe1_pch_txn" )
			)
			( bus "P3E_CPU0_PE1_PCH_TXP"
				( memberType ( signal ) )
				( member ( signalRef "P3E_CPU0_PE1_PCH_TXP<8>") )
				( member ( signalRef "P3E_CPU0_PE1_PCH_TXP<9>") )
				( member ( signalRef "P3E_CPU0_PE1_PCH_TXP<10>") )
				( member ( signalRef "P3E_CPU0_PE1_PCH_TXP<11>") )
				( member ( signalRef "P3E_CPU0_PE1_PCH_TXP<12>") )
				( member ( signalRef "P3E_CPU0_PE1_PCH_TXP<13>") )
				( member ( signalRef "P3E_CPU0_PE1_PCH_TXP<14>") )
				( member ( signalRef "P3E_CPU0_PE1_PCH_TXP<15>") )
				( member ( signalRef "P3E_CPU0_PE1_PCH_TXP<0>") )
				( member ( signalRef "P3E_CPU0_PE1_PCH_TXP<1>") )
				( member ( signalRef "P3E_CPU0_PE1_PCH_TXP<2>") )
				( member ( signalRef "P3E_CPU0_PE1_PCH_TXP<3>") )
				( member ( signalRef "P3E_CPU0_PE1_PCH_TXP<4>") )
				( member ( signalRef "P3E_CPU0_PE1_PCH_TXP<5>") )
				( member ( signalRef "P3E_CPU0_PE1_PCH_TXP<6>") )
				( member ( signalRef "P3E_CPU0_PE1_PCH_TXP<7>") )
				( objectStatus "@baseboard_fab2_lib.baseboard_fab2(sch_1):p3e_cpu0_pe1_pch_txp" )
			)
			( bus "P3E_CPU0_PE1_SS_RXN"
				( memberType ( signal ) )
				( member ( signalRef "P3E_CPU0_PE1_SS_RXN<0>") )
				( member ( signalRef "P3E_CPU0_PE1_SS_RXN<1>") )
				( member ( signalRef "P3E_CPU0_PE1_SS_RXN<2>") )
				( member ( signalRef "P3E_CPU0_PE1_SS_RXN<3>") )
				( member ( signalRef "P3E_CPU0_PE1_SS_RXN<4>") )
				( member ( signalRef "P3E_CPU0_PE1_SS_RXN<5>") )
				( member ( signalRef "P3E_CPU0_PE1_SS_RXN<6>") )
				( member ( signalRef "P3E_CPU0_PE1_SS_RXN<7>") )
				( objectStatus "@baseboard_fab2_lib.baseboard_fab2(sch_1):p3e_cpu0_pe1_ss_rxn" )
			)
			( bus "P3E_CPU0_PE1_SS_RXP"
				( memberType ( signal ) )
				( member ( signalRef "P3E_CPU0_PE1_SS_RXP<0>") )
				( member ( signalRef "P3E_CPU0_PE1_SS_RXP<1>") )
				( member ( signalRef "P3E_CPU0_PE1_SS_RXP<2>") )
				( member ( signalRef "P3E_CPU0_PE1_SS_RXP<3>") )
				( member ( signalRef "P3E_CPU0_PE1_SS_RXP<4>") )
				( member ( signalRef "P3E_CPU0_PE1_SS_RXP<5>") )
				( member ( signalRef "P3E_CPU0_PE1_SS_RXP<6>") )
				( member ( signalRef "P3E_CPU0_PE1_SS_RXP<7>") )
				( objectStatus "@baseboard_fab2_lib.baseboard_fab2(sch_1):p3e_cpu0_pe1_ss_rxp" )
			)
			( bus "P3E_CPU0_PE1_SS_TXN"
				( memberType ( signal ) )
				( member ( signalRef "P3E_CPU0_PE1_SS_TXN<0>") )
				( member ( signalRef "P3E_CPU0_PE1_SS_TXN<1>") )
				( member ( signalRef "P3E_CPU0_PE1_SS_TXN<2>") )
				( member ( signalRef "P3E_CPU0_PE1_SS_TXN<3>") )
				( member ( signalRef "P3E_CPU0_PE1_SS_TXN<4>") )
				( member ( signalRef "P3E_CPU0_PE1_SS_TXN<5>") )
				( member ( signalRef "P3E_CPU0_PE1_SS_TXN<6>") )
				( member ( signalRef "P3E_CPU0_PE1_SS_TXN<7>") )
				( objectStatus "@baseboard_fab2_lib.baseboard_fab2(sch_1):p3e_cpu0_pe1_ss_txn" )
			)
			( bus "P3E_CPU0_PE1_SS_TXP"
				( memberType ( signal ) )
				( member ( signalRef "P3E_CPU0_PE1_SS_TXP<0>") )
				( member ( signalRef "P3E_CPU0_PE1_SS_TXP<1>") )
				( member ( signalRef "P3E_CPU0_PE1_SS_TXP<2>") )
				( member ( signalRef "P3E_CPU0_PE1_SS_TXP<3>") )
				( member ( signalRef "P3E_CPU0_PE1_SS_TXP<4>") )
				( member ( signalRef "P3E_CPU0_PE1_SS_TXP<5>") )
				( member ( signalRef "P3E_CPU0_PE1_SS_TXP<6>") )
				( member ( signalRef "P3E_CPU0_PE1_SS_TXP<7>") )
				( objectStatus "@baseboard_fab2_lib.baseboard_fab2(sch_1):p3e_cpu0_pe1_ss_txp" )
			)
			( bus "P3E_CPU0_PE2_SS_RXN"
				( memberType ( signal ) )
				( member ( signalRef "P3E_CPU0_PE2_SS_RXN<0>") )
				( member ( signalRef "P3E_CPU0_PE2_SS_RXN<1>") )
				( member ( signalRef "P3E_CPU0_PE2_SS_RXN<2>") )
				( member ( signalRef "P3E_CPU0_PE2_SS_RXN<3>") )
				( member ( signalRef "P3E_CPU0_PE2_SS_RXN<4>") )
				( member ( signalRef "P3E_CPU0_PE2_SS_RXN<5>") )
				( member ( signalRef "P3E_CPU0_PE2_SS_RXN<6>") )
				( member ( signalRef "P3E_CPU0_PE2_SS_RXN<7>") )
				( member ( signalRef "P3E_CPU0_PE2_SS_RXN<8>") )
				( member ( signalRef "P3E_CPU0_PE2_SS_RXN<9>") )
				( member ( signalRef "P3E_CPU0_PE2_SS_RXN<10>") )
				( member ( signalRef "P3E_CPU0_PE2_SS_RXN<11>") )
				( member ( signalRef "P3E_CPU0_PE2_SS_RXN<12>") )
				( member ( signalRef "P3E_CPU0_PE2_SS_RXN<13>") )
				( member ( signalRef "P3E_CPU0_PE2_SS_RXN<14>") )
				( member ( signalRef "P3E_CPU0_PE2_SS_RXN<15>") )
				( objectStatus "@baseboard_fab2_lib.baseboard_fab2(sch_1):p3e_cpu0_pe2_ss_rxn" )
			)
			( bus "P3E_CPU0_PE2_SS_RXP"
				( memberType ( signal ) )
				( member ( signalRef "P3E_CPU0_PE2_SS_RXP<0>") )
				( member ( signalRef "P3E_CPU0_PE2_SS_RXP<1>") )
				( member ( signalRef "P3E_CPU0_PE2_SS_RXP<2>") )
				( member ( signalRef "P3E_CPU0_PE2_SS_RXP<3>") )
				( member ( signalRef "P3E_CPU0_PE2_SS_RXP<4>") )
				( member ( signalRef "P3E_CPU0_PE2_SS_RXP<5>") )
				( member ( signalRef "P3E_CPU0_PE2_SS_RXP<6>") )
				( member ( signalRef "P3E_CPU0_PE2_SS_RXP<7>") )
				( member ( signalRef "P3E_CPU0_PE2_SS_RXP<8>") )
				( member ( signalRef "P3E_CPU0_PE2_SS_RXP<9>") )
				( member ( signalRef "P3E_CPU0_PE2_SS_RXP<10>") )
				( member ( signalRef "P3E_CPU0_PE2_SS_RXP<11>") )
				( member ( signalRef "P3E_CPU0_PE2_SS_RXP<12>") )
				( member ( signalRef "P3E_CPU0_PE2_SS_RXP<13>") )
				( member ( signalRef "P3E_CPU0_PE2_SS_RXP<14>") )
				( member ( signalRef "P3E_CPU0_PE2_SS_RXP<15>") )
				( objectStatus "@baseboard_fab2_lib.baseboard_fab2(sch_1):p3e_cpu0_pe2_ss_rxp" )
			)
			( bus "P3E_CPU0_PE2_SS_TXN"
				( memberType ( signal ) )
				( member ( signalRef "P3E_CPU0_PE2_SS_TXN<0>") )
				( member ( signalRef "P3E_CPU0_PE2_SS_TXN<1>") )
				( member ( signalRef "P3E_CPU0_PE2_SS_TXN<2>") )
				( member ( signalRef "P3E_CPU0_PE2_SS_TXN<3>") )
				( member ( signalRef "P3E_CPU0_PE2_SS_TXN<4>") )
				( member ( signalRef "P3E_CPU0_PE2_SS_TXN<5>") )
				( member ( signalRef "P3E_CPU0_PE2_SS_TXN<6>") )
				( member ( signalRef "P3E_CPU0_PE2_SS_TXN<7>") )
				( member ( signalRef "P3E_CPU0_PE2_SS_TXN<8>") )
				( member ( signalRef "P3E_CPU0_PE2_SS_TXN<9>") )
				( member ( signalRef "P3E_CPU0_PE2_SS_TXN<10>") )
				( member ( signalRef "P3E_CPU0_PE2_SS_TXN<11>") )
				( member ( signalRef "P3E_CPU0_PE2_SS_TXN<12>") )
				( member ( signalRef "P3E_CPU0_PE2_SS_TXN<13>") )
				( member ( signalRef "P3E_CPU0_PE2_SS_TXN<14>") )
				( member ( signalRef "P3E_CPU0_PE2_SS_TXN<15>") )
				( objectStatus "@baseboard_fab2_lib.baseboard_fab2(sch_1):p3e_cpu0_pe2_ss_txn" )
			)
			( bus "P3E_CPU0_PE2_SS_TXP"
				( memberType ( signal ) )
				( member ( signalRef "P3E_CPU0_PE2_SS_TXP<0>") )
				( member ( signalRef "P3E_CPU0_PE2_SS_TXP<1>") )
				( member ( signalRef "P3E_CPU0_PE2_SS_TXP<2>") )
				( member ( signalRef "P3E_CPU0_PE2_SS_TXP<3>") )
				( member ( signalRef "P3E_CPU0_PE2_SS_TXP<4>") )
				( member ( signalRef "P3E_CPU0_PE2_SS_TXP<5>") )
				( member ( signalRef "P3E_CPU0_PE2_SS_TXP<6>") )
				( member ( signalRef "P3E_CPU0_PE2_SS_TXP<7>") )
				( member ( signalRef "P3E_CPU0_PE2_SS_TXP<8>") )
				( member ( signalRef "P3E_CPU0_PE2_SS_TXP<9>") )
				( member ( signalRef "P3E_CPU0_PE2_SS_TXP<10>") )
				( member ( signalRef "P3E_CPU0_PE2_SS_TXP<11>") )
				( member ( signalRef "P3E_CPU0_PE2_SS_TXP<12>") )
				( member ( signalRef "P3E_CPU0_PE2_SS_TXP<13>") )
				( member ( signalRef "P3E_CPU0_PE2_SS_TXP<14>") )
				( member ( signalRef "P3E_CPU0_PE2_SS_TXP<15>") )
				( objectStatus "@baseboard_fab2_lib.baseboard_fab2(sch_1):p3e_cpu0_pe2_ss_txp" )
			)
			( bus "P3E_CPU0_PE3_OCP_RXN"
				( memberType ( signal ) )
				( member ( signalRef "P3E_CPU0_PE3_OCP_RXN<0>") )
				( member ( signalRef "P3E_CPU0_PE3_OCP_RXN<1>") )
				( member ( signalRef "P3E_CPU0_PE3_OCP_RXN<2>") )
				( member ( signalRef "P3E_CPU0_PE3_OCP_RXN<3>") )
				( member ( signalRef "P3E_CPU0_PE3_OCP_RXN<4>") )
				( member ( signalRef "P3E_CPU0_PE3_OCP_RXN<5>") )
				( member ( signalRef "P3E_CPU0_PE3_OCP_RXN<6>") )
				( member ( signalRef "P3E_CPU0_PE3_OCP_RXN<7>") )
				( member ( signalRef "P3E_CPU0_PE3_OCP_RXN<8>") )
				( member ( signalRef "P3E_CPU0_PE3_OCP_RXN<9>") )
				( member ( signalRef "P3E_CPU0_PE3_OCP_RXN<10>") )
				( member ( signalRef "P3E_CPU0_PE3_OCP_RXN<11>") )
				( member ( signalRef "P3E_CPU0_PE3_OCP_RXN<12>") )
				( member ( signalRef "P3E_CPU0_PE3_OCP_RXN<13>") )
				( member ( signalRef "P3E_CPU0_PE3_OCP_RXN<14>") )
				( member ( signalRef "P3E_CPU0_PE3_OCP_RXN<15>") )
				( objectStatus "@baseboard_fab2_lib.baseboard_fab2(sch_1):p3e_cpu0_pe3_ocp_rxn" )
			)
			( bus "P3E_CPU0_PE3_OCP_RXP"
				( memberType ( signal ) )
				( member ( signalRef "P3E_CPU0_PE3_OCP_RXP<0>") )
				( member ( signalRef "P3E_CPU0_PE3_OCP_RXP<1>") )
				( member ( signalRef "P3E_CPU0_PE3_OCP_RXP<2>") )
				( member ( signalRef "P3E_CPU0_PE3_OCP_RXP<3>") )
				( member ( signalRef "P3E_CPU0_PE3_OCP_RXP<4>") )
				( member ( signalRef "P3E_CPU0_PE3_OCP_RXP<5>") )
				( member ( signalRef "P3E_CPU0_PE3_OCP_RXP<6>") )
				( member ( signalRef "P3E_CPU0_PE3_OCP_RXP<7>") )
				( member ( signalRef "P3E_CPU0_PE3_OCP_RXP<8>") )
				( member ( signalRef "P3E_CPU0_PE3_OCP_RXP<9>") )
				( member ( signalRef "P3E_CPU0_PE3_OCP_RXP<10>") )
				( member ( signalRef "P3E_CPU0_PE3_OCP_RXP<11>") )
				( member ( signalRef "P3E_CPU0_PE3_OCP_RXP<12>") )
				( member ( signalRef "P3E_CPU0_PE3_OCP_RXP<13>") )
				( member ( signalRef "P3E_CPU0_PE3_OCP_RXP<14>") )
				( member ( signalRef "P3E_CPU0_PE3_OCP_RXP<15>") )
				( objectStatus "@baseboard_fab2_lib.baseboard_fab2(sch_1):p3e_cpu0_pe3_ocp_rxp" )
			)
			( bus "P3E_CPU0_PE3_OCP_TXN"
				( memberType ( signal ) )
				( member ( signalRef "P3E_CPU0_PE3_OCP_TXN<0>") )
				( member ( signalRef "P3E_CPU0_PE3_OCP_TXN<1>") )
				( member ( signalRef "P3E_CPU0_PE3_OCP_TXN<2>") )
				( member ( signalRef "P3E_CPU0_PE3_OCP_TXN<3>") )
				( member ( signalRef "P3E_CPU0_PE3_OCP_TXN<4>") )
				( member ( signalRef "P3E_CPU0_PE3_OCP_TXN<5>") )
				( member ( signalRef "P3E_CPU0_PE3_OCP_TXN<6>") )
				( member ( signalRef "P3E_CPU0_PE3_OCP_TXN<7>") )
				( member ( signalRef "P3E_CPU0_PE3_OCP_TXN<8>") )
				( member ( signalRef "P3E_CPU0_PE3_OCP_TXN<9>") )
				( member ( signalRef "P3E_CPU0_PE3_OCP_TXN<10>") )
				( member ( signalRef "P3E_CPU0_PE3_OCP_TXN<11>") )
				( member ( signalRef "P3E_CPU0_PE3_OCP_TXN<12>") )
				( member ( signalRef "P3E_CPU0_PE3_OCP_TXN<13>") )
				( member ( signalRef "P3E_CPU0_PE3_OCP_TXN<14>") )
				( member ( signalRef "P3E_CPU0_PE3_OCP_TXN<15>") )
				( objectStatus "@baseboard_fab2_lib.baseboard_fab2(sch_1):p3e_cpu0_pe3_ocp_txn" )
			)
			( bus "P3E_CPU0_PE3_OCP_TXP"
				( memberType ( signal ) )
				( member ( signalRef "P3E_CPU0_PE3_OCP_TXP<0>") )
				( member ( signalRef "P3E_CPU0_PE3_OCP_TXP<1>") )
				( member ( signalRef "P3E_CPU0_PE3_OCP_TXP<2>") )
				( member ( signalRef "P3E_CPU0_PE3_OCP_TXP<3>") )
				( member ( signalRef "P3E_CPU0_PE3_OCP_TXP<4>") )
				( member ( signalRef "P3E_CPU0_PE3_OCP_TXP<5>") )
				( member ( signalRef "P3E_CPU0_PE3_OCP_TXP<6>") )
				( member ( signalRef "P3E_CPU0_PE3_OCP_TXP<7>") )
				( member ( signalRef "P3E_CPU0_PE3_OCP_TXP<8>") )
				( member ( signalRef "P3E_CPU0_PE3_OCP_TXP<9>") )
				( member ( signalRef "P3E_CPU0_PE3_OCP_TXP<10>") )
				( member ( signalRef "P3E_CPU0_PE3_OCP_TXP<11>") )
				( member ( signalRef "P3E_CPU0_PE3_OCP_TXP<12>") )
				( member ( signalRef "P3E_CPU0_PE3_OCP_TXP<13>") )
				( member ( signalRef "P3E_CPU0_PE3_OCP_TXP<14>") )
				( member ( signalRef "P3E_CPU0_PE3_OCP_TXP<15>") )
				( objectStatus "@baseboard_fab2_lib.baseboard_fab2(sch_1):p3e_cpu0_pe3_ocp_txp" )
			)
			( bus "UPI_CPU0_CPU1_P0P0_DN"
				( memberType ( signal ) )
				( member ( signalRef "UPI_CPU0_CPU1_P0P0_DN<0>") )
				( member ( signalRef "UPI_CPU0_CPU1_P0P0_DN<1>") )
				( member ( signalRef "UPI_CPU0_CPU1_P0P0_DN<2>") )
				( member ( signalRef "UPI_CPU0_CPU1_P0P0_DN<3>") )
				( member ( signalRef "UPI_CPU0_CPU1_P0P0_DN<4>") )
				( member ( signalRef "UPI_CPU0_CPU1_P0P0_DN<5>") )
				( member ( signalRef "UPI_CPU0_CPU1_P0P0_DN<6>") )
				( member ( signalRef "UPI_CPU0_CPU1_P0P0_DN<7>") )
				( member ( signalRef "UPI_CPU0_CPU1_P0P0_DN<8>") )
				( member ( signalRef "UPI_CPU0_CPU1_P0P0_DN<9>") )
				( member ( signalRef "UPI_CPU0_CPU1_P0P0_DN<10>") )
				( member ( signalRef "UPI_CPU0_CPU1_P0P0_DN<11>") )
				( member ( signalRef "UPI_CPU0_CPU1_P0P0_DN<12>") )
				( member ( signalRef "UPI_CPU0_CPU1_P0P0_DN<13>") )
				( member ( signalRef "UPI_CPU0_CPU1_P0P0_DN<14>") )
				( member ( signalRef "UPI_CPU0_CPU1_P0P0_DN<15>") )
				( member ( signalRef "UPI_CPU0_CPU1_P0P0_DN<16>") )
				( member ( signalRef "UPI_CPU0_CPU1_P0P0_DN<17>") )
				( member ( signalRef "UPI_CPU0_CPU1_P0P0_DN<18>") )
				( member ( signalRef "UPI_CPU0_CPU1_P0P0_DN<19>") )
				( objectStatus "@baseboard_fab2_lib.baseboard_fab2(sch_1):upi_cpu0_cpu1_p0p0_dn" )
			)
			( bus "UPI_CPU0_CPU1_P0P0_DP"
				( memberType ( signal ) )
				( member ( signalRef "UPI_CPU0_CPU1_P0P0_DP<0>") )
				( member ( signalRef "UPI_CPU0_CPU1_P0P0_DP<1>") )
				( member ( signalRef "UPI_CPU0_CPU1_P0P0_DP<2>") )
				( member ( signalRef "UPI_CPU0_CPU1_P0P0_DP<3>") )
				( member ( signalRef "UPI_CPU0_CPU1_P0P0_DP<4>") )
				( member ( signalRef "UPI_CPU0_CPU1_P0P0_DP<5>") )
				( member ( signalRef "UPI_CPU0_CPU1_P0P0_DP<6>") )
				( member ( signalRef "UPI_CPU0_CPU1_P0P0_DP<7>") )
				( member ( signalRef "UPI_CPU0_CPU1_P0P0_DP<8>") )
				( member ( signalRef "UPI_CPU0_CPU1_P0P0_DP<9>") )
				( member ( signalRef "UPI_CPU0_CPU1_P0P0_DP<10>") )
				( member ( signalRef "UPI_CPU0_CPU1_P0P0_DP<11>") )
				( member ( signalRef "UPI_CPU0_CPU1_P0P0_DP<12>") )
				( member ( signalRef "UPI_CPU0_CPU1_P0P0_DP<13>") )
				( member ( signalRef "UPI_CPU0_CPU1_P0P0_DP<14>") )
				( member ( signalRef "UPI_CPU0_CPU1_P0P0_DP<15>") )
				( member ( signalRef "UPI_CPU0_CPU1_P0P0_DP<16>") )
				( member ( signalRef "UPI_CPU0_CPU1_P0P0_DP<17>") )
				( member ( signalRef "UPI_CPU0_CPU1_P0P0_DP<18>") )
				( member ( signalRef "UPI_CPU0_CPU1_P0P0_DP<19>") )
				( objectStatus "@baseboard_fab2_lib.baseboard_fab2(sch_1):upi_cpu0_cpu1_p0p0_dp" )
			)
			( bus "UPI_CPU1_CPU0_P0P0_DN"
				( memberType ( signal ) )
				( member ( signalRef "UPI_CPU1_CPU0_P0P0_DN<0>") )
				( member ( signalRef "UPI_CPU1_CPU0_P0P0_DN<1>") )
				( member ( signalRef "UPI_CPU1_CPU0_P0P0_DN<2>") )
				( member ( signalRef "UPI_CPU1_CPU0_P0P0_DN<3>") )
				( member ( signalRef "UPI_CPU1_CPU0_P0P0_DN<4>") )
				( member ( signalRef "UPI_CPU1_CPU0_P0P0_DN<5>") )
				( member ( signalRef "UPI_CPU1_CPU0_P0P0_DN<6>") )
				( member ( signalRef "UPI_CPU1_CPU0_P0P0_DN<7>") )
				( member ( signalRef "UPI_CPU1_CPU0_P0P0_DN<8>") )
				( member ( signalRef "UPI_CPU1_CPU0_P0P0_DN<9>") )
				( member ( signalRef "UPI_CPU1_CPU0_P0P0_DN<10>") )
				( member ( signalRef "UPI_CPU1_CPU0_P0P0_DN<11>") )
				( member ( signalRef "UPI_CPU1_CPU0_P0P0_DN<12>") )
				( member ( signalRef "UPI_CPU1_CPU0_P0P0_DN<13>") )
				( member ( signalRef "UPI_CPU1_CPU0_P0P0_DN<14>") )
				( member ( signalRef "UPI_CPU1_CPU0_P0P0_DN<15>") )
				( member ( signalRef "UPI_CPU1_CPU0_P0P0_DN<16>") )
				( member ( signalRef "UPI_CPU1_CPU0_P0P0_DN<17>") )
				( member ( signalRef "UPI_CPU1_CPU0_P0P0_DN<18>") )
				( member ( signalRef "UPI_CPU1_CPU0_P0P0_DN<19>") )
				( objectStatus "@baseboard_fab2_lib.baseboard_fab2(sch_1):upi_cpu1_cpu0_p0p0_dn" )
			)
			( bus "UPI_CPU1_CPU0_P0P0_DP"
				( memberType ( signal ) )
				( member ( signalRef "UPI_CPU1_CPU0_P0P0_DP<0>") )
				( member ( signalRef "UPI_CPU1_CPU0_P0P0_DP<1>") )
				( member ( signalRef "UPI_CPU1_CPU0_P0P0_DP<2>") )
				( member ( signalRef "UPI_CPU1_CPU0_P0P0_DP<3>") )
				( member ( signalRef "UPI_CPU1_CPU0_P0P0_DP<4>") )
				( member ( signalRef "UPI_CPU1_CPU0_P0P0_DP<5>") )
				( member ( signalRef "UPI_CPU1_CPU0_P0P0_DP<6>") )
				( member ( signalRef "UPI_CPU1_CPU0_P0P0_DP<7>") )
				( member ( signalRef "UPI_CPU1_CPU0_P0P0_DP<8>") )
				( member ( signalRef "UPI_CPU1_CPU0_P0P0_DP<9>") )
				( member ( signalRef "UPI_CPU1_CPU0_P0P0_DP<10>") )
				( member ( signalRef "UPI_CPU1_CPU0_P0P0_DP<11>") )
				( member ( signalRef "UPI_CPU1_CPU0_P0P0_DP<12>") )
				( member ( signalRef "UPI_CPU1_CPU0_P0P0_DP<13>") )
				( member ( signalRef "UPI_CPU1_CPU0_P0P0_DP<14>") )
				( member ( signalRef "UPI_CPU1_CPU0_P0P0_DP<15>") )
				( member ( signalRef "UPI_CPU1_CPU0_P0P0_DP<16>") )
				( member ( signalRef "UPI_CPU1_CPU0_P0P0_DP<17>") )
				( member ( signalRef "UPI_CPU1_CPU0_P0P0_DP<18>") )
				( member ( signalRef "UPI_CPU1_CPU0_P0P0_DP<19>") )
				( objectStatus "@baseboard_fab2_lib.baseboard_fab2(sch_1):upi_cpu1_cpu0_p0p0_dp" )
			)
			( bus "UPI_CPU0_CPU1_P1P1_DN"
				( memberType ( signal ) )
				( member ( signalRef "UPI_CPU0_CPU1_P1P1_DN<0>") )
				( member ( signalRef "UPI_CPU0_CPU1_P1P1_DN<1>") )
				( member ( signalRef "UPI_CPU0_CPU1_P1P1_DN<2>") )
				( member ( signalRef "UPI_CPU0_CPU1_P1P1_DN<3>") )
				( member ( signalRef "UPI_CPU0_CPU1_P1P1_DN<4>") )
				( member ( signalRef "UPI_CPU0_CPU1_P1P1_DN<5>") )
				( member ( signalRef "UPI_CPU0_CPU1_P1P1_DN<6>") )
				( member ( signalRef "UPI_CPU0_CPU1_P1P1_DN<7>") )
				( member ( signalRef "UPI_CPU0_CPU1_P1P1_DN<8>") )
				( member ( signalRef "UPI_CPU0_CPU1_P1P1_DN<9>") )
				( member ( signalRef "UPI_CPU0_CPU1_P1P1_DN<10>") )
				( member ( signalRef "UPI_CPU0_CPU1_P1P1_DN<11>") )
				( member ( signalRef "UPI_CPU0_CPU1_P1P1_DN<12>") )
				( member ( signalRef "UPI_CPU0_CPU1_P1P1_DN<13>") )
				( member ( signalRef "UPI_CPU0_CPU1_P1P1_DN<14>") )
				( member ( signalRef "UPI_CPU0_CPU1_P1P1_DN<15>") )
				( member ( signalRef "UPI_CPU0_CPU1_P1P1_DN<16>") )
				( member ( signalRef "UPI_CPU0_CPU1_P1P1_DN<17>") )
				( member ( signalRef "UPI_CPU0_CPU1_P1P1_DN<18>") )
				( member ( signalRef "UPI_CPU0_CPU1_P1P1_DN<19>") )
				( objectStatus "@baseboard_fab2_lib.baseboard_fab2(sch_1):upi_cpu0_cpu1_p1p1_dn" )
			)
			( bus "UPI_CPU0_CPU1_P1P1_DP"
				( memberType ( signal ) )
				( member ( signalRef "UPI_CPU0_CPU1_P1P1_DP<0>") )
				( member ( signalRef "UPI_CPU0_CPU1_P1P1_DP<1>") )
				( member ( signalRef "UPI_CPU0_CPU1_P1P1_DP<2>") )
				( member ( signalRef "UPI_CPU0_CPU1_P1P1_DP<3>") )
				( member ( signalRef "UPI_CPU0_CPU1_P1P1_DP<4>") )
				( member ( signalRef "UPI_CPU0_CPU1_P1P1_DP<5>") )
				( member ( signalRef "UPI_CPU0_CPU1_P1P1_DP<6>") )
				( member ( signalRef "UPI_CPU0_CPU1_P1P1_DP<7>") )
				( member ( signalRef "UPI_CPU0_CPU1_P1P1_DP<8>") )
				( member ( signalRef "UPI_CPU0_CPU1_P1P1_DP<9>") )
				( member ( signalRef "UPI_CPU0_CPU1_P1P1_DP<10>") )
				( member ( signalRef "UPI_CPU0_CPU1_P1P1_DP<11>") )
				( member ( signalRef "UPI_CPU0_CPU1_P1P1_DP<12>") )
				( member ( signalRef "UPI_CPU0_CPU1_P1P1_DP<13>") )
				( member ( signalRef "UPI_CPU0_CPU1_P1P1_DP<14>") )
				( member ( signalRef "UPI_CPU0_CPU1_P1P1_DP<15>") )
				( member ( signalRef "UPI_CPU0_CPU1_P1P1_DP<16>") )
				( member ( signalRef "UPI_CPU0_CPU1_P1P1_DP<17>") )
				( member ( signalRef "UPI_CPU0_CPU1_P1P1_DP<18>") )
				( member ( signalRef "UPI_CPU0_CPU1_P1P1_DP<19>") )
				( objectStatus "@baseboard_fab2_lib.baseboard_fab2(sch_1):upi_cpu0_cpu1_p1p1_dp" )
			)
			( bus "UPI_CPU1_CPU0_P1P1_DN"
				( memberType ( signal ) )
				( member ( signalRef "UPI_CPU1_CPU0_P1P1_DN<0>") )
				( member ( signalRef "UPI_CPU1_CPU0_P1P1_DN<1>") )
				( member ( signalRef "UPI_CPU1_CPU0_P1P1_DN<2>") )
				( member ( signalRef "UPI_CPU1_CPU0_P1P1_DN<3>") )
				( member ( signalRef "UPI_CPU1_CPU0_P1P1_DN<4>") )
				( member ( signalRef "UPI_CPU1_CPU0_P1P1_DN<5>") )
				( member ( signalRef "UPI_CPU1_CPU0_P1P1_DN<6>") )
				( member ( signalRef "UPI_CPU1_CPU0_P1P1_DN<7>") )
				( member ( signalRef "UPI_CPU1_CPU0_P1P1_DN<8>") )
				( member ( signalRef "UPI_CPU1_CPU0_P1P1_DN<9>") )
				( member ( signalRef "UPI_CPU1_CPU0_P1P1_DN<10>") )
				( member ( signalRef "UPI_CPU1_CPU0_P1P1_DN<11>") )
				( member ( signalRef "UPI_CPU1_CPU0_P1P1_DN<12>") )
				( member ( signalRef "UPI_CPU1_CPU0_P1P1_DN<13>") )
				( member ( signalRef "UPI_CPU1_CPU0_P1P1_DN<14>") )
				( member ( signalRef "UPI_CPU1_CPU0_P1P1_DN<15>") )
				( member ( signalRef "UPI_CPU1_CPU0_P1P1_DN<16>") )
				( member ( signalRef "UPI_CPU1_CPU0_P1P1_DN<17>") )
				( member ( signalRef "UPI_CPU1_CPU0_P1P1_DN<18>") )
				( member ( signalRef "UPI_CPU1_CPU0_P1P1_DN<19>") )
				( objectStatus "@baseboard_fab2_lib.baseboard_fab2(sch_1):upi_cpu1_cpu0_p1p1_dn" )
			)
			( bus "UPI_CPU1_CPU0_P1P1_DP"
				( memberType ( signal ) )
				( member ( signalRef "UPI_CPU1_CPU0_P1P1_DP<0>") )
				( member ( signalRef "UPI_CPU1_CPU0_P1P1_DP<1>") )
				( member ( signalRef "UPI_CPU1_CPU0_P1P1_DP<2>") )
				( member ( signalRef "UPI_CPU1_CPU0_P1P1_DP<3>") )
				( member ( signalRef "UPI_CPU1_CPU0_P1P1_DP<4>") )
				( member ( signalRef "UPI_CPU1_CPU0_P1P1_DP<5>") )
				( member ( signalRef "UPI_CPU1_CPU0_P1P1_DP<6>") )
				( member ( signalRef "UPI_CPU1_CPU0_P1P1_DP<7>") )
				( member ( signalRef "UPI_CPU1_CPU0_P1P1_DP<8>") )
				( member ( signalRef "UPI_CPU1_CPU0_P1P1_DP<9>") )
				( member ( signalRef "UPI_CPU1_CPU0_P1P1_DP<10>") )
				( member ( signalRef "UPI_CPU1_CPU0_P1P1_DP<11>") )
				( member ( signalRef "UPI_CPU1_CPU0_P1P1_DP<12>") )
				( member ( signalRef "UPI_CPU1_CPU0_P1P1_DP<13>") )
				( member ( signalRef "UPI_CPU1_CPU0_P1P1_DP<14>") )
				( member ( signalRef "UPI_CPU1_CPU0_P1P1_DP<15>") )
				( member ( signalRef "UPI_CPU1_CPU0_P1P1_DP<16>") )
				( member ( signalRef "UPI_CPU1_CPU0_P1P1_DP<17>") )
				( member ( signalRef "UPI_CPU1_CPU0_P1P1_DP<18>") )
				( member ( signalRef "UPI_CPU1_CPU0_P1P1_DP<19>") )
				( objectStatus "@baseboard_fab2_lib.baseboard_fab2(sch_1):upi_cpu1_cpu0_p1p1_dp" )
			)
			( bus "M_G_BA"
				( memberType ( signal ) )
				( member ( signalRef "M_G_BA<0>") )
				( member ( signalRef "M_G_BA<1>") )
				( objectStatus "@baseboard_fab2_lib.baseboard_fab2(sch_1):m_g_ba" )
			)
			( bus "M_G_BG"
				( memberType ( signal ) )
				( member ( signalRef "M_G_BG<0>") )
				( member ( signalRef "M_G_BG<1>") )
				( objectStatus "@baseboard_fab2_lib.baseboard_fab2(sch_1):m_g_bg" )
			)
			( bus "M_G_C"
				( memberType ( signal ) )
				( member ( signalRef "M_G_C<2>") )
				( objectStatus "@baseboard_fab2_lib.baseboard_fab2(sch_1):m_g_c" )
			)
			( bus "M_G_CKE"
				( memberType ( signal ) )
				( member ( signalRef "M_G_CKE<0>") )
				( member ( signalRef "M_G_CKE<1>") )
				( member ( signalRef "M_G_CKE<2>") )
				( member ( signalRef "M_G_CKE<3>") )
				( objectStatus "@baseboard_fab2_lib.baseboard_fab2(sch_1):m_g_cke" )
			)
			( bus "M_G_CLK_DN"
				( memberType ( signal ) )
				( member ( signalRef "M_G_CLK_DN<0>") )
				( member ( signalRef "M_G_CLK_DN<1>") )
				( member ( signalRef "M_G_CLK_DN<2>") )
				( member ( signalRef "M_G_CLK_DN<3>") )
				( objectStatus "@baseboard_fab2_lib.baseboard_fab2(sch_1):m_g_clk_dn" )
			)
			( bus "M_G_CLK_DP"
				( memberType ( signal ) )
				( member ( signalRef "M_G_CLK_DP<0>") )
				( member ( signalRef "M_G_CLK_DP<1>") )
				( member ( signalRef "M_G_CLK_DP<2>") )
				( member ( signalRef "M_G_CLK_DP<3>") )
				( objectStatus "@baseboard_fab2_lib.baseboard_fab2(sch_1):m_g_clk_dp" )
			)
			( bus "M_G_CS_N"
				( memberType ( signal ) )
				( member ( signalRef "M_G_CS_N<0>") )
				( member ( signalRef "M_G_CS_N<1>") )
				( member ( signalRef "M_G_CS_N<2>") )
				( member ( signalRef "M_G_CS_N<3>") )
				( member ( signalRef "M_G_CS_N<4>") )
				( member ( signalRef "M_G_CS_N<5>") )
				( member ( signalRef "M_G_CS_N<6>") )
				( member ( signalRef "M_G_CS_N<7>") )
				( objectStatus "@baseboard_fab2_lib.baseboard_fab2(sch_1):m_g_cs_n" )
			)
			( bus "M_G_DQ"
				( memberType ( signal ) )
				( member ( signalRef "M_G_DQ<0>") )
				( member ( signalRef "M_G_DQ<1>") )
				( member ( signalRef "M_G_DQ<2>") )
				( member ( signalRef "M_G_DQ<3>") )
				( member ( signalRef "M_G_DQ<4>") )
				( member ( signalRef "M_G_DQ<5>") )
				( member ( signalRef "M_G_DQ<6>") )
				( member ( signalRef "M_G_DQ<7>") )
				( member ( signalRef "M_G_DQ<8>") )
				( member ( signalRef "M_G_DQ<9>") )
				( member ( signalRef "M_G_DQ<10>") )
				( member ( signalRef "M_G_DQ<11>") )
				( member ( signalRef "M_G_DQ<12>") )
				( member ( signalRef "M_G_DQ<13>") )
				( member ( signalRef "M_G_DQ<14>") )
				( member ( signalRef "M_G_DQ<15>") )
				( member ( signalRef "M_G_DQ<16>") )
				( member ( signalRef "M_G_DQ<17>") )
				( member ( signalRef "M_G_DQ<18>") )
				( member ( signalRef "M_G_DQ<19>") )
				( member ( signalRef "M_G_DQ<20>") )
				( member ( signalRef "M_G_DQ<21>") )
				( member ( signalRef "M_G_DQ<22>") )
				( member ( signalRef "M_G_DQ<23>") )
				( member ( signalRef "M_G_DQ<24>") )
				( member ( signalRef "M_G_DQ<25>") )
				( member ( signalRef "M_G_DQ<26>") )
				( member ( signalRef "M_G_DQ<27>") )
				( member ( signalRef "M_G_DQ<28>") )
				( member ( signalRef "M_G_DQ<29>") )
				( member ( signalRef "M_G_DQ<30>") )
				( member ( signalRef "M_G_DQ<31>") )
				( member ( signalRef "M_G_DQ<32>") )
				( member ( signalRef "M_G_DQ<33>") )
				( member ( signalRef "M_G_DQ<34>") )
				( member ( signalRef "M_G_DQ<35>") )
				( member ( signalRef "M_G_DQ<36>") )
				( member ( signalRef "M_G_DQ<37>") )
				( member ( signalRef "M_G_DQ<38>") )
				( member ( signalRef "M_G_DQ<39>") )
				( member ( signalRef "M_G_DQ<40>") )
				( member ( signalRef "M_G_DQ<41>") )
				( member ( signalRef "M_G_DQ<42>") )
				( member ( signalRef "M_G_DQ<43>") )
				( member ( signalRef "M_G_DQ<44>") )
				( member ( signalRef "M_G_DQ<45>") )
				( member ( signalRef "M_G_DQ<46>") )
				( member ( signalRef "M_G_DQ<47>") )
				( member ( signalRef "M_G_DQ<48>") )
				( member ( signalRef "M_G_DQ<49>") )
				( member ( signalRef "M_G_DQ<50>") )
				( member ( signalRef "M_G_DQ<51>") )
				( member ( signalRef "M_G_DQ<52>") )
				( member ( signalRef "M_G_DQ<53>") )
				( member ( signalRef "M_G_DQ<54>") )
				( member ( signalRef "M_G_DQ<55>") )
				( member ( signalRef "M_G_DQ<56>") )
				( member ( signalRef "M_G_DQ<57>") )
				( member ( signalRef "M_G_DQ<58>") )
				( member ( signalRef "M_G_DQ<59>") )
				( member ( signalRef "M_G_DQ<60>") )
				( member ( signalRef "M_G_DQ<61>") )
				( member ( signalRef "M_G_DQ<62>") )
				( member ( signalRef "M_G_DQ<63>") )
				( objectStatus "@baseboard_fab2_lib.baseboard_fab2(sch_1):m_g_dq" )
			)
			( bus "M_G_DQS_DN"
				( memberType ( signal ) )
				( member ( signalRef "M_G_DQS_DN<0>") )
				( member ( signalRef "M_G_DQS_DN<1>") )
				( member ( signalRef "M_G_DQS_DN<2>") )
				( member ( signalRef "M_G_DQS_DN<3>") )
				( member ( signalRef "M_G_DQS_DN<4>") )
				( member ( signalRef "M_G_DQS_DN<5>") )
				( member ( signalRef "M_G_DQS_DN<6>") )
				( member ( signalRef "M_G_DQS_DN<7>") )
				( member ( signalRef "M_G_DQS_DN<8>") )
				( member ( signalRef "M_G_DQS_DN<9>") )
				( member ( signalRef "M_G_DQS_DN<10>") )
				( member ( signalRef "M_G_DQS_DN<11>") )
				( member ( signalRef "M_G_DQS_DN<12>") )
				( member ( signalRef "M_G_DQS_DN<13>") )
				( member ( signalRef "M_G_DQS_DN<14>") )
				( member ( signalRef "M_G_DQS_DN<15>") )
				( member ( signalRef "M_G_DQS_DN<16>") )
				( member ( signalRef "M_G_DQS_DN<17>") )
				( objectStatus "@baseboard_fab2_lib.baseboard_fab2(sch_1):m_g_dqs_dn" )
			)
			( bus "M_G_DQS_DP"
				( memberType ( signal ) )
				( member ( signalRef "M_G_DQS_DP<0>") )
				( member ( signalRef "M_G_DQS_DP<1>") )
				( member ( signalRef "M_G_DQS_DP<2>") )
				( member ( signalRef "M_G_DQS_DP<3>") )
				( member ( signalRef "M_G_DQS_DP<4>") )
				( member ( signalRef "M_G_DQS_DP<5>") )
				( member ( signalRef "M_G_DQS_DP<6>") )
				( member ( signalRef "M_G_DQS_DP<7>") )
				( member ( signalRef "M_G_DQS_DP<8>") )
				( member ( signalRef "M_G_DQS_DP<9>") )
				( member ( signalRef "M_G_DQS_DP<10>") )
				( member ( signalRef "M_G_DQS_DP<11>") )
				( member ( signalRef "M_G_DQS_DP<12>") )
				( member ( signalRef "M_G_DQS_DP<13>") )
				( member ( signalRef "M_G_DQS_DP<14>") )
				( member ( signalRef "M_G_DQS_DP<15>") )
				( member ( signalRef "M_G_DQS_DP<16>") )
				( member ( signalRef "M_G_DQS_DP<17>") )
				( objectStatus "@baseboard_fab2_lib.baseboard_fab2(sch_1):m_g_dqs_dp" )
			)
			( bus "M_G_ECC"
				( memberType ( signal ) )
				( member ( signalRef "M_G_ECC<0>") )
				( member ( signalRef "M_G_ECC<1>") )
				( member ( signalRef "M_G_ECC<2>") )
				( member ( signalRef "M_G_ECC<3>") )
				( member ( signalRef "M_G_ECC<4>") )
				( member ( signalRef "M_G_ECC<5>") )
				( member ( signalRef "M_G_ECC<6>") )
				( member ( signalRef "M_G_ECC<7>") )
				( objectStatus "@baseboard_fab2_lib.baseboard_fab2(sch_1):m_g_ecc" )
			)
			( bus "M_G_MA"
				( memberType ( signal ) )
				( member ( signalRef "M_G_MA<0>") )
				( member ( signalRef "M_G_MA<1>") )
				( member ( signalRef "M_G_MA<2>") )
				( member ( signalRef "M_G_MA<3>") )
				( member ( signalRef "M_G_MA<4>") )
				( member ( signalRef "M_G_MA<5>") )
				( member ( signalRef "M_G_MA<6>") )
				( member ( signalRef "M_G_MA<7>") )
				( member ( signalRef "M_G_MA<8>") )
				( member ( signalRef "M_G_MA<9>") )
				( member ( signalRef "M_G_MA<10>") )
				( member ( signalRef "M_G_MA<11>") )
				( member ( signalRef "M_G_MA<12>") )
				( member ( signalRef "M_G_MA<13>") )
				( member ( signalRef "M_G_MA<14>") )
				( member ( signalRef "M_G_MA<15>") )
				( member ( signalRef "M_G_MA<16>") )
				( member ( signalRef "M_G_MA<17>") )
				( objectStatus "@baseboard_fab2_lib.baseboard_fab2(sch_1):m_g_ma" )
			)
			( bus "M_G_ODT"
				( memberType ( signal ) )
				( member ( signalRef "M_G_ODT<0>") )
				( member ( signalRef "M_G_ODT<1>") )
				( member ( signalRef "M_G_ODT<2>") )
				( member ( signalRef "M_G_ODT<3>") )
				( objectStatus "@baseboard_fab2_lib.baseboard_fab2(sch_1):m_g_odt" )
			)
			( bus "M_H_BA"
				( memberType ( signal ) )
				( member ( signalRef "M_H_BA<0>") )
				( member ( signalRef "M_H_BA<1>") )
				( objectStatus "@baseboard_fab2_lib.baseboard_fab2(sch_1):m_h_ba" )
			)
			( bus "M_H_BG"
				( memberType ( signal ) )
				( member ( signalRef "M_H_BG<0>") )
				( member ( signalRef "M_H_BG<1>") )
				( objectStatus "@baseboard_fab2_lib.baseboard_fab2(sch_1):m_h_bg" )
			)
			( bus "M_H_C"
				( memberType ( signal ) )
				( member ( signalRef "M_H_C<2>") )
				( objectStatus "@baseboard_fab2_lib.baseboard_fab2(sch_1):m_h_c" )
			)
			( bus "M_H_CKE"
				( memberType ( signal ) )
				( member ( signalRef "M_H_CKE<0>") )
				( member ( signalRef "M_H_CKE<1>") )
				( member ( signalRef "M_H_CKE<2>") )
				( member ( signalRef "M_H_CKE<3>") )
				( objectStatus "@baseboard_fab2_lib.baseboard_fab2(sch_1):m_h_cke" )
			)
			( bus "M_H_CLK_DN"
				( memberType ( signal ) )
				( member ( signalRef "M_H_CLK_DN<0>") )
				( member ( signalRef "M_H_CLK_DN<1>") )
				( member ( signalRef "M_H_CLK_DN<2>") )
				( member ( signalRef "M_H_CLK_DN<3>") )
				( objectStatus "@baseboard_fab2_lib.baseboard_fab2(sch_1):m_h_clk_dn" )
			)
			( bus "M_H_CLK_DP"
				( memberType ( signal ) )
				( member ( signalRef "M_H_CLK_DP<0>") )
				( member ( signalRef "M_H_CLK_DP<1>") )
				( member ( signalRef "M_H_CLK_DP<2>") )
				( member ( signalRef "M_H_CLK_DP<3>") )
				( objectStatus "@baseboard_fab2_lib.baseboard_fab2(sch_1):m_h_clk_dp" )
			)
			( bus "M_H_CS_N"
				( memberType ( signal ) )
				( member ( signalRef "M_H_CS_N<0>") )
				( member ( signalRef "M_H_CS_N<1>") )
				( member ( signalRef "M_H_CS_N<2>") )
				( member ( signalRef "M_H_CS_N<3>") )
				( member ( signalRef "M_H_CS_N<4>") )
				( member ( signalRef "M_H_CS_N<5>") )
				( member ( signalRef "M_H_CS_N<6>") )
				( member ( signalRef "M_H_CS_N<7>") )
				( objectStatus "@baseboard_fab2_lib.baseboard_fab2(sch_1):m_h_cs_n" )
			)
			( bus "M_H_DQ"
				( memberType ( signal ) )
				( member ( signalRef "M_H_DQ<0>") )
				( member ( signalRef "M_H_DQ<1>") )
				( member ( signalRef "M_H_DQ<2>") )
				( member ( signalRef "M_H_DQ<3>") )
				( member ( signalRef "M_H_DQ<4>") )
				( member ( signalRef "M_H_DQ<5>") )
				( member ( signalRef "M_H_DQ<6>") )
				( member ( signalRef "M_H_DQ<7>") )
				( member ( signalRef "M_H_DQ<8>") )
				( member ( signalRef "M_H_DQ<9>") )
				( member ( signalRef "M_H_DQ<10>") )
				( member ( signalRef "M_H_DQ<11>") )
				( member ( signalRef "M_H_DQ<12>") )
				( member ( signalRef "M_H_DQ<13>") )
				( member ( signalRef "M_H_DQ<14>") )
				( member ( signalRef "M_H_DQ<15>") )
				( member ( signalRef "M_H_DQ<16>") )
				( member ( signalRef "M_H_DQ<17>") )
				( member ( signalRef "M_H_DQ<18>") )
				( member ( signalRef "M_H_DQ<19>") )
				( member ( signalRef "M_H_DQ<20>") )
				( member ( signalRef "M_H_DQ<21>") )
				( member ( signalRef "M_H_DQ<22>") )
				( member ( signalRef "M_H_DQ<23>") )
				( member ( signalRef "M_H_DQ<24>") )
				( member ( signalRef "M_H_DQ<25>") )
				( member ( signalRef "M_H_DQ<26>") )
				( member ( signalRef "M_H_DQ<27>") )
				( member ( signalRef "M_H_DQ<28>") )
				( member ( signalRef "M_H_DQ<29>") )
				( member ( signalRef "M_H_DQ<30>") )
				( member ( signalRef "M_H_DQ<31>") )
				( member ( signalRef "M_H_DQ<32>") )
				( member ( signalRef "M_H_DQ<33>") )
				( member ( signalRef "M_H_DQ<34>") )
				( member ( signalRef "M_H_DQ<35>") )
				( member ( signalRef "M_H_DQ<36>") )
				( member ( signalRef "M_H_DQ<37>") )
				( member ( signalRef "M_H_DQ<38>") )
				( member ( signalRef "M_H_DQ<39>") )
				( member ( signalRef "M_H_DQ<40>") )
				( member ( signalRef "M_H_DQ<41>") )
				( member ( signalRef "M_H_DQ<42>") )
				( member ( signalRef "M_H_DQ<43>") )
				( member ( signalRef "M_H_DQ<44>") )
				( member ( signalRef "M_H_DQ<45>") )
				( member ( signalRef "M_H_DQ<46>") )
				( member ( signalRef "M_H_DQ<47>") )
				( member ( signalRef "M_H_DQ<48>") )
				( member ( signalRef "M_H_DQ<49>") )
				( member ( signalRef "M_H_DQ<50>") )
				( member ( signalRef "M_H_DQ<51>") )
				( member ( signalRef "M_H_DQ<52>") )
				( member ( signalRef "M_H_DQ<53>") )
				( member ( signalRef "M_H_DQ<54>") )
				( member ( signalRef "M_H_DQ<55>") )
				( member ( signalRef "M_H_DQ<56>") )
				( member ( signalRef "M_H_DQ<57>") )
				( member ( signalRef "M_H_DQ<58>") )
				( member ( signalRef "M_H_DQ<59>") )
				( member ( signalRef "M_H_DQ<60>") )
				( member ( signalRef "M_H_DQ<61>") )
				( member ( signalRef "M_H_DQ<62>") )
				( member ( signalRef "M_H_DQ<63>") )
				( objectStatus "@baseboard_fab2_lib.baseboard_fab2(sch_1):m_h_dq" )
			)
			( bus "M_H_DQS_DN"
				( memberType ( signal ) )
				( member ( signalRef "M_H_DQS_DN<0>") )
				( member ( signalRef "M_H_DQS_DN<1>") )
				( member ( signalRef "M_H_DQS_DN<2>") )
				( member ( signalRef "M_H_DQS_DN<3>") )
				( member ( signalRef "M_H_DQS_DN<4>") )
				( member ( signalRef "M_H_DQS_DN<5>") )
				( member ( signalRef "M_H_DQS_DN<6>") )
				( member ( signalRef "M_H_DQS_DN<7>") )
				( member ( signalRef "M_H_DQS_DN<8>") )
				( member ( signalRef "M_H_DQS_DN<9>") )
				( member ( signalRef "M_H_DQS_DN<10>") )
				( member ( signalRef "M_H_DQS_DN<11>") )
				( member ( signalRef "M_H_DQS_DN<12>") )
				( member ( signalRef "M_H_DQS_DN<13>") )
				( member ( signalRef "M_H_DQS_DN<14>") )
				( member ( signalRef "M_H_DQS_DN<15>") )
				( member ( signalRef "M_H_DQS_DN<16>") )
				( member ( signalRef "M_H_DQS_DN<17>") )
				( objectStatus "@baseboard_fab2_lib.baseboard_fab2(sch_1):m_h_dqs_dn" )
			)
			( bus "M_H_DQS_DP"
				( memberType ( signal ) )
				( member ( signalRef "M_H_DQS_DP<0>") )
				( member ( signalRef "M_H_DQS_DP<1>") )
				( member ( signalRef "M_H_DQS_DP<2>") )
				( member ( signalRef "M_H_DQS_DP<3>") )
				( member ( signalRef "M_H_DQS_DP<4>") )
				( member ( signalRef "M_H_DQS_DP<5>") )
				( member ( signalRef "M_H_DQS_DP<6>") )
				( member ( signalRef "M_H_DQS_DP<7>") )
				( member ( signalRef "M_H_DQS_DP<8>") )
				( member ( signalRef "M_H_DQS_DP<9>") )
				( member ( signalRef "M_H_DQS_DP<10>") )
				( member ( signalRef "M_H_DQS_DP<11>") )
				( member ( signalRef "M_H_DQS_DP<12>") )
				( member ( signalRef "M_H_DQS_DP<13>") )
				( member ( signalRef "M_H_DQS_DP<14>") )
				( member ( signalRef "M_H_DQS_DP<15>") )
				( member ( signalRef "M_H_DQS_DP<16>") )
				( member ( signalRef "M_H_DQS_DP<17>") )
				( objectStatus "@baseboard_fab2_lib.baseboard_fab2(sch_1):m_h_dqs_dp" )
			)
			( bus "M_H_ECC"
				( memberType ( signal ) )
				( member ( signalRef "M_H_ECC<0>") )
				( member ( signalRef "M_H_ECC<1>") )
				( member ( signalRef "M_H_ECC<2>") )
				( member ( signalRef "M_H_ECC<3>") )
				( member ( signalRef "M_H_ECC<4>") )
				( member ( signalRef "M_H_ECC<5>") )
				( member ( signalRef "M_H_ECC<6>") )
				( member ( signalRef "M_H_ECC<7>") )
				( objectStatus "@baseboard_fab2_lib.baseboard_fab2(sch_1):m_h_ecc" )
			)
			( bus "M_H_MA"
				( memberType ( signal ) )
				( member ( signalRef "M_H_MA<0>") )
				( member ( signalRef "M_H_MA<1>") )
				( member ( signalRef "M_H_MA<2>") )
				( member ( signalRef "M_H_MA<3>") )
				( member ( signalRef "M_H_MA<4>") )
				( member ( signalRef "M_H_MA<5>") )
				( member ( signalRef "M_H_MA<6>") )
				( member ( signalRef "M_H_MA<7>") )
				( member ( signalRef "M_H_MA<8>") )
				( member ( signalRef "M_H_MA<9>") )
				( member ( signalRef "M_H_MA<10>") )
				( member ( signalRef "M_H_MA<11>") )
				( member ( signalRef "M_H_MA<12>") )
				( member ( signalRef "M_H_MA<13>") )
				( member ( signalRef "M_H_MA<14>") )
				( member ( signalRef "M_H_MA<15>") )
				( member ( signalRef "M_H_MA<16>") )
				( member ( signalRef "M_H_MA<17>") )
				( objectStatus "@baseboard_fab2_lib.baseboard_fab2(sch_1):m_h_ma" )
			)
			( bus "M_H_ODT"
				( memberType ( signal ) )
				( member ( signalRef "M_H_ODT<0>") )
				( member ( signalRef "M_H_ODT<1>") )
				( member ( signalRef "M_H_ODT<2>") )
				( member ( signalRef "M_H_ODT<3>") )
				( objectStatus "@baseboard_fab2_lib.baseboard_fab2(sch_1):m_h_odt" )
			)
			( bus "M_J_BA"
				( memberType ( signal ) )
				( member ( signalRef "M_J_BA<0>") )
				( member ( signalRef "M_J_BA<1>") )
				( objectStatus "@baseboard_fab2_lib.baseboard_fab2(sch_1):m_j_ba" )
			)
			( bus "M_J_BG"
				( memberType ( signal ) )
				( member ( signalRef "M_J_BG<0>") )
				( member ( signalRef "M_J_BG<1>") )
				( objectStatus "@baseboard_fab2_lib.baseboard_fab2(sch_1):m_j_bg" )
			)
			( bus "M_J_C"
				( memberType ( signal ) )
				( member ( signalRef "M_J_C<2>") )
				( objectStatus "@baseboard_fab2_lib.baseboard_fab2(sch_1):m_j_c" )
			)
			( bus "M_J_CKE"
				( memberType ( signal ) )
				( member ( signalRef "M_J_CKE<0>") )
				( member ( signalRef "M_J_CKE<1>") )
				( member ( signalRef "M_J_CKE<2>") )
				( member ( signalRef "M_J_CKE<3>") )
				( objectStatus "@baseboard_fab2_lib.baseboard_fab2(sch_1):m_j_cke" )
			)
			( bus "M_J_CLK_DN"
				( memberType ( signal ) )
				( member ( signalRef "M_J_CLK_DN<0>") )
				( member ( signalRef "M_J_CLK_DN<1>") )
				( member ( signalRef "M_J_CLK_DN<2>") )
				( member ( signalRef "M_J_CLK_DN<3>") )
				( objectStatus "@baseboard_fab2_lib.baseboard_fab2(sch_1):m_j_clk_dn" )
			)
			( bus "M_J_CLK_DP"
				( memberType ( signal ) )
				( member ( signalRef "M_J_CLK_DP<0>") )
				( member ( signalRef "M_J_CLK_DP<1>") )
				( member ( signalRef "M_J_CLK_DP<2>") )
				( member ( signalRef "M_J_CLK_DP<3>") )
				( objectStatus "@baseboard_fab2_lib.baseboard_fab2(sch_1):m_j_clk_dp" )
			)
			( bus "M_J_CS_N"
				( memberType ( signal ) )
				( member ( signalRef "M_J_CS_N<0>") )
				( member ( signalRef "M_J_CS_N<1>") )
				( member ( signalRef "M_J_CS_N<2>") )
				( member ( signalRef "M_J_CS_N<3>") )
				( member ( signalRef "M_J_CS_N<4>") )
				( member ( signalRef "M_J_CS_N<5>") )
				( member ( signalRef "M_J_CS_N<6>") )
				( member ( signalRef "M_J_CS_N<7>") )
				( objectStatus "@baseboard_fab2_lib.baseboard_fab2(sch_1):m_j_cs_n" )
			)
			( bus "M_J_DQ"
				( memberType ( signal ) )
				( member ( signalRef "M_J_DQ<0>") )
				( member ( signalRef "M_J_DQ<1>") )
				( member ( signalRef "M_J_DQ<2>") )
				( member ( signalRef "M_J_DQ<3>") )
				( member ( signalRef "M_J_DQ<4>") )
				( member ( signalRef "M_J_DQ<5>") )
				( member ( signalRef "M_J_DQ<6>") )
				( member ( signalRef "M_J_DQ<7>") )
				( member ( signalRef "M_J_DQ<8>") )
				( member ( signalRef "M_J_DQ<9>") )
				( member ( signalRef "M_J_DQ<10>") )
				( member ( signalRef "M_J_DQ<11>") )
				( member ( signalRef "M_J_DQ<12>") )
				( member ( signalRef "M_J_DQ<13>") )
				( member ( signalRef "M_J_DQ<14>") )
				( member ( signalRef "M_J_DQ<15>") )
				( member ( signalRef "M_J_DQ<16>") )
				( member ( signalRef "M_J_DQ<17>") )
				( member ( signalRef "M_J_DQ<18>") )
				( member ( signalRef "M_J_DQ<19>") )
				( member ( signalRef "M_J_DQ<20>") )
				( member ( signalRef "M_J_DQ<21>") )
				( member ( signalRef "M_J_DQ<22>") )
				( member ( signalRef "M_J_DQ<23>") )
				( member ( signalRef "M_J_DQ<24>") )
				( member ( signalRef "M_J_DQ<25>") )
				( member ( signalRef "M_J_DQ<26>") )
				( member ( signalRef "M_J_DQ<27>") )
				( member ( signalRef "M_J_DQ<28>") )
				( member ( signalRef "M_J_DQ<29>") )
				( member ( signalRef "M_J_DQ<30>") )
				( member ( signalRef "M_J_DQ<31>") )
				( member ( signalRef "M_J_DQ<32>") )
				( member ( signalRef "M_J_DQ<33>") )
				( member ( signalRef "M_J_DQ<34>") )
				( member ( signalRef "M_J_DQ<35>") )
				( member ( signalRef "M_J_DQ<36>") )
				( member ( signalRef "M_J_DQ<37>") )
				( member ( signalRef "M_J_DQ<38>") )
				( member ( signalRef "M_J_DQ<39>") )
				( member ( signalRef "M_J_DQ<40>") )
				( member ( signalRef "M_J_DQ<41>") )
				( member ( signalRef "M_J_DQ<42>") )
				( member ( signalRef "M_J_DQ<43>") )
				( member ( signalRef "M_J_DQ<44>") )
				( member ( signalRef "M_J_DQ<45>") )
				( member ( signalRef "M_J_DQ<46>") )
				( member ( signalRef "M_J_DQ<47>") )
				( member ( signalRef "M_J_DQ<48>") )
				( member ( signalRef "M_J_DQ<49>") )
				( member ( signalRef "M_J_DQ<50>") )
				( member ( signalRef "M_J_DQ<51>") )
				( member ( signalRef "M_J_DQ<52>") )
				( member ( signalRef "M_J_DQ<53>") )
				( member ( signalRef "M_J_DQ<54>") )
				( member ( signalRef "M_J_DQ<55>") )
				( member ( signalRef "M_J_DQ<56>") )
				( member ( signalRef "M_J_DQ<57>") )
				( member ( signalRef "M_J_DQ<58>") )
				( member ( signalRef "M_J_DQ<59>") )
				( member ( signalRef "M_J_DQ<60>") )
				( member ( signalRef "M_J_DQ<61>") )
				( member ( signalRef "M_J_DQ<62>") )
				( member ( signalRef "M_J_DQ<63>") )
				( objectStatus "@baseboard_fab2_lib.baseboard_fab2(sch_1):m_j_dq" )
			)
			( bus "M_J_DQS_DN"
				( memberType ( signal ) )
				( member ( signalRef "M_J_DQS_DN<0>") )
				( member ( signalRef "M_J_DQS_DN<1>") )
				( member ( signalRef "M_J_DQS_DN<2>") )
				( member ( signalRef "M_J_DQS_DN<3>") )
				( member ( signalRef "M_J_DQS_DN<4>") )
				( member ( signalRef "M_J_DQS_DN<5>") )
				( member ( signalRef "M_J_DQS_DN<6>") )
				( member ( signalRef "M_J_DQS_DN<7>") )
				( member ( signalRef "M_J_DQS_DN<8>") )
				( member ( signalRef "M_J_DQS_DN<9>") )
				( member ( signalRef "M_J_DQS_DN<10>") )
				( member ( signalRef "M_J_DQS_DN<11>") )
				( member ( signalRef "M_J_DQS_DN<12>") )
				( member ( signalRef "M_J_DQS_DN<13>") )
				( member ( signalRef "M_J_DQS_DN<14>") )
				( member ( signalRef "M_J_DQS_DN<15>") )
				( member ( signalRef "M_J_DQS_DN<16>") )
				( member ( signalRef "M_J_DQS_DN<17>") )
				( objectStatus "@baseboard_fab2_lib.baseboard_fab2(sch_1):m_j_dqs_dn" )
			)
			( bus "M_J_DQS_DP"
				( memberType ( signal ) )
				( member ( signalRef "M_J_DQS_DP<0>") )
				( member ( signalRef "M_J_DQS_DP<1>") )
				( member ( signalRef "M_J_DQS_DP<2>") )
				( member ( signalRef "M_J_DQS_DP<3>") )
				( member ( signalRef "M_J_DQS_DP<4>") )
				( member ( signalRef "M_J_DQS_DP<5>") )
				( member ( signalRef "M_J_DQS_DP<6>") )
				( member ( signalRef "M_J_DQS_DP<7>") )
				( member ( signalRef "M_J_DQS_DP<8>") )
				( member ( signalRef "M_J_DQS_DP<9>") )
				( member ( signalRef "M_J_DQS_DP<10>") )
				( member ( signalRef "M_J_DQS_DP<11>") )
				( member ( signalRef "M_J_DQS_DP<12>") )
				( member ( signalRef "M_J_DQS_DP<13>") )
				( member ( signalRef "M_J_DQS_DP<14>") )
				( member ( signalRef "M_J_DQS_DP<15>") )
				( member ( signalRef "M_J_DQS_DP<16>") )
				( member ( signalRef "M_J_DQS_DP<17>") )
				( objectStatus "@baseboard_fab2_lib.baseboard_fab2(sch_1):m_j_dqs_dp" )
			)
			( bus "M_J_ECC"
				( memberType ( signal ) )
				( member ( signalRef "M_J_ECC<0>") )
				( member ( signalRef "M_J_ECC<1>") )
				( member ( signalRef "M_J_ECC<2>") )
				( member ( signalRef "M_J_ECC<3>") )
				( member ( signalRef "M_J_ECC<4>") )
				( member ( signalRef "M_J_ECC<5>") )
				( member ( signalRef "M_J_ECC<6>") )
				( member ( signalRef "M_J_ECC<7>") )
				( objectStatus "@baseboard_fab2_lib.baseboard_fab2(sch_1):m_j_ecc" )
			)
			( bus "M_J_MA"
				( memberType ( signal ) )
				( member ( signalRef "M_J_MA<0>") )
				( member ( signalRef "M_J_MA<1>") )
				( member ( signalRef "M_J_MA<2>") )
				( member ( signalRef "M_J_MA<3>") )
				( member ( signalRef "M_J_MA<4>") )
				( member ( signalRef "M_J_MA<5>") )
				( member ( signalRef "M_J_MA<6>") )
				( member ( signalRef "M_J_MA<7>") )
				( member ( signalRef "M_J_MA<8>") )
				( member ( signalRef "M_J_MA<9>") )
				( member ( signalRef "M_J_MA<10>") )
				( member ( signalRef "M_J_MA<11>") )
				( member ( signalRef "M_J_MA<12>") )
				( member ( signalRef "M_J_MA<13>") )
				( member ( signalRef "M_J_MA<14>") )
				( member ( signalRef "M_J_MA<15>") )
				( member ( signalRef "M_J_MA<16>") )
				( member ( signalRef "M_J_MA<17>") )
				( objectStatus "@baseboard_fab2_lib.baseboard_fab2(sch_1):m_j_ma" )
			)
			( bus "M_J_ODT"
				( memberType ( signal ) )
				( member ( signalRef "M_J_ODT<0>") )
				( member ( signalRef "M_J_ODT<1>") )
				( member ( signalRef "M_J_ODT<2>") )
				( member ( signalRef "M_J_ODT<3>") )
				( objectStatus "@baseboard_fab2_lib.baseboard_fab2(sch_1):m_j_odt" )
			)
			( bus "M_K_BA"
				( memberType ( signal ) )
				( member ( signalRef "M_K_BA<0>") )
				( member ( signalRef "M_K_BA<1>") )
				( objectStatus "@baseboard_fab2_lib.baseboard_fab2(sch_1):m_k_ba" )
			)
			( bus "M_K_BG"
				( memberType ( signal ) )
				( member ( signalRef "M_K_BG<0>") )
				( member ( signalRef "M_K_BG<1>") )
				( objectStatus "@baseboard_fab2_lib.baseboard_fab2(sch_1):m_k_bg" )
			)
			( bus "M_K_C"
				( memberType ( signal ) )
				( member ( signalRef "M_K_C<2>") )
				( objectStatus "@baseboard_fab2_lib.baseboard_fab2(sch_1):m_k_c" )
			)
			( bus "M_K_CKE"
				( memberType ( signal ) )
				( member ( signalRef "M_K_CKE<0>") )
				( member ( signalRef "M_K_CKE<1>") )
				( member ( signalRef "M_K_CKE<2>") )
				( member ( signalRef "M_K_CKE<3>") )
				( objectStatus "@baseboard_fab2_lib.baseboard_fab2(sch_1):m_k_cke" )
			)
			( bus "M_K_CLK_DN"
				( memberType ( signal ) )
				( member ( signalRef "M_K_CLK_DN<0>") )
				( member ( signalRef "M_K_CLK_DN<1>") )
				( member ( signalRef "M_K_CLK_DN<2>") )
				( member ( signalRef "M_K_CLK_DN<3>") )
				( objectStatus "@baseboard_fab2_lib.baseboard_fab2(sch_1):m_k_clk_dn" )
			)
			( bus "M_K_CLK_DP"
				( memberType ( signal ) )
				( member ( signalRef "M_K_CLK_DP<0>") )
				( member ( signalRef "M_K_CLK_DP<1>") )
				( member ( signalRef "M_K_CLK_DP<2>") )
				( member ( signalRef "M_K_CLK_DP<3>") )
				( objectStatus "@baseboard_fab2_lib.baseboard_fab2(sch_1):m_k_clk_dp" )
			)
			( bus "M_K_CS_N"
				( memberType ( signal ) )
				( member ( signalRef "M_K_CS_N<0>") )
				( member ( signalRef "M_K_CS_N<1>") )
				( member ( signalRef "M_K_CS_N<2>") )
				( member ( signalRef "M_K_CS_N<3>") )
				( member ( signalRef "M_K_CS_N<4>") )
				( member ( signalRef "M_K_CS_N<5>") )
				( member ( signalRef "M_K_CS_N<6>") )
				( member ( signalRef "M_K_CS_N<7>") )
				( objectStatus "@baseboard_fab2_lib.baseboard_fab2(sch_1):m_k_cs_n" )
			)
			( bus "M_K_DQ"
				( memberType ( signal ) )
				( member ( signalRef "M_K_DQ<0>") )
				( member ( signalRef "M_K_DQ<1>") )
				( member ( signalRef "M_K_DQ<2>") )
				( member ( signalRef "M_K_DQ<3>") )
				( member ( signalRef "M_K_DQ<4>") )
				( member ( signalRef "M_K_DQ<5>") )
				( member ( signalRef "M_K_DQ<6>") )
				( member ( signalRef "M_K_DQ<7>") )
				( member ( signalRef "M_K_DQ<8>") )
				( member ( signalRef "M_K_DQ<9>") )
				( member ( signalRef "M_K_DQ<10>") )
				( member ( signalRef "M_K_DQ<11>") )
				( member ( signalRef "M_K_DQ<12>") )
				( member ( signalRef "M_K_DQ<13>") )
				( member ( signalRef "M_K_DQ<14>") )
				( member ( signalRef "M_K_DQ<15>") )
				( member ( signalRef "M_K_DQ<16>") )
				( member ( signalRef "M_K_DQ<17>") )
				( member ( signalRef "M_K_DQ<18>") )
				( member ( signalRef "M_K_DQ<19>") )
				( member ( signalRef "M_K_DQ<20>") )
				( member ( signalRef "M_K_DQ<21>") )
				( member ( signalRef "M_K_DQ<22>") )
				( member ( signalRef "M_K_DQ<23>") )
				( member ( signalRef "M_K_DQ<24>") )
				( member ( signalRef "M_K_DQ<25>") )
				( member ( signalRef "M_K_DQ<26>") )
				( member ( signalRef "M_K_DQ<27>") )
				( member ( signalRef "M_K_DQ<28>") )
				( member ( signalRef "M_K_DQ<29>") )
				( member ( signalRef "M_K_DQ<30>") )
				( member ( signalRef "M_K_DQ<31>") )
				( member ( signalRef "M_K_DQ<32>") )
				( member ( signalRef "M_K_DQ<33>") )
				( member ( signalRef "M_K_DQ<34>") )
				( member ( signalRef "M_K_DQ<35>") )
				( member ( signalRef "M_K_DQ<36>") )
				( member ( signalRef "M_K_DQ<37>") )
				( member ( signalRef "M_K_DQ<38>") )
				( member ( signalRef "M_K_DQ<39>") )
				( member ( signalRef "M_K_DQ<40>") )
				( member ( signalRef "M_K_DQ<41>") )
				( member ( signalRef "M_K_DQ<42>") )
				( member ( signalRef "M_K_DQ<43>") )
				( member ( signalRef "M_K_DQ<44>") )
				( member ( signalRef "M_K_DQ<45>") )
				( member ( signalRef "M_K_DQ<46>") )
				( member ( signalRef "M_K_DQ<47>") )
				( member ( signalRef "M_K_DQ<48>") )
				( member ( signalRef "M_K_DQ<49>") )
				( member ( signalRef "M_K_DQ<50>") )
				( member ( signalRef "M_K_DQ<51>") )
				( member ( signalRef "M_K_DQ<52>") )
				( member ( signalRef "M_K_DQ<53>") )
				( member ( signalRef "M_K_DQ<54>") )
				( member ( signalRef "M_K_DQ<55>") )
				( member ( signalRef "M_K_DQ<56>") )
				( member ( signalRef "M_K_DQ<57>") )
				( member ( signalRef "M_K_DQ<58>") )
				( member ( signalRef "M_K_DQ<59>") )
				( member ( signalRef "M_K_DQ<60>") )
				( member ( signalRef "M_K_DQ<61>") )
				( member ( signalRef "M_K_DQ<62>") )
				( member ( signalRef "M_K_DQ<63>") )
				( objectStatus "@baseboard_fab2_lib.baseboard_fab2(sch_1):m_k_dq" )
			)
			( bus "M_K_DQS_DN"
				( memberType ( signal ) )
				( member ( signalRef "M_K_DQS_DN<0>") )
				( member ( signalRef "M_K_DQS_DN<1>") )
				( member ( signalRef "M_K_DQS_DN<2>") )
				( member ( signalRef "M_K_DQS_DN<3>") )
				( member ( signalRef "M_K_DQS_DN<4>") )
				( member ( signalRef "M_K_DQS_DN<5>") )
				( member ( signalRef "M_K_DQS_DN<6>") )
				( member ( signalRef "M_K_DQS_DN<7>") )
				( member ( signalRef "M_K_DQS_DN<8>") )
				( member ( signalRef "M_K_DQS_DN<9>") )
				( member ( signalRef "M_K_DQS_DN<10>") )
				( member ( signalRef "M_K_DQS_DN<11>") )
				( member ( signalRef "M_K_DQS_DN<12>") )
				( member ( signalRef "M_K_DQS_DN<13>") )
				( member ( signalRef "M_K_DQS_DN<14>") )
				( member ( signalRef "M_K_DQS_DN<15>") )
				( member ( signalRef "M_K_DQS_DN<16>") )
				( member ( signalRef "M_K_DQS_DN<17>") )
				( objectStatus "@baseboard_fab2_lib.baseboard_fab2(sch_1):m_k_dqs_dn" )
			)
			( bus "M_K_DQS_DP"
				( memberType ( signal ) )
				( member ( signalRef "M_K_DQS_DP<0>") )
				( member ( signalRef "M_K_DQS_DP<1>") )
				( member ( signalRef "M_K_DQS_DP<2>") )
				( member ( signalRef "M_K_DQS_DP<3>") )
				( member ( signalRef "M_K_DQS_DP<4>") )
				( member ( signalRef "M_K_DQS_DP<5>") )
				( member ( signalRef "M_K_DQS_DP<6>") )
				( member ( signalRef "M_K_DQS_DP<7>") )
				( member ( signalRef "M_K_DQS_DP<8>") )
				( member ( signalRef "M_K_DQS_DP<9>") )
				( member ( signalRef "M_K_DQS_DP<10>") )
				( member ( signalRef "M_K_DQS_DP<11>") )
				( member ( signalRef "M_K_DQS_DP<12>") )
				( member ( signalRef "M_K_DQS_DP<13>") )
				( member ( signalRef "M_K_DQS_DP<14>") )
				( member ( signalRef "M_K_DQS_DP<15>") )
				( member ( signalRef "M_K_DQS_DP<16>") )
				( member ( signalRef "M_K_DQS_DP<17>") )
				( objectStatus "@baseboard_fab2_lib.baseboard_fab2(sch_1):m_k_dqs_dp" )
			)
			( bus "M_K_ECC"
				( memberType ( signal ) )
				( member ( signalRef "M_K_ECC<0>") )
				( member ( signalRef "M_K_ECC<1>") )
				( member ( signalRef "M_K_ECC<2>") )
				( member ( signalRef "M_K_ECC<3>") )
				( member ( signalRef "M_K_ECC<4>") )
				( member ( signalRef "M_K_ECC<5>") )
				( member ( signalRef "M_K_ECC<6>") )
				( member ( signalRef "M_K_ECC<7>") )
				( objectStatus "@baseboard_fab2_lib.baseboard_fab2(sch_1):m_k_ecc" )
			)
			( bus "M_K_MA"
				( memberType ( signal ) )
				( member ( signalRef "M_K_MA<0>") )
				( member ( signalRef "M_K_MA<1>") )
				( member ( signalRef "M_K_MA<2>") )
				( member ( signalRef "M_K_MA<3>") )
				( member ( signalRef "M_K_MA<4>") )
				( member ( signalRef "M_K_MA<5>") )
				( member ( signalRef "M_K_MA<6>") )
				( member ( signalRef "M_K_MA<7>") )
				( member ( signalRef "M_K_MA<8>") )
				( member ( signalRef "M_K_MA<9>") )
				( member ( signalRef "M_K_MA<10>") )
				( member ( signalRef "M_K_MA<11>") )
				( member ( signalRef "M_K_MA<12>") )
				( member ( signalRef "M_K_MA<13>") )
				( member ( signalRef "M_K_MA<14>") )
				( member ( signalRef "M_K_MA<15>") )
				( member ( signalRef "M_K_MA<16>") )
				( member ( signalRef "M_K_MA<17>") )
				( objectStatus "@baseboard_fab2_lib.baseboard_fab2(sch_1):m_k_ma" )
			)
			( bus "M_K_ODT"
				( memberType ( signal ) )
				( member ( signalRef "M_K_ODT<0>") )
				( member ( signalRef "M_K_ODT<1>") )
				( member ( signalRef "M_K_ODT<2>") )
				( member ( signalRef "M_K_ODT<3>") )
				( objectStatus "@baseboard_fab2_lib.baseboard_fab2(sch_1):m_k_odt" )
			)
			( bus "M_L_BA"
				( memberType ( signal ) )
				( member ( signalRef "M_L_BA<0>") )
				( member ( signalRef "M_L_BA<1>") )
				( objectStatus "@baseboard_fab2_lib.baseboard_fab2(sch_1):m_l_ba" )
			)
			( bus "M_L_BG"
				( memberType ( signal ) )
				( member ( signalRef "M_L_BG<0>") )
				( member ( signalRef "M_L_BG<1>") )
				( objectStatus "@baseboard_fab2_lib.baseboard_fab2(sch_1):m_l_bg" )
			)
			( bus "M_L_C"
				( memberType ( signal ) )
				( member ( signalRef "M_L_C<2>") )
				( objectStatus "@baseboard_fab2_lib.baseboard_fab2(sch_1):m_l_c" )
			)
			( bus "M_L_CKE"
				( memberType ( signal ) )
				( member ( signalRef "M_L_CKE<0>") )
				( member ( signalRef "M_L_CKE<1>") )
				( member ( signalRef "M_L_CKE<2>") )
				( member ( signalRef "M_L_CKE<3>") )
				( objectStatus "@baseboard_fab2_lib.baseboard_fab2(sch_1):m_l_cke" )
			)
			( bus "M_L_CLK_DN"
				( memberType ( signal ) )
				( member ( signalRef "M_L_CLK_DN<0>") )
				( member ( signalRef "M_L_CLK_DN<1>") )
				( member ( signalRef "M_L_CLK_DN<2>") )
				( member ( signalRef "M_L_CLK_DN<3>") )
				( objectStatus "@baseboard_fab2_lib.baseboard_fab2(sch_1):m_l_clk_dn" )
			)
			( bus "M_L_CLK_DP"
				( memberType ( signal ) )
				( member ( signalRef "M_L_CLK_DP<0>") )
				( member ( signalRef "M_L_CLK_DP<1>") )
				( member ( signalRef "M_L_CLK_DP<2>") )
				( member ( signalRef "M_L_CLK_DP<3>") )
				( objectStatus "@baseboard_fab2_lib.baseboard_fab2(sch_1):m_l_clk_dp" )
			)
			( bus "M_L_CS_N"
				( memberType ( signal ) )
				( member ( signalRef "M_L_CS_N<0>") )
				( member ( signalRef "M_L_CS_N<1>") )
				( member ( signalRef "M_L_CS_N<2>") )
				( member ( signalRef "M_L_CS_N<3>") )
				( member ( signalRef "M_L_CS_N<4>") )
				( member ( signalRef "M_L_CS_N<5>") )
				( member ( signalRef "M_L_CS_N<6>") )
				( member ( signalRef "M_L_CS_N<7>") )
				( objectStatus "@baseboard_fab2_lib.baseboard_fab2(sch_1):m_l_cs_n" )
			)
			( bus "M_L_DQ"
				( memberType ( signal ) )
				( member ( signalRef "M_L_DQ<0>") )
				( member ( signalRef "M_L_DQ<1>") )
				( member ( signalRef "M_L_DQ<2>") )
				( member ( signalRef "M_L_DQ<3>") )
				( member ( signalRef "M_L_DQ<4>") )
				( member ( signalRef "M_L_DQ<5>") )
				( member ( signalRef "M_L_DQ<6>") )
				( member ( signalRef "M_L_DQ<7>") )
				( member ( signalRef "M_L_DQ<8>") )
				( member ( signalRef "M_L_DQ<9>") )
				( member ( signalRef "M_L_DQ<10>") )
				( member ( signalRef "M_L_DQ<11>") )
				( member ( signalRef "M_L_DQ<12>") )
				( member ( signalRef "M_L_DQ<13>") )
				( member ( signalRef "M_L_DQ<14>") )
				( member ( signalRef "M_L_DQ<15>") )
				( member ( signalRef "M_L_DQ<16>") )
				( member ( signalRef "M_L_DQ<17>") )
				( member ( signalRef "M_L_DQ<18>") )
				( member ( signalRef "M_L_DQ<19>") )
				( member ( signalRef "M_L_DQ<20>") )
				( member ( signalRef "M_L_DQ<21>") )
				( member ( signalRef "M_L_DQ<22>") )
				( member ( signalRef "M_L_DQ<23>") )
				( member ( signalRef "M_L_DQ<24>") )
				( member ( signalRef "M_L_DQ<25>") )
				( member ( signalRef "M_L_DQ<26>") )
				( member ( signalRef "M_L_DQ<27>") )
				( member ( signalRef "M_L_DQ<28>") )
				( member ( signalRef "M_L_DQ<29>") )
				( member ( signalRef "M_L_DQ<30>") )
				( member ( signalRef "M_L_DQ<31>") )
				( member ( signalRef "M_L_DQ<32>") )
				( member ( signalRef "M_L_DQ<33>") )
				( member ( signalRef "M_L_DQ<34>") )
				( member ( signalRef "M_L_DQ<35>") )
				( member ( signalRef "M_L_DQ<36>") )
				( member ( signalRef "M_L_DQ<37>") )
				( member ( signalRef "M_L_DQ<38>") )
				( member ( signalRef "M_L_DQ<39>") )
				( member ( signalRef "M_L_DQ<40>") )
				( member ( signalRef "M_L_DQ<41>") )
				( member ( signalRef "M_L_DQ<42>") )
				( member ( signalRef "M_L_DQ<43>") )
				( member ( signalRef "M_L_DQ<44>") )
				( member ( signalRef "M_L_DQ<45>") )
				( member ( signalRef "M_L_DQ<46>") )
				( member ( signalRef "M_L_DQ<47>") )
				( member ( signalRef "M_L_DQ<48>") )
				( member ( signalRef "M_L_DQ<49>") )
				( member ( signalRef "M_L_DQ<50>") )
				( member ( signalRef "M_L_DQ<51>") )
				( member ( signalRef "M_L_DQ<52>") )
				( member ( signalRef "M_L_DQ<53>") )
				( member ( signalRef "M_L_DQ<54>") )
				( member ( signalRef "M_L_DQ<55>") )
				( member ( signalRef "M_L_DQ<56>") )
				( member ( signalRef "M_L_DQ<57>") )
				( member ( signalRef "M_L_DQ<58>") )
				( member ( signalRef "M_L_DQ<59>") )
				( member ( signalRef "M_L_DQ<60>") )
				( member ( signalRef "M_L_DQ<61>") )
				( member ( signalRef "M_L_DQ<62>") )
				( member ( signalRef "M_L_DQ<63>") )
				( objectStatus "@baseboard_fab2_lib.baseboard_fab2(sch_1):m_l_dq" )
			)
			( bus "M_L_DQS_DN"
				( memberType ( signal ) )
				( member ( signalRef "M_L_DQS_DN<0>") )
				( member ( signalRef "M_L_DQS_DN<1>") )
				( member ( signalRef "M_L_DQS_DN<2>") )
				( member ( signalRef "M_L_DQS_DN<3>") )
				( member ( signalRef "M_L_DQS_DN<4>") )
				( member ( signalRef "M_L_DQS_DN<5>") )
				( member ( signalRef "M_L_DQS_DN<6>") )
				( member ( signalRef "M_L_DQS_DN<7>") )
				( member ( signalRef "M_L_DQS_DN<8>") )
				( member ( signalRef "M_L_DQS_DN<9>") )
				( member ( signalRef "M_L_DQS_DN<10>") )
				( member ( signalRef "M_L_DQS_DN<11>") )
				( member ( signalRef "M_L_DQS_DN<12>") )
				( member ( signalRef "M_L_DQS_DN<13>") )
				( member ( signalRef "M_L_DQS_DN<14>") )
				( member ( signalRef "M_L_DQS_DN<15>") )
				( member ( signalRef "M_L_DQS_DN<16>") )
				( member ( signalRef "M_L_DQS_DN<17>") )
				( objectStatus "@baseboard_fab2_lib.baseboard_fab2(sch_1):m_l_dqs_dn" )
			)
			( bus "M_L_DQS_DP"
				( memberType ( signal ) )
				( member ( signalRef "M_L_DQS_DP<0>") )
				( member ( signalRef "M_L_DQS_DP<1>") )
				( member ( signalRef "M_L_DQS_DP<2>") )
				( member ( signalRef "M_L_DQS_DP<3>") )
				( member ( signalRef "M_L_DQS_DP<4>") )
				( member ( signalRef "M_L_DQS_DP<5>") )
				( member ( signalRef "M_L_DQS_DP<6>") )
				( member ( signalRef "M_L_DQS_DP<7>") )
				( member ( signalRef "M_L_DQS_DP<8>") )
				( member ( signalRef "M_L_DQS_DP<9>") )
				( member ( signalRef "M_L_DQS_DP<10>") )
				( member ( signalRef "M_L_DQS_DP<11>") )
				( member ( signalRef "M_L_DQS_DP<12>") )
				( member ( signalRef "M_L_DQS_DP<13>") )
				( member ( signalRef "M_L_DQS_DP<14>") )
				( member ( signalRef "M_L_DQS_DP<15>") )
				( member ( signalRef "M_L_DQS_DP<16>") )
				( member ( signalRef "M_L_DQS_DP<17>") )
				( objectStatus "@baseboard_fab2_lib.baseboard_fab2(sch_1):m_l_dqs_dp" )
			)
			( bus "M_L_ECC"
				( memberType ( signal ) )
				( member ( signalRef "M_L_ECC<0>") )
				( member ( signalRef "M_L_ECC<1>") )
				( member ( signalRef "M_L_ECC<2>") )
				( member ( signalRef "M_L_ECC<3>") )
				( member ( signalRef "M_L_ECC<4>") )
				( member ( signalRef "M_L_ECC<5>") )
				( member ( signalRef "M_L_ECC<6>") )
				( member ( signalRef "M_L_ECC<7>") )
				( objectStatus "@baseboard_fab2_lib.baseboard_fab2(sch_1):m_l_ecc" )
			)
			( bus "M_L_MA"
				( memberType ( signal ) )
				( member ( signalRef "M_L_MA<0>") )
				( member ( signalRef "M_L_MA<1>") )
				( member ( signalRef "M_L_MA<2>") )
				( member ( signalRef "M_L_MA<3>") )
				( member ( signalRef "M_L_MA<4>") )
				( member ( signalRef "M_L_MA<5>") )
				( member ( signalRef "M_L_MA<6>") )
				( member ( signalRef "M_L_MA<7>") )
				( member ( signalRef "M_L_MA<8>") )
				( member ( signalRef "M_L_MA<9>") )
				( member ( signalRef "M_L_MA<10>") )
				( member ( signalRef "M_L_MA<11>") )
				( member ( signalRef "M_L_MA<12>") )
				( member ( signalRef "M_L_MA<13>") )
				( member ( signalRef "M_L_MA<14>") )
				( member ( signalRef "M_L_MA<15>") )
				( member ( signalRef "M_L_MA<16>") )
				( member ( signalRef "M_L_MA<17>") )
				( objectStatus "@baseboard_fab2_lib.baseboard_fab2(sch_1):m_l_ma" )
			)
			( bus "M_L_ODT"
				( memberType ( signal ) )
				( member ( signalRef "M_L_ODT<0>") )
				( member ( signalRef "M_L_ODT<1>") )
				( member ( signalRef "M_L_ODT<2>") )
				( member ( signalRef "M_L_ODT<3>") )
				( objectStatus "@baseboard_fab2_lib.baseboard_fab2(sch_1):m_l_odt" )
			)
			( bus "M_M_BA"
				( memberType ( signal ) )
				( member ( signalRef "M_M_BA<0>") )
				( member ( signalRef "M_M_BA<1>") )
				( objectStatus "@baseboard_fab2_lib.baseboard_fab2(sch_1):m_m_ba" )
			)
			( bus "M_M_BG"
				( memberType ( signal ) )
				( member ( signalRef "M_M_BG<0>") )
				( member ( signalRef "M_M_BG<1>") )
				( objectStatus "@baseboard_fab2_lib.baseboard_fab2(sch_1):m_m_bg" )
			)
			( bus "M_M_C"
				( memberType ( signal ) )
				( member ( signalRef "M_M_C<2>") )
				( objectStatus "@baseboard_fab2_lib.baseboard_fab2(sch_1):m_m_c" )
			)
			( bus "M_M_CKE"
				( memberType ( signal ) )
				( member ( signalRef "M_M_CKE<0>") )
				( member ( signalRef "M_M_CKE<1>") )
				( member ( signalRef "M_M_CKE<2>") )
				( member ( signalRef "M_M_CKE<3>") )
				( objectStatus "@baseboard_fab2_lib.baseboard_fab2(sch_1):m_m_cke" )
			)
			( bus "M_M_CLK_DN"
				( memberType ( signal ) )
				( member ( signalRef "M_M_CLK_DN<0>") )
				( member ( signalRef "M_M_CLK_DN<1>") )
				( member ( signalRef "M_M_CLK_DN<2>") )
				( member ( signalRef "M_M_CLK_DN<3>") )
				( objectStatus "@baseboard_fab2_lib.baseboard_fab2(sch_1):m_m_clk_dn" )
			)
			( bus "M_M_CLK_DP"
				( memberType ( signal ) )
				( member ( signalRef "M_M_CLK_DP<0>") )
				( member ( signalRef "M_M_CLK_DP<1>") )
				( member ( signalRef "M_M_CLK_DP<2>") )
				( member ( signalRef "M_M_CLK_DP<3>") )
				( objectStatus "@baseboard_fab2_lib.baseboard_fab2(sch_1):m_m_clk_dp" )
			)
			( bus "M_M_CS_N"
				( memberType ( signal ) )
				( member ( signalRef "M_M_CS_N<0>") )
				( member ( signalRef "M_M_CS_N<1>") )
				( member ( signalRef "M_M_CS_N<2>") )
				( member ( signalRef "M_M_CS_N<3>") )
				( member ( signalRef "M_M_CS_N<4>") )
				( member ( signalRef "M_M_CS_N<5>") )
				( member ( signalRef "M_M_CS_N<6>") )
				( member ( signalRef "M_M_CS_N<7>") )
				( objectStatus "@baseboard_fab2_lib.baseboard_fab2(sch_1):m_m_cs_n" )
			)
			( bus "M_M_DQ"
				( memberType ( signal ) )
				( member ( signalRef "M_M_DQ<0>") )
				( member ( signalRef "M_M_DQ<1>") )
				( member ( signalRef "M_M_DQ<2>") )
				( member ( signalRef "M_M_DQ<3>") )
				( member ( signalRef "M_M_DQ<4>") )
				( member ( signalRef "M_M_DQ<5>") )
				( member ( signalRef "M_M_DQ<6>") )
				( member ( signalRef "M_M_DQ<7>") )
				( member ( signalRef "M_M_DQ<8>") )
				( member ( signalRef "M_M_DQ<9>") )
				( member ( signalRef "M_M_DQ<10>") )
				( member ( signalRef "M_M_DQ<11>") )
				( member ( signalRef "M_M_DQ<12>") )
				( member ( signalRef "M_M_DQ<13>") )
				( member ( signalRef "M_M_DQ<14>") )
				( member ( signalRef "M_M_DQ<15>") )
				( member ( signalRef "M_M_DQ<16>") )
				( member ( signalRef "M_M_DQ<17>") )
				( member ( signalRef "M_M_DQ<18>") )
				( member ( signalRef "M_M_DQ<19>") )
				( member ( signalRef "M_M_DQ<20>") )
				( member ( signalRef "M_M_DQ<21>") )
				( member ( signalRef "M_M_DQ<22>") )
				( member ( signalRef "M_M_DQ<23>") )
				( member ( signalRef "M_M_DQ<24>") )
				( member ( signalRef "M_M_DQ<25>") )
				( member ( signalRef "M_M_DQ<26>") )
				( member ( signalRef "M_M_DQ<27>") )
				( member ( signalRef "M_M_DQ<28>") )
				( member ( signalRef "M_M_DQ<29>") )
				( member ( signalRef "M_M_DQ<30>") )
				( member ( signalRef "M_M_DQ<31>") )
				( member ( signalRef "M_M_DQ<32>") )
				( member ( signalRef "M_M_DQ<33>") )
				( member ( signalRef "M_M_DQ<34>") )
				( member ( signalRef "M_M_DQ<35>") )
				( member ( signalRef "M_M_DQ<36>") )
				( member ( signalRef "M_M_DQ<37>") )
				( member ( signalRef "M_M_DQ<38>") )
				( member ( signalRef "M_M_DQ<39>") )
				( member ( signalRef "M_M_DQ<40>") )
				( member ( signalRef "M_M_DQ<41>") )
				( member ( signalRef "M_M_DQ<42>") )
				( member ( signalRef "M_M_DQ<43>") )
				( member ( signalRef "M_M_DQ<44>") )
				( member ( signalRef "M_M_DQ<45>") )
				( member ( signalRef "M_M_DQ<46>") )
				( member ( signalRef "M_M_DQ<47>") )
				( member ( signalRef "M_M_DQ<48>") )
				( member ( signalRef "M_M_DQ<49>") )
				( member ( signalRef "M_M_DQ<50>") )
				( member ( signalRef "M_M_DQ<51>") )
				( member ( signalRef "M_M_DQ<52>") )
				( member ( signalRef "M_M_DQ<53>") )
				( member ( signalRef "M_M_DQ<54>") )
				( member ( signalRef "M_M_DQ<55>") )
				( member ( signalRef "M_M_DQ<56>") )
				( member ( signalRef "M_M_DQ<57>") )
				( member ( signalRef "M_M_DQ<58>") )
				( member ( signalRef "M_M_DQ<59>") )
				( member ( signalRef "M_M_DQ<60>") )
				( member ( signalRef "M_M_DQ<61>") )
				( member ( signalRef "M_M_DQ<62>") )
				( member ( signalRef "M_M_DQ<63>") )
				( objectStatus "@baseboard_fab2_lib.baseboard_fab2(sch_1):m_m_dq" )
			)
			( bus "M_M_DQS_DN"
				( memberType ( signal ) )
				( member ( signalRef "M_M_DQS_DN<0>") )
				( member ( signalRef "M_M_DQS_DN<1>") )
				( member ( signalRef "M_M_DQS_DN<2>") )
				( member ( signalRef "M_M_DQS_DN<3>") )
				( member ( signalRef "M_M_DQS_DN<4>") )
				( member ( signalRef "M_M_DQS_DN<5>") )
				( member ( signalRef "M_M_DQS_DN<6>") )
				( member ( signalRef "M_M_DQS_DN<7>") )
				( member ( signalRef "M_M_DQS_DN<8>") )
				( member ( signalRef "M_M_DQS_DN<9>") )
				( member ( signalRef "M_M_DQS_DN<10>") )
				( member ( signalRef "M_M_DQS_DN<11>") )
				( member ( signalRef "M_M_DQS_DN<12>") )
				( member ( signalRef "M_M_DQS_DN<13>") )
				( member ( signalRef "M_M_DQS_DN<14>") )
				( member ( signalRef "M_M_DQS_DN<15>") )
				( member ( signalRef "M_M_DQS_DN<16>") )
				( member ( signalRef "M_M_DQS_DN<17>") )
				( objectStatus "@baseboard_fab2_lib.baseboard_fab2(sch_1):m_m_dqs_dn" )
			)
			( bus "M_M_DQS_DP"
				( memberType ( signal ) )
				( member ( signalRef "M_M_DQS_DP<0>") )
				( member ( signalRef "M_M_DQS_DP<1>") )
				( member ( signalRef "M_M_DQS_DP<2>") )
				( member ( signalRef "M_M_DQS_DP<3>") )
				( member ( signalRef "M_M_DQS_DP<4>") )
				( member ( signalRef "M_M_DQS_DP<5>") )
				( member ( signalRef "M_M_DQS_DP<6>") )
				( member ( signalRef "M_M_DQS_DP<7>") )
				( member ( signalRef "M_M_DQS_DP<8>") )
				( member ( signalRef "M_M_DQS_DP<9>") )
				( member ( signalRef "M_M_DQS_DP<10>") )
				( member ( signalRef "M_M_DQS_DP<11>") )
				( member ( signalRef "M_M_DQS_DP<12>") )
				( member ( signalRef "M_M_DQS_DP<13>") )
				( member ( signalRef "M_M_DQS_DP<14>") )
				( member ( signalRef "M_M_DQS_DP<15>") )
				( member ( signalRef "M_M_DQS_DP<16>") )
				( member ( signalRef "M_M_DQS_DP<17>") )
				( objectStatus "@baseboard_fab2_lib.baseboard_fab2(sch_1):m_m_dqs_dp" )
			)
			( bus "M_M_ECC"
				( memberType ( signal ) )
				( member ( signalRef "M_M_ECC<0>") )
				( member ( signalRef "M_M_ECC<1>") )
				( member ( signalRef "M_M_ECC<2>") )
				( member ( signalRef "M_M_ECC<3>") )
				( member ( signalRef "M_M_ECC<4>") )
				( member ( signalRef "M_M_ECC<5>") )
				( member ( signalRef "M_M_ECC<6>") )
				( member ( signalRef "M_M_ECC<7>") )
				( objectStatus "@baseboard_fab2_lib.baseboard_fab2(sch_1):m_m_ecc" )
			)
			( bus "M_M_MA"
				( memberType ( signal ) )
				( member ( signalRef "M_M_MA<0>") )
				( member ( signalRef "M_M_MA<1>") )
				( member ( signalRef "M_M_MA<2>") )
				( member ( signalRef "M_M_MA<3>") )
				( member ( signalRef "M_M_MA<4>") )
				( member ( signalRef "M_M_MA<5>") )
				( member ( signalRef "M_M_MA<6>") )
				( member ( signalRef "M_M_MA<7>") )
				( member ( signalRef "M_M_MA<8>") )
				( member ( signalRef "M_M_MA<9>") )
				( member ( signalRef "M_M_MA<10>") )
				( member ( signalRef "M_M_MA<11>") )
				( member ( signalRef "M_M_MA<12>") )
				( member ( signalRef "M_M_MA<13>") )
				( member ( signalRef "M_M_MA<14>") )
				( member ( signalRef "M_M_MA<15>") )
				( member ( signalRef "M_M_MA<16>") )
				( member ( signalRef "M_M_MA<17>") )
				( objectStatus "@baseboard_fab2_lib.baseboard_fab2(sch_1):m_m_ma" )
			)
			( bus "M_M_ODT"
				( memberType ( signal ) )
				( member ( signalRef "M_M_ODT<0>") )
				( member ( signalRef "M_M_ODT<1>") )
				( member ( signalRef "M_M_ODT<2>") )
				( member ( signalRef "M_M_ODT<3>") )
				( objectStatus "@baseboard_fab2_lib.baseboard_fab2(sch_1):m_m_odt" )
			)
			( bus "TP_P3E_CPU1_PE1_MP_RXN"
				( memberType ( signal ) )
				( member ( signalRef "TP_P3E_CPU1_PE1_MP_RXN<0>") )
				( member ( signalRef "TP_P3E_CPU1_PE1_MP_RXN<1>") )
				( member ( signalRef "TP_P3E_CPU1_PE1_MP_RXN<2>") )
				( member ( signalRef "TP_P3E_CPU1_PE1_MP_RXN<3>") )
				( member ( signalRef "TP_P3E_CPU1_PE1_MP_RXN<4>") )
				( member ( signalRef "TP_P3E_CPU1_PE1_MP_RXN<5>") )
				( member ( signalRef "TP_P3E_CPU1_PE1_MP_RXN<6>") )
				( member ( signalRef "TP_P3E_CPU1_PE1_MP_RXN<7>") )
				( objectStatus "@baseboard_fab2_lib.baseboard_fab2(sch_1):tp_p3e_cpu1_pe1_mp_rxn" )
			)
			( bus "TP_P3E_CPU1_PE1_MP_RXP"
				( memberType ( signal ) )
				( member ( signalRef "TP_P3E_CPU1_PE1_MP_RXP<0>") )
				( member ( signalRef "TP_P3E_CPU1_PE1_MP_RXP<1>") )
				( member ( signalRef "TP_P3E_CPU1_PE1_MP_RXP<2>") )
				( member ( signalRef "TP_P3E_CPU1_PE1_MP_RXP<3>") )
				( member ( signalRef "TP_P3E_CPU1_PE1_MP_RXP<4>") )
				( member ( signalRef "TP_P3E_CPU1_PE1_MP_RXP<5>") )
				( member ( signalRef "TP_P3E_CPU1_PE1_MP_RXP<6>") )
				( member ( signalRef "TP_P3E_CPU1_PE1_MP_RXP<7>") )
				( objectStatus "@baseboard_fab2_lib.baseboard_fab2(sch_1):tp_p3e_cpu1_pe1_mp_rxp" )
			)
			( bus "TP_P3E_CPU1_PE1_MP_TXN"
				( memberType ( signal ) )
				( member ( signalRef "TP_P3E_CPU1_PE1_MP_TXN<0>") )
				( member ( signalRef "TP_P3E_CPU1_PE1_MP_TXN<1>") )
				( member ( signalRef "TP_P3E_CPU1_PE1_MP_TXN<2>") )
				( member ( signalRef "TP_P3E_CPU1_PE1_MP_TXN<3>") )
				( member ( signalRef "TP_P3E_CPU1_PE1_MP_TXN<4>") )
				( member ( signalRef "TP_P3E_CPU1_PE1_MP_TXN<5>") )
				( member ( signalRef "TP_P3E_CPU1_PE1_MP_TXN<6>") )
				( member ( signalRef "TP_P3E_CPU1_PE1_MP_TXN<7>") )
				( objectStatus "@baseboard_fab2_lib.baseboard_fab2(sch_1):tp_p3e_cpu1_pe1_mp_txn" )
			)
			( bus "TP_P3E_CPU1_PE1_MP_TXP"
				( memberType ( signal ) )
				( member ( signalRef "TP_P3E_CPU1_PE1_MP_TXP<0>") )
				( member ( signalRef "TP_P3E_CPU1_PE1_MP_TXP<1>") )
				( member ( signalRef "TP_P3E_CPU1_PE1_MP_TXP<2>") )
				( member ( signalRef "TP_P3E_CPU1_PE1_MP_TXP<3>") )
				( member ( signalRef "TP_P3E_CPU1_PE1_MP_TXP<4>") )
				( member ( signalRef "TP_P3E_CPU1_PE1_MP_TXP<5>") )
				( member ( signalRef "TP_P3E_CPU1_PE1_MP_TXP<6>") )
				( member ( signalRef "TP_P3E_CPU1_PE1_MP_TXP<7>") )
				( objectStatus "@baseboard_fab2_lib.baseboard_fab2(sch_1):tp_p3e_cpu1_pe1_mp_txp" )
			)
			( bus "TP_P3E_CPU1_PE1_RSR3_RXN"
				( memberType ( signal ) )
				( member ( signalRef "TP_P3E_CPU1_PE1_RSR3_RXN<8>") )
				( member ( signalRef "TP_P3E_CPU1_PE1_RSR3_RXN<9>") )
				( member ( signalRef "TP_P3E_CPU1_PE1_RSR3_RXN<10>") )
				( member ( signalRef "TP_P3E_CPU1_PE1_RSR3_RXN<11>") )
				( member ( signalRef "TP_P3E_CPU1_PE1_RSR3_RXN<12>") )
				( member ( signalRef "TP_P3E_CPU1_PE1_RSR3_RXN<13>") )
				( member ( signalRef "TP_P3E_CPU1_PE1_RSR3_RXN<14>") )
				( member ( signalRef "TP_P3E_CPU1_PE1_RSR3_RXN<15>") )
				( objectStatus "@baseboard_fab2_lib.baseboard_fab2(sch_1):tp_p3e_cpu1_pe1_rsr3_rxn" )
			)
			( bus "TP_P3E_CPU1_PE1_RSR3_RXP"
				( memberType ( signal ) )
				( member ( signalRef "TP_P3E_CPU1_PE1_RSR3_RXP<8>") )
				( member ( signalRef "TP_P3E_CPU1_PE1_RSR3_RXP<9>") )
				( member ( signalRef "TP_P3E_CPU1_PE1_RSR3_RXP<10>") )
				( member ( signalRef "TP_P3E_CPU1_PE1_RSR3_RXP<11>") )
				( member ( signalRef "TP_P3E_CPU1_PE1_RSR3_RXP<12>") )
				( member ( signalRef "TP_P3E_CPU1_PE1_RSR3_RXP<13>") )
				( member ( signalRef "TP_P3E_CPU1_PE1_RSR3_RXP<14>") )
				( member ( signalRef "TP_P3E_CPU1_PE1_RSR3_RXP<15>") )
				( objectStatus "@baseboard_fab2_lib.baseboard_fab2(sch_1):tp_p3e_cpu1_pe1_rsr3_rxp" )
			)
			( bus "TP_P3E_CPU1_PE1_RSR3_TXN"
				( memberType ( signal ) )
				( member ( signalRef "TP_P3E_CPU1_PE1_RSR3_TXN<8>") )
				( member ( signalRef "TP_P3E_CPU1_PE1_RSR3_TXN<9>") )
				( member ( signalRef "TP_P3E_CPU1_PE1_RSR3_TXN<10>") )
				( member ( signalRef "TP_P3E_CPU1_PE1_RSR3_TXN<11>") )
				( member ( signalRef "TP_P3E_CPU1_PE1_RSR3_TXN<12>") )
				( member ( signalRef "TP_P3E_CPU1_PE1_RSR3_TXN<13>") )
				( member ( signalRef "TP_P3E_CPU1_PE1_RSR3_TXN<14>") )
				( member ( signalRef "TP_P3E_CPU1_PE1_RSR3_TXN<15>") )
				( objectStatus "@baseboard_fab2_lib.baseboard_fab2(sch_1):tp_p3e_cpu1_pe1_rsr3_txn" )
			)
			( bus "TP_P3E_CPU1_PE1_RSR3_TXP"
				( memberType ( signal ) )
				( member ( signalRef "TP_P3E_CPU1_PE1_RSR3_TXP<8>") )
				( member ( signalRef "TP_P3E_CPU1_PE1_RSR3_TXP<9>") )
				( member ( signalRef "TP_P3E_CPU1_PE1_RSR3_TXP<10>") )
				( member ( signalRef "TP_P3E_CPU1_PE1_RSR3_TXP<11>") )
				( member ( signalRef "TP_P3E_CPU1_PE1_RSR3_TXP<12>") )
				( member ( signalRef "TP_P3E_CPU1_PE1_RSR3_TXP<13>") )
				( member ( signalRef "TP_P3E_CPU1_PE1_RSR3_TXP<14>") )
				( member ( signalRef "TP_P3E_CPU1_PE1_RSR3_TXP<15>") )
				( objectStatus "@baseboard_fab2_lib.baseboard_fab2(sch_1):tp_p3e_cpu1_pe1_rsr3_txp" )
			)
			( bus "TP_P3E_CPU1_PE2_RSR_RXN"
				( memberType ( signal ) )
				( member ( signalRef "TP_P3E_CPU1_PE2_RSR_RXN<0>") )
				( member ( signalRef "TP_P3E_CPU1_PE2_RSR_RXN<1>") )
				( member ( signalRef "TP_P3E_CPU1_PE2_RSR_RXN<2>") )
				( member ( signalRef "TP_P3E_CPU1_PE2_RSR_RXN<3>") )
				( member ( signalRef "TP_P3E_CPU1_PE2_RSR_RXN<4>") )
				( member ( signalRef "TP_P3E_CPU1_PE2_RSR_RXN<5>") )
				( member ( signalRef "TP_P3E_CPU1_PE2_RSR_RXN<6>") )
				( member ( signalRef "TP_P3E_CPU1_PE2_RSR_RXN<7>") )
				( member ( signalRef "TP_P3E_CPU1_PE2_RSR_RXN<8>") )
				( member ( signalRef "TP_P3E_CPU1_PE2_RSR_RXN<9>") )
				( member ( signalRef "TP_P3E_CPU1_PE2_RSR_RXN<10>") )
				( member ( signalRef "TP_P3E_CPU1_PE2_RSR_RXN<11>") )
				( member ( signalRef "TP_P3E_CPU1_PE2_RSR_RXN<12>") )
				( member ( signalRef "TP_P3E_CPU1_PE2_RSR_RXN<13>") )
				( member ( signalRef "TP_P3E_CPU1_PE2_RSR_RXN<14>") )
				( member ( signalRef "TP_P3E_CPU1_PE2_RSR_RXN<15>") )
				( objectStatus "@baseboard_fab2_lib.baseboard_fab2(sch_1):tp_p3e_cpu1_pe2_rsr_rxn" )
			)
			( bus "TP_P3E_CPU1_PE2_RSR_RXP"
				( memberType ( signal ) )
				( member ( signalRef "TP_P3E_CPU1_PE2_RSR_RXP<0>") )
				( member ( signalRef "TP_P3E_CPU1_PE2_RSR_RXP<1>") )
				( member ( signalRef "TP_P3E_CPU1_PE2_RSR_RXP<2>") )
				( member ( signalRef "TP_P3E_CPU1_PE2_RSR_RXP<3>") )
				( member ( signalRef "TP_P3E_CPU1_PE2_RSR_RXP<4>") )
				( member ( signalRef "TP_P3E_CPU1_PE2_RSR_RXP<5>") )
				( member ( signalRef "TP_P3E_CPU1_PE2_RSR_RXP<6>") )
				( member ( signalRef "TP_P3E_CPU1_PE2_RSR_RXP<7>") )
				( member ( signalRef "TP_P3E_CPU1_PE2_RSR_RXP<8>") )
				( member ( signalRef "TP_P3E_CPU1_PE2_RSR_RXP<9>") )
				( member ( signalRef "TP_P3E_CPU1_PE2_RSR_RXP<10>") )
				( member ( signalRef "TP_P3E_CPU1_PE2_RSR_RXP<11>") )
				( member ( signalRef "TP_P3E_CPU1_PE2_RSR_RXP<12>") )
				( member ( signalRef "TP_P3E_CPU1_PE2_RSR_RXP<13>") )
				( member ( signalRef "TP_P3E_CPU1_PE2_RSR_RXP<14>") )
				( member ( signalRef "TP_P3E_CPU1_PE2_RSR_RXP<15>") )
				( objectStatus "@baseboard_fab2_lib.baseboard_fab2(sch_1):tp_p3e_cpu1_pe2_rsr_rxp" )
			)
			( bus "TP_P3E_CPU1_PE2_RSR_TXN"
				( memberType ( signal ) )
				( member ( signalRef "TP_P3E_CPU1_PE2_RSR_TXN<0>") )
				( member ( signalRef "TP_P3E_CPU1_PE2_RSR_TXN<1>") )
				( member ( signalRef "TP_P3E_CPU1_PE2_RSR_TXN<2>") )
				( member ( signalRef "TP_P3E_CPU1_PE2_RSR_TXN<3>") )
				( member ( signalRef "TP_P3E_CPU1_PE2_RSR_TXN<4>") )
				( member ( signalRef "TP_P3E_CPU1_PE2_RSR_TXN<5>") )
				( member ( signalRef "TP_P3E_CPU1_PE2_RSR_TXN<6>") )
				( member ( signalRef "TP_P3E_CPU1_PE2_RSR_TXN<7>") )
				( member ( signalRef "TP_P3E_CPU1_PE2_RSR_TXN<8>") )
				( member ( signalRef "TP_P3E_CPU1_PE2_RSR_TXN<9>") )
				( member ( signalRef "TP_P3E_CPU1_PE2_RSR_TXN<10>") )
				( member ( signalRef "TP_P3E_CPU1_PE2_RSR_TXN<11>") )
				( member ( signalRef "TP_P3E_CPU1_PE2_RSR_TXN<12>") )
				( member ( signalRef "TP_P3E_CPU1_PE2_RSR_TXN<13>") )
				( member ( signalRef "TP_P3E_CPU1_PE2_RSR_TXN<14>") )
				( member ( signalRef "TP_P3E_CPU1_PE2_RSR_TXN<15>") )
				( objectStatus "@baseboard_fab2_lib.baseboard_fab2(sch_1):tp_p3e_cpu1_pe2_rsr_txn" )
			)
			( bus "TP_P3E_CPU1_PE2_RSR_TXP"
				( memberType ( signal ) )
				( member ( signalRef "TP_P3E_CPU1_PE2_RSR_TXP<0>") )
				( member ( signalRef "TP_P3E_CPU1_PE2_RSR_TXP<1>") )
				( member ( signalRef "TP_P3E_CPU1_PE2_RSR_TXP<2>") )
				( member ( signalRef "TP_P3E_CPU1_PE2_RSR_TXP<3>") )
				( member ( signalRef "TP_P3E_CPU1_PE2_RSR_TXP<4>") )
				( member ( signalRef "TP_P3E_CPU1_PE2_RSR_TXP<5>") )
				( member ( signalRef "TP_P3E_CPU1_PE2_RSR_TXP<6>") )
				( member ( signalRef "TP_P3E_CPU1_PE2_RSR_TXP<7>") )
				( member ( signalRef "TP_P3E_CPU1_PE2_RSR_TXP<8>") )
				( member ( signalRef "TP_P3E_CPU1_PE2_RSR_TXP<9>") )
				( member ( signalRef "TP_P3E_CPU1_PE2_RSR_TXP<10>") )
				( member ( signalRef "TP_P3E_CPU1_PE2_RSR_TXP<11>") )
				( member ( signalRef "TP_P3E_CPU1_PE2_RSR_TXP<12>") )
				( member ( signalRef "TP_P3E_CPU1_PE2_RSR_TXP<13>") )
				( member ( signalRef "TP_P3E_CPU1_PE2_RSR_TXP<14>") )
				( member ( signalRef "TP_P3E_CPU1_PE2_RSR_TXP<15>") )
				( objectStatus "@baseboard_fab2_lib.baseboard_fab2(sch_1):tp_p3e_cpu1_pe2_rsr_txp" )
			)
			( bus "P3E_CPU1_PE3_MP_RXN"
				( memberType ( signal ) )
				( member ( signalRef "P3E_CPU1_PE3_MP_RXN<0>") )
				( member ( signalRef "P3E_CPU1_PE3_MP_RXN<1>") )
				( member ( signalRef "P3E_CPU1_PE3_MP_RXN<2>") )
				( member ( signalRef "P3E_CPU1_PE3_MP_RXN<3>") )
				( member ( signalRef "P3E_CPU1_PE3_MP_RXN<4>") )
				( member ( signalRef "P3E_CPU1_PE3_MP_RXN<5>") )
				( member ( signalRef "P3E_CPU1_PE3_MP_RXN<6>") )
				( member ( signalRef "P3E_CPU1_PE3_MP_RXN<7>") )
				( member ( signalRef "P3E_CPU1_PE3_MP_RXN<8>") )
				( member ( signalRef "P3E_CPU1_PE3_MP_RXN<9>") )
				( member ( signalRef "P3E_CPU1_PE3_MP_RXN<10>") )
				( member ( signalRef "P3E_CPU1_PE3_MP_RXN<11>") )
				( member ( signalRef "P3E_CPU1_PE3_MP_RXN<12>") )
				( member ( signalRef "P3E_CPU1_PE3_MP_RXN<13>") )
				( member ( signalRef "P3E_CPU1_PE3_MP_RXN<14>") )
				( member ( signalRef "P3E_CPU1_PE3_MP_RXN<15>") )
				( objectStatus "@baseboard_fab2_lib.baseboard_fab2(sch_1):p3e_cpu1_pe3_mp_rxn" )
			)
			( bus "P3E_CPU1_PE3_MP_RXP"
				( memberType ( signal ) )
				( member ( signalRef "P3E_CPU1_PE3_MP_RXP<0>") )
				( member ( signalRef "P3E_CPU1_PE3_MP_RXP<1>") )
				( member ( signalRef "P3E_CPU1_PE3_MP_RXP<2>") )
				( member ( signalRef "P3E_CPU1_PE3_MP_RXP<3>") )
				( member ( signalRef "P3E_CPU1_PE3_MP_RXP<4>") )
				( member ( signalRef "P3E_CPU1_PE3_MP_RXP<5>") )
				( member ( signalRef "P3E_CPU1_PE3_MP_RXP<6>") )
				( member ( signalRef "P3E_CPU1_PE3_MP_RXP<7>") )
				( member ( signalRef "P3E_CPU1_PE3_MP_RXP<8>") )
				( member ( signalRef "P3E_CPU1_PE3_MP_RXP<9>") )
				( member ( signalRef "P3E_CPU1_PE3_MP_RXP<10>") )
				( member ( signalRef "P3E_CPU1_PE3_MP_RXP<11>") )
				( member ( signalRef "P3E_CPU1_PE3_MP_RXP<12>") )
				( member ( signalRef "P3E_CPU1_PE3_MP_RXP<13>") )
				( member ( signalRef "P3E_CPU1_PE3_MP_RXP<14>") )
				( member ( signalRef "P3E_CPU1_PE3_MP_RXP<15>") )
				( objectStatus "@baseboard_fab2_lib.baseboard_fab2(sch_1):p3e_cpu1_pe3_mp_rxp" )
			)
			( bus "P3E_CPU1_PE3_MP_TXN"
				( memberType ( signal ) )
				( member ( signalRef "P3E_CPU1_PE3_MP_TXN<0>") )
				( member ( signalRef "P3E_CPU1_PE3_MP_TXN<1>") )
				( member ( signalRef "P3E_CPU1_PE3_MP_TXN<2>") )
				( member ( signalRef "P3E_CPU1_PE3_MP_TXN<3>") )
				( member ( signalRef "P3E_CPU1_PE3_MP_TXN<4>") )
				( member ( signalRef "P3E_CPU1_PE3_MP_TXN<5>") )
				( member ( signalRef "P3E_CPU1_PE3_MP_TXN<6>") )
				( member ( signalRef "P3E_CPU1_PE3_MP_TXN<7>") )
				( member ( signalRef "P3E_CPU1_PE3_MP_TXN<8>") )
				( member ( signalRef "P3E_CPU1_PE3_MP_TXN<9>") )
				( member ( signalRef "P3E_CPU1_PE3_MP_TXN<10>") )
				( member ( signalRef "P3E_CPU1_PE3_MP_TXN<11>") )
				( member ( signalRef "P3E_CPU1_PE3_MP_TXN<12>") )
				( member ( signalRef "P3E_CPU1_PE3_MP_TXN<13>") )
				( member ( signalRef "P3E_CPU1_PE3_MP_TXN<14>") )
				( member ( signalRef "P3E_CPU1_PE3_MP_TXN<15>") )
				( objectStatus "@baseboard_fab2_lib.baseboard_fab2(sch_1):p3e_cpu1_pe3_mp_txn" )
			)
			( bus "P3E_CPU1_PE3_MP_TXP"
				( memberType ( signal ) )
				( member ( signalRef "P3E_CPU1_PE3_MP_TXP<0>") )
				( member ( signalRef "P3E_CPU1_PE3_MP_TXP<1>") )
				( member ( signalRef "P3E_CPU1_PE3_MP_TXP<2>") )
				( member ( signalRef "P3E_CPU1_PE3_MP_TXP<3>") )
				( member ( signalRef "P3E_CPU1_PE3_MP_TXP<4>") )
				( member ( signalRef "P3E_CPU1_PE3_MP_TXP<5>") )
				( member ( signalRef "P3E_CPU1_PE3_MP_TXP<6>") )
				( member ( signalRef "P3E_CPU1_PE3_MP_TXP<7>") )
				( member ( signalRef "P3E_CPU1_PE3_MP_TXP<8>") )
				( member ( signalRef "P3E_CPU1_PE3_MP_TXP<9>") )
				( member ( signalRef "P3E_CPU1_PE3_MP_TXP<10>") )
				( member ( signalRef "P3E_CPU1_PE3_MP_TXP<11>") )
				( member ( signalRef "P3E_CPU1_PE3_MP_TXP<12>") )
				( member ( signalRef "P3E_CPU1_PE3_MP_TXP<13>") )
				( member ( signalRef "P3E_CPU1_PE3_MP_TXP<14>") )
				( member ( signalRef "P3E_CPU1_PE3_MP_TXP<15>") )
				( objectStatus "@baseboard_fab2_lib.baseboard_fab2(sch_1):p3e_cpu1_pe3_mp_txp" )
			)
			( bus "NC_DB1200ZL"
				( memberType ( signal ) )
				( member ( signalRef "NC_DB1200ZL<0>") )
				( member ( signalRef "NC_DB1200ZL<1>") )
				( member ( signalRef "NC_DB1200ZL<2>") )
				( objectStatus "@baseboard_fab2_lib.baseboard_fab2(sch_1):nc_db1200zl" )
			)
			( bus "P3E_CPU0_PE1_PCH_C_TXN"
				( memberType ( signal ) )
				( member ( signalRef "P3E_CPU0_PE1_PCH_C_TXN<8>") )
				( member ( signalRef "P3E_CPU0_PE1_PCH_C_TXN<9>") )
				( member ( signalRef "P3E_CPU0_PE1_PCH_C_TXN<10>") )
				( member ( signalRef "P3E_CPU0_PE1_PCH_C_TXN<11>") )
				( member ( signalRef "P3E_CPU0_PE1_PCH_C_TXN<12>") )
				( member ( signalRef "P3E_CPU0_PE1_PCH_C_TXN<13>") )
				( member ( signalRef "P3E_CPU0_PE1_PCH_C_TXN<14>") )
				( member ( signalRef "P3E_CPU0_PE1_PCH_C_TXN<15>") )
				( objectStatus "@baseboard_fab2_lib.baseboard_fab2(sch_1):p3e_cpu0_pe1_pch_c_txn" )
			)
			( bus "P3E_CPU0_PE1_PCH_C_TXP"
				( memberType ( signal ) )
				( member ( signalRef "P3E_CPU0_PE1_PCH_C_TXP<8>") )
				( member ( signalRef "P3E_CPU0_PE1_PCH_C_TXP<9>") )
				( member ( signalRef "P3E_CPU0_PE1_PCH_C_TXP<10>") )
				( member ( signalRef "P3E_CPU0_PE1_PCH_C_TXP<11>") )
				( member ( signalRef "P3E_CPU0_PE1_PCH_C_TXP<12>") )
				( member ( signalRef "P3E_CPU0_PE1_PCH_C_TXP<13>") )
				( member ( signalRef "P3E_CPU0_PE1_PCH_C_TXP<14>") )
				( member ( signalRef "P3E_CPU0_PE1_PCH_C_TXP<15>") )
				( objectStatus "@baseboard_fab2_lib.baseboard_fab2(sch_1):p3e_cpu0_pe1_pch_c_txp" )
			)
			( bus "P3E_CPU0_PE1_PCH_R_RXN"
				( memberType ( signal ) )
				( member ( signalRef "P3E_CPU0_PE1_PCH_R_RXN<8>") )
				( member ( signalRef "P3E_CPU0_PE1_PCH_R_RXN<9>") )
				( member ( signalRef "P3E_CPU0_PE1_PCH_R_RXN<10>") )
				( member ( signalRef "P3E_CPU0_PE1_PCH_R_RXN<11>") )
				( member ( signalRef "P3E_CPU0_PE1_PCH_R_RXN<12>") )
				( member ( signalRef "P3E_CPU0_PE1_PCH_R_RXN<13>") )
				( member ( signalRef "P3E_CPU0_PE1_PCH_R_RXN<14>") )
				( member ( signalRef "P3E_CPU0_PE1_PCH_R_RXN<15>") )
				( objectStatus "@baseboard_fab2_lib.baseboard_fab2(sch_1):p3e_cpu0_pe1_pch_r_rxn" )
			)
			( bus "P3E_CPU0_PE1_PCH_R_RXP"
				( memberType ( signal ) )
				( member ( signalRef "P3E_CPU0_PE1_PCH_R_RXP<8>") )
				( member ( signalRef "P3E_CPU0_PE1_PCH_R_RXP<9>") )
				( member ( signalRef "P3E_CPU0_PE1_PCH_R_RXP<10>") )
				( member ( signalRef "P3E_CPU0_PE1_PCH_R_RXP<11>") )
				( member ( signalRef "P3E_CPU0_PE1_PCH_R_RXP<12>") )
				( member ( signalRef "P3E_CPU0_PE1_PCH_R_RXP<13>") )
				( member ( signalRef "P3E_CPU0_PE1_PCH_R_RXP<14>") )
				( member ( signalRef "P3E_CPU0_PE1_PCH_R_RXP<15>") )
				( objectStatus "@baseboard_fab2_lib.baseboard_fab2(sch_1):p3e_cpu0_pe1_pch_r_rxp" )
			)
			( bus "P3E_CPU0_PE2_SS_C_TXN"
				( memberType ( signal ) )
				( member ( signalRef "P3E_CPU0_PE2_SS_C_TXN<0>") )
				( member ( signalRef "P3E_CPU0_PE2_SS_C_TXN<1>") )
				( member ( signalRef "P3E_CPU0_PE2_SS_C_TXN<2>") )
				( member ( signalRef "P3E_CPU0_PE2_SS_C_TXN<3>") )
				( member ( signalRef "P3E_CPU0_PE2_SS_C_TXN<4>") )
				( member ( signalRef "P3E_CPU0_PE2_SS_C_TXN<5>") )
				( member ( signalRef "P3E_CPU0_PE2_SS_C_TXN<6>") )
				( member ( signalRef "P3E_CPU0_PE2_SS_C_TXN<7>") )
				( member ( signalRef "P3E_CPU0_PE2_SS_C_TXN<8>") )
				( member ( signalRef "P3E_CPU0_PE2_SS_C_TXN<9>") )
				( member ( signalRef "P3E_CPU0_PE2_SS_C_TXN<10>") )
				( member ( signalRef "P3E_CPU0_PE2_SS_C_TXN<11>") )
				( member ( signalRef "P3E_CPU0_PE2_SS_C_TXN<12>") )
				( member ( signalRef "P3E_CPU0_PE2_SS_C_TXN<13>") )
				( member ( signalRef "P3E_CPU0_PE2_SS_C_TXN<14>") )
				( member ( signalRef "P3E_CPU0_PE2_SS_C_TXN<15>") )
				( objectStatus "@baseboard_fab2_lib.baseboard_fab2(sch_1):p3e_cpu0_pe2_ss_c_txn" )
			)
			( bus "P3E_CPU0_PE2_SS_C_TXP"
				( memberType ( signal ) )
				( member ( signalRef "P3E_CPU0_PE2_SS_C_TXP<0>") )
				( member ( signalRef "P3E_CPU0_PE2_SS_C_TXP<1>") )
				( member ( signalRef "P3E_CPU0_PE2_SS_C_TXP<2>") )
				( member ( signalRef "P3E_CPU0_PE2_SS_C_TXP<3>") )
				( member ( signalRef "P3E_CPU0_PE2_SS_C_TXP<4>") )
				( member ( signalRef "P3E_CPU0_PE2_SS_C_TXP<5>") )
				( member ( signalRef "P3E_CPU0_PE2_SS_C_TXP<6>") )
				( member ( signalRef "P3E_CPU0_PE2_SS_C_TXP<7>") )
				( member ( signalRef "P3E_CPU0_PE2_SS_C_TXP<8>") )
				( member ( signalRef "P3E_CPU0_PE2_SS_C_TXP<9>") )
				( member ( signalRef "P3E_CPU0_PE2_SS_C_TXP<10>") )
				( member ( signalRef "P3E_CPU0_PE2_SS_C_TXP<11>") )
				( member ( signalRef "P3E_CPU0_PE2_SS_C_TXP<12>") )
				( member ( signalRef "P3E_CPU0_PE2_SS_C_TXP<13>") )
				( member ( signalRef "P3E_CPU0_PE2_SS_C_TXP<14>") )
				( member ( signalRef "P3E_CPU0_PE2_SS_C_TXP<15>") )
				( objectStatus "@baseboard_fab2_lib.baseboard_fab2(sch_1):p3e_cpu0_pe2_ss_c_txp" )
			)
			( bus "P3E_OCP_CPU0_PE3_C_TXN"
				( memberType ( signal ) )
				( member ( signalRef "P3E_OCP_CPU0_PE3_C_TXN<0>") )
				( member ( signalRef "P3E_OCP_CPU0_PE3_C_TXN<1>") )
				( member ( signalRef "P3E_OCP_CPU0_PE3_C_TXN<2>") )
				( member ( signalRef "P3E_OCP_CPU0_PE3_C_TXN<3>") )
				( member ( signalRef "P3E_OCP_CPU0_PE3_C_TXN<4>") )
				( member ( signalRef "P3E_OCP_CPU0_PE3_C_TXN<5>") )
				( member ( signalRef "P3E_OCP_CPU0_PE3_C_TXN<6>") )
				( member ( signalRef "P3E_OCP_CPU0_PE3_C_TXN<7>") )
				( member ( signalRef "P3E_OCP_CPU0_PE3_C_TXN<8>") )
				( member ( signalRef "P3E_OCP_CPU0_PE3_C_TXN<9>") )
				( member ( signalRef "P3E_OCP_CPU0_PE3_C_TXN<10>") )
				( member ( signalRef "P3E_OCP_CPU0_PE3_C_TXN<11>") )
				( member ( signalRef "P3E_OCP_CPU0_PE3_C_TXN<12>") )
				( member ( signalRef "P3E_OCP_CPU0_PE3_C_TXN<13>") )
				( member ( signalRef "P3E_OCP_CPU0_PE3_C_TXN<14>") )
				( member ( signalRef "P3E_OCP_CPU0_PE3_C_TXN<15>") )
				( objectStatus "@baseboard_fab2_lib.baseboard_fab2(sch_1):p3e_ocp_cpu0_pe3_c_txn" )
			)
			( bus "P3E_OCP_CPU0_PE3_C_TXP"
				( memberType ( signal ) )
				( member ( signalRef "P3E_OCP_CPU0_PE3_C_TXP<0>") )
				( member ( signalRef "P3E_OCP_CPU0_PE3_C_TXP<1>") )
				( member ( signalRef "P3E_OCP_CPU0_PE3_C_TXP<2>") )
				( member ( signalRef "P3E_OCP_CPU0_PE3_C_TXP<3>") )
				( member ( signalRef "P3E_OCP_CPU0_PE3_C_TXP<4>") )
				( member ( signalRef "P3E_OCP_CPU0_PE3_C_TXP<5>") )
				( member ( signalRef "P3E_OCP_CPU0_PE3_C_TXP<6>") )
				( member ( signalRef "P3E_OCP_CPU0_PE3_C_TXP<7>") )
				( member ( signalRef "P3E_OCP_CPU0_PE3_C_TXP<8>") )
				( member ( signalRef "P3E_OCP_CPU0_PE3_C_TXP<9>") )
				( member ( signalRef "P3E_OCP_CPU0_PE3_C_TXP<10>") )
				( member ( signalRef "P3E_OCP_CPU0_PE3_C_TXP<11>") )
				( member ( signalRef "P3E_OCP_CPU0_PE3_C_TXP<12>") )
				( member ( signalRef "P3E_OCP_CPU0_PE3_C_TXP<13>") )
				( member ( signalRef "P3E_OCP_CPU0_PE3_C_TXP<14>") )
				( member ( signalRef "P3E_OCP_CPU0_PE3_C_TXP<15>") )
				( objectStatus "@baseboard_fab2_lib.baseboard_fab2(sch_1):p3e_ocp_cpu0_pe3_c_txp" )
			)
			( bus "P3E_CPU0_PE1_SS_C_TXN"
				( memberType ( signal ) )
				( member ( signalRef "P3E_CPU0_PE1_SS_C_TXN<0>") )
				( member ( signalRef "P3E_CPU0_PE1_SS_C_TXN<1>") )
				( member ( signalRef "P3E_CPU0_PE1_SS_C_TXN<2>") )
				( member ( signalRef "P3E_CPU0_PE1_SS_C_TXN<3>") )
				( member ( signalRef "P3E_CPU0_PE1_SS_C_TXN<4>") )
				( member ( signalRef "P3E_CPU0_PE1_SS_C_TXN<5>") )
				( member ( signalRef "P3E_CPU0_PE1_SS_C_TXN<6>") )
				( member ( signalRef "P3E_CPU0_PE1_SS_C_TXN<7>") )
				( objectStatus "@baseboard_fab2_lib.baseboard_fab2(sch_1):p3e_cpu0_pe1_ss_c_txn" )
			)
			( bus "P3E_CPU0_PE1_SS_C_TXP"
				( memberType ( signal ) )
				( member ( signalRef "P3E_CPU0_PE1_SS_C_TXP<0>") )
				( member ( signalRef "P3E_CPU0_PE1_SS_C_TXP<1>") )
				( member ( signalRef "P3E_CPU0_PE1_SS_C_TXP<2>") )
				( member ( signalRef "P3E_CPU0_PE1_SS_C_TXP<3>") )
				( member ( signalRef "P3E_CPU0_PE1_SS_C_TXP<4>") )
				( member ( signalRef "P3E_CPU0_PE1_SS_C_TXP<5>") )
				( member ( signalRef "P3E_CPU0_PE1_SS_C_TXP<6>") )
				( member ( signalRef "P3E_CPU0_PE1_SS_C_TXP<7>") )
				( objectStatus "@baseboard_fab2_lib.baseboard_fab2(sch_1):p3e_cpu0_pe1_ss_c_txp" )
			)
			( bus "P3E_CPU0_PE1_SS_R_RXN"
				( memberType ( signal ) )
				( member ( signalRef "P3E_CPU0_PE1_SS_R_RXN<0>") )
				( member ( signalRef "P3E_CPU0_PE1_SS_R_RXN<1>") )
				( member ( signalRef "P3E_CPU0_PE1_SS_R_RXN<2>") )
				( member ( signalRef "P3E_CPU0_PE1_SS_R_RXN<3>") )
				( member ( signalRef "P3E_CPU0_PE1_SS_R_RXN<4>") )
				( member ( signalRef "P3E_CPU0_PE1_SS_R_RXN<5>") )
				( member ( signalRef "P3E_CPU0_PE1_SS_R_RXN<6>") )
				( member ( signalRef "P3E_CPU0_PE1_SS_R_RXN<7>") )
				( objectStatus "@baseboard_fab2_lib.baseboard_fab2(sch_1):p3e_cpu0_pe1_ss_r_rxn" )
			)
			( bus "P3E_CPU0_PE1_SS_R_RXP"
				( memberType ( signal ) )
				( member ( signalRef "P3E_CPU0_PE1_SS_R_RXP<0>") )
				( member ( signalRef "P3E_CPU0_PE1_SS_R_RXP<1>") )
				( member ( signalRef "P3E_CPU0_PE1_SS_R_RXP<2>") )
				( member ( signalRef "P3E_CPU0_PE1_SS_R_RXP<3>") )
				( member ( signalRef "P3E_CPU0_PE1_SS_R_RXP<4>") )
				( member ( signalRef "P3E_CPU0_PE1_SS_R_RXP<5>") )
				( member ( signalRef "P3E_CPU0_PE1_SS_R_RXP<6>") )
				( member ( signalRef "P3E_CPU0_PE1_SS_R_RXP<7>") )
				( objectStatus "@baseboard_fab2_lib.baseboard_fab2(sch_1):p3e_cpu0_pe1_ss_r_rxp" )
			)
			( bus "P3E_PCH_M2_RX_DN"
				( memberType ( signal ) )
				( member ( signalRef "P3E_PCH_M2_RX_DN<1>") )
				( member ( signalRef "P3E_PCH_M2_RX_DN<2>") )
				( member ( signalRef "P3E_PCH_M2_RX_DN<3>") )
				( objectStatus "@baseboard_fab2_lib.baseboard_fab2(sch_1):p3e_pch_m2_rx_dn" )
			)
			( bus "P3E_PCH_M2_RX_DP"
				( memberType ( signal ) )
				( member ( signalRef "P3E_PCH_M2_RX_DP<1>") )
				( member ( signalRef "P3E_PCH_M2_RX_DP<2>") )
				( member ( signalRef "P3E_PCH_M2_RX_DP<3>") )
				( objectStatus "@baseboard_fab2_lib.baseboard_fab2(sch_1):p3e_pch_m2_rx_dp" )
			)
			( bus "P3E_PCH_M2_TX_DN"
				( memberType ( signal ) )
				( member ( signalRef "P3E_PCH_M2_TX_DN<1>") )
				( member ( signalRef "P3E_PCH_M2_TX_DN<2>") )
				( member ( signalRef "P3E_PCH_M2_TX_DN<3>") )
				( objectStatus "@baseboard_fab2_lib.baseboard_fab2(sch_1):p3e_pch_m2_tx_dn" )
			)
			( bus "P3E_PCH_M2_TX_DP"
				( memberType ( signal ) )
				( member ( signalRef "P3E_PCH_M2_TX_DP<1>") )
				( member ( signalRef "P3E_PCH_M2_TX_DP<2>") )
				( member ( signalRef "P3E_PCH_M2_TX_DP<3>") )
				( objectStatus "@baseboard_fab2_lib.baseboard_fab2(sch_1):p3e_pch_m2_tx_dp" )
			)
			( bus "SATA6G_PCH_PCIE_UP_SATA_RXN"
				( memberType ( signal ) )
				( member ( signalRef "SATA6G_PCH_PCIE_UP_SATA_RXN<0>") )
				( member ( signalRef "SATA6G_PCH_PCIE_UP_SATA_RXN<1>") )
				( member ( signalRef "SATA6G_PCH_PCIE_UP_SATA_RXN<2>") )
				( member ( signalRef "SATA6G_PCH_PCIE_UP_SATA_RXN<3>") )
				( member ( signalRef "SATA6G_PCH_PCIE_UP_SATA_RXN<4>") )
				( member ( signalRef "SATA6G_PCH_PCIE_UP_SATA_RXN<5>") )
				( member ( signalRef "SATA6G_PCH_PCIE_UP_SATA_RXN<6>") )
				( member ( signalRef "SATA6G_PCH_PCIE_UP_SATA_RXN<7>") )
				( objectStatus "@baseboard_fab2_lib.baseboard_fab2(sch_1):sata6g_pch_pcie_up_sata_rxn" )
			)
			( bus "SATA6G_PCH_PCIE_UP_SATA_RXP"
				( memberType ( signal ) )
				( member ( signalRef "SATA6G_PCH_PCIE_UP_SATA_RXP<0>") )
				( member ( signalRef "SATA6G_PCH_PCIE_UP_SATA_RXP<1>") )
				( member ( signalRef "SATA6G_PCH_PCIE_UP_SATA_RXP<2>") )
				( member ( signalRef "SATA6G_PCH_PCIE_UP_SATA_RXP<3>") )
				( member ( signalRef "SATA6G_PCH_PCIE_UP_SATA_RXP<4>") )
				( member ( signalRef "SATA6G_PCH_PCIE_UP_SATA_RXP<5>") )
				( member ( signalRef "SATA6G_PCH_PCIE_UP_SATA_RXP<6>") )
				( member ( signalRef "SATA6G_PCH_PCIE_UP_SATA_RXP<7>") )
				( objectStatus "@baseboard_fab2_lib.baseboard_fab2(sch_1):sata6g_pch_pcie_up_sata_rxp" )
			)
			( bus "SATA6G_PCH_PCIE_UP_SATA_TXN"
				( memberType ( signal ) )
				( member ( signalRef "SATA6G_PCH_PCIE_UP_SATA_TXN<0>") )
				( member ( signalRef "SATA6G_PCH_PCIE_UP_SATA_TXN<1>") )
				( member ( signalRef "SATA6G_PCH_PCIE_UP_SATA_TXN<2>") )
				( member ( signalRef "SATA6G_PCH_PCIE_UP_SATA_TXN<3>") )
				( member ( signalRef "SATA6G_PCH_PCIE_UP_SATA_TXN<4>") )
				( member ( signalRef "SATA6G_PCH_PCIE_UP_SATA_TXN<5>") )
				( member ( signalRef "SATA6G_PCH_PCIE_UP_SATA_TXN<6>") )
				( member ( signalRef "SATA6G_PCH_PCIE_UP_SATA_TXN<7>") )
				( objectStatus "@baseboard_fab2_lib.baseboard_fab2(sch_1):sata6g_pch_pcie_up_sata_txn" )
			)
			( bus "SATA6G_PCH_PCIE_UP_SATA_TXP"
				( memberType ( signal ) )
				( member ( signalRef "SATA6G_PCH_PCIE_UP_SATA_TXP<0>") )
				( member ( signalRef "SATA6G_PCH_PCIE_UP_SATA_TXP<1>") )
				( member ( signalRef "SATA6G_PCH_PCIE_UP_SATA_TXP<2>") )
				( member ( signalRef "SATA6G_PCH_PCIE_UP_SATA_TXP<3>") )
				( member ( signalRef "SATA6G_PCH_PCIE_UP_SATA_TXP<4>") )
				( member ( signalRef "SATA6G_PCH_PCIE_UP_SATA_TXP<5>") )
				( member ( signalRef "SATA6G_PCH_PCIE_UP_SATA_TXP<6>") )
				( member ( signalRef "SATA6G_PCH_PCIE_UP_SATA_TXP<7>") )
				( objectStatus "@baseboard_fab2_lib.baseboard_fab2(sch_1):sata6g_pch_pcie_up_sata_txp" )
			)
			( bus "SATA6G_RX_DN"
				( memberType ( signal ) )
				( member ( signalRef "SATA6G_RX_DN<0>") )
				( member ( signalRef "SATA6G_RX_DN<1>") )
				( member ( signalRef "SATA6G_RX_DN<2>") )
				( member ( signalRef "SATA6G_RX_DN<3>") )
				( objectStatus "@baseboard_fab2_lib.baseboard_fab2(sch_1):sata6g_rx_dn" )
			)
			( bus "SATA6G_RX_DP"
				( memberType ( signal ) )
				( member ( signalRef "SATA6G_RX_DP<0>") )
				( member ( signalRef "SATA6G_RX_DP<1>") )
				( member ( signalRef "SATA6G_RX_DP<2>") )
				( member ( signalRef "SATA6G_RX_DP<3>") )
				( objectStatus "@baseboard_fab2_lib.baseboard_fab2(sch_1):sata6g_rx_dp" )
			)
			( bus "SATA6G_TX_DN"
				( memberType ( signal ) )
				( member ( signalRef "SATA6G_TX_DN<0>") )
				( member ( signalRef "SATA6G_TX_DN<1>") )
				( member ( signalRef "SATA6G_TX_DN<2>") )
				( member ( signalRef "SATA6G_TX_DN<3>") )
				( objectStatus "@baseboard_fab2_lib.baseboard_fab2(sch_1):sata6g_tx_dn" )
			)
			( bus "SATA6G_TX_DP"
				( memberType ( signal ) )
				( member ( signalRef "SATA6G_TX_DP<0>") )
				( member ( signalRef "SATA6G_TX_DP<1>") )
				( member ( signalRef "SATA6G_TX_DP<2>") )
				( member ( signalRef "SATA6G_TX_DP<3>") )
				( objectStatus "@baseboard_fab2_lib.baseboard_fab2(sch_1):sata6g_tx_dp" )
			)
			( bus "DMI_CPU0_PCH_RX_DN"
				( memberType ( signal ) )
				( member ( signalRef "DMI_CPU0_PCH_RX_DN<0>") )
				( member ( signalRef "DMI_CPU0_PCH_RX_DN<1>") )
				( member ( signalRef "DMI_CPU0_PCH_RX_DN<2>") )
				( member ( signalRef "DMI_CPU0_PCH_RX_DN<3>") )
				( objectStatus "@baseboard_fab2_lib.baseboard_fab2(sch_1):dmi_cpu0_pch_rx_dn" )
			)
			( bus "DMI_CPU0_PCH_RX_DP"
				( memberType ( signal ) )
				( member ( signalRef "DMI_CPU0_PCH_RX_DP<0>") )
				( member ( signalRef "DMI_CPU0_PCH_RX_DP<1>") )
				( member ( signalRef "DMI_CPU0_PCH_RX_DP<2>") )
				( member ( signalRef "DMI_CPU0_PCH_RX_DP<3>") )
				( objectStatus "@baseboard_fab2_lib.baseboard_fab2(sch_1):dmi_cpu0_pch_rx_dp" )
			)
			( bus "DMI_CPU0_PCH_TX_C_DN"
				( memberType ( signal ) )
				( member ( signalRef "DMI_CPU0_PCH_TX_C_DN<0>") )
				( member ( signalRef "DMI_CPU0_PCH_TX_C_DN<1>") )
				( member ( signalRef "DMI_CPU0_PCH_TX_C_DN<2>") )
				( member ( signalRef "DMI_CPU0_PCH_TX_C_DN<3>") )
				( objectStatus "@baseboard_fab2_lib.baseboard_fab2(sch_1):dmi_cpu0_pch_tx_c_dn" )
			)
			( bus "DMI_CPU0_PCH_TX_C_DP"
				( memberType ( signal ) )
				( member ( signalRef "DMI_CPU0_PCH_TX_C_DP<0>") )
				( member ( signalRef "DMI_CPU0_PCH_TX_C_DP<1>") )
				( member ( signalRef "DMI_CPU0_PCH_TX_C_DP<2>") )
				( member ( signalRef "DMI_CPU0_PCH_TX_C_DP<3>") )
				( objectStatus "@baseboard_fab2_lib.baseboard_fab2(sch_1):dmi_cpu0_pch_tx_c_dp" )
			)
			( bus "LPC_LAD_IO"
				( memberType ( signal ) )
				( member ( signalRef "LPC_LAD0_IO0") )
				( member ( signalRef "LPC_LAD1_IO1") )
				( member ( signalRef "LPC_LAD2_IO2") )
				( member ( signalRef "LPC_LAD3_IO3") )
				( objectStatus "@baseboard_fab2_lib.baseboard_fab2(sch_1):lpc_lad_io" )
			)
			( bus "FM_ROMA"
				( memberType ( signal ) )
				( member ( signalRef "FM_ROMA<0>") )
				( objectStatus "@baseboard_fab2_lib.baseboard_fab2(sch_1):fm_roma" )
			)
			( bus "P3E_CPU1_PE3_MP_C_TXN"
				( memberType ( signal ) )
				( member ( signalRef "P3E_CPU1_PE3_MP_C_TXN<0>") )
				( member ( signalRef "P3E_CPU1_PE3_MP_C_TXN<1>") )
				( member ( signalRef "P3E_CPU1_PE3_MP_C_TXN<2>") )
				( member ( signalRef "P3E_CPU1_PE3_MP_C_TXN<3>") )
				( member ( signalRef "P3E_CPU1_PE3_MP_C_TXN<4>") )
				( member ( signalRef "P3E_CPU1_PE3_MP_C_TXN<5>") )
				( member ( signalRef "P3E_CPU1_PE3_MP_C_TXN<6>") )
				( member ( signalRef "P3E_CPU1_PE3_MP_C_TXN<7>") )
				( member ( signalRef "P3E_CPU1_PE3_MP_C_TXN<8>") )
				( member ( signalRef "P3E_CPU1_PE3_MP_C_TXN<9>") )
				( member ( signalRef "P3E_CPU1_PE3_MP_C_TXN<10>") )
				( member ( signalRef "P3E_CPU1_PE3_MP_C_TXN<11>") )
				( member ( signalRef "P3E_CPU1_PE3_MP_C_TXN<12>") )
				( member ( signalRef "P3E_CPU1_PE3_MP_C_TXN<13>") )
				( member ( signalRef "P3E_CPU1_PE3_MP_C_TXN<14>") )
				( member ( signalRef "P3E_CPU1_PE3_MP_C_TXN<15>") )
				( objectStatus "@baseboard_fab2_lib.baseboard_fab2(sch_1):p3e_cpu1_pe3_mp_c_txn" )
			)
			( bus "P3E_CPU1_PE3_MP_C_TXP"
				( memberType ( signal ) )
				( member ( signalRef "P3E_CPU1_PE3_MP_C_TXP<0>") )
				( member ( signalRef "P3E_CPU1_PE3_MP_C_TXP<1>") )
				( member ( signalRef "P3E_CPU1_PE3_MP_C_TXP<2>") )
				( member ( signalRef "P3E_CPU1_PE3_MP_C_TXP<3>") )
				( member ( signalRef "P3E_CPU1_PE3_MP_C_TXP<4>") )
				( member ( signalRef "P3E_CPU1_PE3_MP_C_TXP<5>") )
				( member ( signalRef "P3E_CPU1_PE3_MP_C_TXP<6>") )
				( member ( signalRef "P3E_CPU1_PE3_MP_C_TXP<7>") )
				( member ( signalRef "P3E_CPU1_PE3_MP_C_TXP<8>") )
				( member ( signalRef "P3E_CPU1_PE3_MP_C_TXP<9>") )
				( member ( signalRef "P3E_CPU1_PE3_MP_C_TXP<10>") )
				( member ( signalRef "P3E_CPU1_PE3_MP_C_TXP<11>") )
				( member ( signalRef "P3E_CPU1_PE3_MP_C_TXP<12>") )
				( member ( signalRef "P3E_CPU1_PE3_MP_C_TXP<13>") )
				( member ( signalRef "P3E_CPU1_PE3_MP_C_TXP<14>") )
				( member ( signalRef "P3E_CPU1_PE3_MP_C_TXP<15>") )
				( objectStatus "@baseboard_fab2_lib.baseboard_fab2(sch_1):p3e_cpu1_pe3_mp_c_txp" )
			)
			( bus "NC_M2"
				( memberType ( signal ) )
				( member ( signalRef "NC_M2<0>") )
				( member ( signalRef "NC_M2<1>") )
				( member ( signalRef "NC_M2<2>") )
				( member ( signalRef "NC_M2<3>") )
				( member ( signalRef "NC_M2<4>") )
				( member ( signalRef "NC_M2<5>") )
				( member ( signalRef "NC_M2<6>") )
				( member ( signalRef "NC_M2<7>") )
				( member ( signalRef "NC_M2<8>") )
				( member ( signalRef "NC_M2<9>") )
				( member ( signalRef "NC_M2<10>") )
				( member ( signalRef "NC_M2<11>") )
				( member ( signalRef "NC_M2<12>") )
				( member ( signalRef "NC_M2<13>") )
				( member ( signalRef "NC_M2<14>") )
				( member ( signalRef "NC_M2<15>") )
				( member ( signalRef "NC_M2<16>") )
				( member ( signalRef "NC_M2<17>") )
				( member ( signalRef "NC_M2<18>") )
				( objectStatus "@baseboard_fab2_lib.baseboard_fab2(sch_1):nc_m2" )
			)
			( bus "P3E_PCH_M2_TX_C_DN"
				( memberType ( signal ) )
				( member ( signalRef "P3E_PCH_M2_TX_C_DN<1>") )
				( member ( signalRef "P3E_PCH_M2_TX_C_DN<2>") )
				( member ( signalRef "P3E_PCH_M2_TX_C_DN<3>") )
				( objectStatus "@baseboard_fab2_lib.baseboard_fab2(sch_1):p3e_pch_m2_tx_c_dn" )
			)
			( bus "P3E_PCH_M2_TX_C_DP"
				( memberType ( signal ) )
				( member ( signalRef "P3E_PCH_M2_TX_C_DP<1>") )
				( member ( signalRef "P3E_PCH_M2_TX_C_DP<2>") )
				( member ( signalRef "P3E_PCH_M2_TX_C_DP<3>") )
				( objectStatus "@baseboard_fab2_lib.baseboard_fab2(sch_1):p3e_pch_m2_tx_c_dp" )
			)
			( bus "TP_RSVD"
				( memberType ( signal ) )
				( member ( signalRef "TP_RSVD<0>") )
				( objectStatus "@baseboard_fab2_lib.baseboard_fab2(sch_1):tp_rsvd" )
			)
			( bus "P3E_CPU0_PE1_PCH_CON_RXN"
				( memberType ( signal ) )
				( member ( signalRef "P3E_CPU0_PE1_PCH_CON_RXN<8>") )
				( member ( signalRef "P3E_CPU0_PE1_PCH_CON_RXN<9>") )
				( member ( signalRef "P3E_CPU0_PE1_PCH_CON_RXN<10>") )
				( member ( signalRef "P3E_CPU0_PE1_PCH_CON_RXN<11>") )
				( member ( signalRef "P3E_CPU0_PE1_PCH_CON_RXN<12>") )
				( member ( signalRef "P3E_CPU0_PE1_PCH_CON_RXN<13>") )
				( member ( signalRef "P3E_CPU0_PE1_PCH_CON_RXN<14>") )
				( member ( signalRef "P3E_CPU0_PE1_PCH_CON_RXN<15>") )
				( objectStatus "@baseboard_fab2_lib.baseboard_fab2(sch_1):p3e_cpu0_pe1_pch_con_rxn" )
			)
			( bus "P3E_CPU0_PE1_PCH_CON_RXP"
				( memberType ( signal ) )
				( member ( signalRef "P3E_CPU0_PE1_PCH_CON_RXP<8>") )
				( member ( signalRef "P3E_CPU0_PE1_PCH_CON_RXP<9>") )
				( member ( signalRef "P3E_CPU0_PE1_PCH_CON_RXP<10>") )
				( member ( signalRef "P3E_CPU0_PE1_PCH_CON_RXP<11>") )
				( member ( signalRef "P3E_CPU0_PE1_PCH_CON_RXP<12>") )
				( member ( signalRef "P3E_CPU0_PE1_PCH_CON_RXP<13>") )
				( member ( signalRef "P3E_CPU0_PE1_PCH_CON_RXP<14>") )
				( member ( signalRef "P3E_CPU0_PE1_PCH_CON_RXP<15>") )
				( objectStatus "@baseboard_fab2_lib.baseboard_fab2(sch_1):p3e_cpu0_pe1_pch_con_rxp" )
			)
			( bus "P3E_CPU0_PE1_PCH_CON_TXN"
				( memberType ( signal ) )
				( member ( signalRef "P3E_CPU0_PE1_PCH_CON_TXN<8>") )
				( member ( signalRef "P3E_CPU0_PE1_PCH_CON_TXN<9>") )
				( member ( signalRef "P3E_CPU0_PE1_PCH_CON_TXN<10>") )
				( member ( signalRef "P3E_CPU0_PE1_PCH_CON_TXN<11>") )
				( member ( signalRef "P3E_CPU0_PE1_PCH_CON_TXN<12>") )
				( member ( signalRef "P3E_CPU0_PE1_PCH_CON_TXN<13>") )
				( member ( signalRef "P3E_CPU0_PE1_PCH_CON_TXN<14>") )
				( member ( signalRef "P3E_CPU0_PE1_PCH_CON_TXN<15>") )
				( objectStatus "@baseboard_fab2_lib.baseboard_fab2(sch_1):p3e_cpu0_pe1_pch_con_txn" )
			)
			( bus "P3E_CPU0_PE1_PCH_CON_TXP"
				( memberType ( signal ) )
				( member ( signalRef "P3E_CPU0_PE1_PCH_CON_TXP<8>") )
				( member ( signalRef "P3E_CPU0_PE1_PCH_CON_TXP<9>") )
				( member ( signalRef "P3E_CPU0_PE1_PCH_CON_TXP<10>") )
				( member ( signalRef "P3E_CPU0_PE1_PCH_CON_TXP<11>") )
				( member ( signalRef "P3E_CPU0_PE1_PCH_CON_TXP<12>") )
				( member ( signalRef "P3E_CPU0_PE1_PCH_CON_TXP<13>") )
				( member ( signalRef "P3E_CPU0_PE1_PCH_CON_TXP<14>") )
				( member ( signalRef "P3E_CPU0_PE1_PCH_CON_TXP<15>") )
				( objectStatus "@baseboard_fab2_lib.baseboard_fab2(sch_1):p3e_cpu0_pe1_pch_con_txp" )
			)
		)
	)
)
